Component Report
G:/<user>/F/F0T/F0T_Motherboard/J/brd/0324/07_Export_Files/Upload_report/03242023_DA0F0TMBIJ0_F0T_Motherboard_J_artwork/9324_DA0F0TMBIJ0_F0T_Motherboard_J_v01_20230324_0910.brd
Sat Mar 25 09:05:20 2023
Total Components:  6093
REFDES,COMP_DEVICE_TYPE,COMP_VALUE,COMP_TOL,COMP_PACKAGE,SYM_X,SYM_Y,SYM_ROTATE,SYM_MIRROR
BT1,CONN2_AAABAT029Y19-CONN2_AAA-BA,,,BATTERY_AAA-BAT-029-Y19,11563.78,1338.66,270.000,NO
C1,"Q_CAP_C0402-10UF,6.3V,20%,X6S,A",10UF,20%,C0402,13888.87,9288.06,180.000,YES
C2,"Q_CAP_C0402-2.2UF,6.3V,20%,X6SA",2.2UF,20%,C0402,11864.41,12569.44,180.000,YES
C3,"Q_CAP_C0805-10UF,16V,10%,X6S,CA",10UF,10%,C0805_H57,12024.41,12659.44,270.000,YES
C4,"Q_CAP_C0805-10UF,16V,10%,X6S,CA",10UF,10%,C0805_H57,11864.41,12659.44,270.000,YES
C5,"Q_CAP_C0402-2.2UF,6.3V,20%,X6SA",2.2UF,20%,C0402,12093.15,12492.38,90.000,YES
C6,"Q_CAP_C0805-10UF,16V,10%,X6S,CA",10UF,10%,C0805_H57,12321.41,12659.44,270.000,YES
C7,"Q_CAP_C0805-10UF,16V,10%,X6S,CA",10UF,10%,C0805_H57,12161.41,12659.44,270.000,YES
C8,"Q_CAP_C0402-2.2UF,6.3V,20%,X6SA",2.2UF,20%,C0402,11270.41,12569.44,180.000,YES
C9,"Q_CAP_C0805-10UF,16V,10%,X6S,CA",10UF,10%,C0805_H57,11270.41,12659.44,270.000,YES
C10,"Q_CAP_C0805-10UF,16V,10%,X6S,CA",10UF,10%,C0805_H57,11430.41,12659.44,270.000,YES
C11,"Q_CAP_C0402-2.2UF,6.3V,20%,X6SA",2.2UF,20%,C0402,11567.41,12569.44,180.000,YES
C12,"Q_CAP_C0805-10UF,16V,10%,X6S,CA",10UF,10%,C0805_H57,11567.41,12659.44,270.000,YES
C13,"Q_CAP_C0805-10UF,16V,10%,X6S,CA",10UF,10%,C0805_H57,11727.41,12659.44,270.000,YES
C14,"Q_CAP_C0402-2.2UF,6.3V,20%,X6SA",2.2UF,20%,C0402,10676.41,12569.44,180.000,YES
C15,"Q_CAP_C0805-10UF,16V,10%,X6S,CA",10UF,10%,C0805_H57,10836.41,12659.44,270.000,YES
C16,"Q_CAP_C0805-10UF,16V,10%,X6S,CA",10UF,10%,C0805_H57,10676.41,12659.44,270.000,YES
C17,"Q_CAP_C0402-2.2UF,6.3V,20%,X6SA",2.2UF,20%,C0402,10973.41,12569.44,180.000,YES
C18,"Q_CAP_C0805-10UF,16V,10%,X6S,CA",10UF,10%,C0805_H57,11133.41,12659.44,270.000,YES
C19,"Q_CAP_C0805-10UF,16V,10%,X6S,CA",10UF,10%,C0805_H57,10973.41,12659.44,270.000,YES
C20,"Q_CAP_C0402-2.2UF,6.3V,20%,X6SA",2.2UF,20%,C0402,10082.35,12578.10,180.000,YES
C21,"Q_CAP_C0805-10UF,16V,10%,X6S,CA",10UF,10%,C0805_H57,10242.41,12659.44,270.000,YES
C22,"Q_CAP_C0805-10UF,16V,10%,X6S,CA",10UF,10%,C0805_H57,10158.41,12658.44,270.000,YES
C23,"Q_CAP_C0402-2.2UF,6.3V,20%,X6SA",2.2UF,20%,C0402,10379.41,12569.44,180.000,YES
C24,"Q_CAP_C0805-10UF,16V,10%,X6S,CA",10UF,10%,C0805_H57,10539.41,12659.44,270.000,YES
C25,"Q_CAP_C0805-10UF,16V,10%,X6S,CA",10UF,10%,C0805_H57,10379.41,12659.44,270.000,YES
C26,"Q_CAP_C0402-2.2UF,6.3V,20%,X6SA",2.2UF,20%,C0402,16311.41,12569.44,180.000,YES
C27,"Q_CAP_C0805-10UF,16V,10%,X6S,CA",10UF,10%,C0805_H57,16471.41,12659.44,270.000,YES
C28,"Q_CAP_C0805-10UF,16V,10%,X6S,CA",10UF,10%,C0805_H57,16311.41,12659.44,270.000,YES
C29,"Q_CAP_C0402-2.2UF,6.3V,20%,X6SA",2.2UF,20%,C0402,16026.50,12562.23,90.000,YES
C30,"Q_CAP_C0805-10UF,16V,10%,X6S,CA",10UF,10%,C0805_H57,16174.41,12659.44,270.000,YES
C31,"Q_CAP_C0805-10UF,16V,10%,X6S,CA",10UF,10%,C0805_H57,16014.41,12659.44,270.000,YES
C32,"Q_CAP_C0402-2.2UF,6.3V,20%,X6SA",2.2UF,20%,C0402,16905.41,12569.44,180.000,YES
C33,"Q_CAP_C0805-10UF,16V,10%,X6S,CA",10UF,10%,C0805_H57,16905.41,12659.44,270.000,YES
C34,"Q_CAP_C0805-10UF,16V,10%,X6S,CA",10UF,10%,C0805_H57,17065.41,12659.44,270.000,YES
C35,"Q_CAP_C0402-2.2UF,6.3V,20%,X6SA",2.2UF,20%,C0402,16608.41,12569.44,180.000,YES
C36,"Q_CAP_C0805-10UF,16V,10%,X6S,CA",10UF,10%,C0805_H57,16608.41,12659.44,270.000,YES
C37,"Q_CAP_C0805-10UF,16V,10%,X6S,CA",10UF,10%,C0805_H57,16768.41,12659.44,270.000,YES
C38,"Q_CAP_C0402-2.2UF,6.3V,20%,X6SA",2.2UF,20%,C0402,17499.41,12569.44,180.000,YES
C39,"Q_CAP_C0805-10UF,16V,10%,X6S,CA",10UF,10%,C0805_H57,17659.41,12659.44,270.000,YES
C40,"Q_CAP_C0805-10UF,16V,10%,X6S,CA",10UF,10%,C0805_H57,17499.41,12659.44,270.000,YES
C41,"Q_CAP_C0402-2.2UF,6.3V,20%,X6SA",2.2UF,20%,C0402,17202.41,12569.44,180.000,YES
C42,"Q_CAP_C0805-10UF,16V,10%,X6S,CA",10UF,10%,C0805_H57,17202.41,12659.44,270.000,YES
C43,"Q_CAP_C0805-10UF,16V,10%,X6S,CA",10UF,10%,C0805_H57,17362.41,12659.44,270.000,YES
C44,"Q_CAP_C0402-2.2UF,6.3V,20%,X6SA",2.2UF,20%,C0402,18048.20,12564.26,0.000,YES
C45,"Q_CAP_C0805-10UF,16V,10%,X6S,CA",10UF,10%,C0805_H57,18093.41,12659.44,270.000,YES
C46,"Q_CAP_C0805-10UF,16V,10%,X6S,CA",10UF,10%,C0805_H57,18167.14,12659.44,270.000,YES
C47,"Q_CAP_C0402-2.2UF,6.3V,20%,X6SA",2.2UF,20%,C0402,17796.41,12569.44,180.000,YES
C48,"Q_CAP_C0805-10UF,16V,10%,X6S,CA",10UF,10%,C0805_H57,17956.41,12659.44,270.000,YES
C49,"Q_CAP_C0805-10UF,16V,10%,X6S,CA",10UF,10%,C0805_H57,17796.41,12659.44,270.000,YES
C50,"Q_CAP_C0402-2.2UF,6.3V,20%,X6SA",2.2UF,20%,C0402,2102.99,12569.64,180.000,YES
C51,"Q_CAP_C0805-10UF,16V,10%,X6S,CA",10UF,10%,C0805_H57,2262.99,12659.64,270.000,YES
C52,"Q_CAP_C0805-10UF,16V,10%,X6S,CA",10UF,10%,C0805_H57,2102.99,12659.64,270.000,YES
C53,"Q_CAP_C0402-2.2UF,6.3V,20%,X6SA",2.2UF,20%,C0402,2398.67,12574.56,180.000,YES
C54,"Q_CAP_C0805-10UF,16V,10%,X6S,CA",10UF,10%,C0805_H57,2559.99,12659.64,270.000,YES
C55,"Q_CAP_C0805-10UF,16V,10%,X6S,CA",10UF,10%,C0805_H57,2399.99,12659.64,270.000,YES
C56,"Q_CAP_C0402-2.2UF,6.3V,20%,X6SA",2.2UF,20%,C0402,1508.99,12569.64,180.000,YES
C57,"Q_CAP_C0805-10UF,16V,10%,X6S,CA",10UF,10%,C0805_H57,1668.99,12659.64,270.000,YES
C58,"Q_CAP_C0805-10UF,16V,10%,X6S,CA",10UF,10%,C0805_H57,1508.99,12659.64,270.000,YES
C59,"Q_CAP_C0402-2.2UF,6.3V,20%,X6SA",2.2UF,20%,C0402,1805.99,12569.64,180.000,YES
C60,"Q_CAP_C0805-10UF,16V,10%,X6S,CA",10UF,10%,C0805_H57,1965.99,12659.64,270.000,YES
C61,"Q_CAP_C0805-10UF,16V,10%,X6S,CA",10UF,10%,C0805_H57,1805.99,12659.64,270.000,YES
C62,"Q_CAP_C0402-2.2UF,6.3V,20%,X6SA",2.2UF,20%,C0402,914.99,12569.64,180.000,YES
C63,"Q_CAP_C0805-10UF,16V,10%,X6S,CA",10UF,10%,C0805_H57,1074.99,12659.64,270.000,YES
C64,"Q_CAP_C0805-10UF,16V,10%,X6S,CA",10UF,10%,C0805_H57,914.99,12659.64,270.000,YES
C65,"Q_CAP_C0402-2.2UF,6.3V,20%,X6SA",2.2UF,20%,C0402,1211.99,12569.64,180.000,YES
C66,"Q_CAP_C0805-10UF,16V,10%,X6S,CA",10UF,10%,C0805_H57,1371.99,12659.64,270.000,YES
C67,"Q_CAP_C0805-10UF,16V,10%,X6S,CA",10UF,10%,C0805_H57,1211.99,12659.64,270.000,YES
C68,"Q_CAP_C0402-2.2UF,6.3V,20%,X6SA",2.2UF,20%,C0402,320.99,12569.64,180.000,YES
C69,"Q_CAP_C0805-10UF,16V,10%,X6S,CA",10UF,10%,C0805_H57,480.99,12659.64,270.000,YES
C70,"Q_CAP_C0805-10UF,16V,10%,X6S,CA",10UF,10%,C0805_H57,320.99,12659.64,270.000,YES
C71,"Q_CAP_C0402-10UF,6.3V,20%,X6S,A",10UF,20%,C0402,4125.47,9291.65,180.000,YES
C72,"Q_CAP_C0402-2.2UF,6.3V,20%,X6SA",2.2UF,20%,C0402,8034.99,12569.64,180.000,YES
C73,"Q_CAP_C0805-10UF,16V,10%,X6S,CA",10UF,10%,C0805_H57,8194.99,12659.64,270.000,YES
C74,"Q_CAP_C0805-10UF,16V,10%,X6S,CA",10UF,10%,C0805_H57,8034.99,12659.64,270.000,YES
C75,"Q_CAP_C0402-2.2UF,6.3V,20%,X6SA",2.2UF,20%,C0402,8331.99,12569.64,180.000,YES
C76,"Q_CAP_C0805-10UF,16V,10%,X6S,CA",10UF,10%,C0805_H57,8331.99,12659.64,270.000,YES
C77,"Q_CAP_C0805-10UF,16V,10%,X6S,CA",10UF,10%,C0805_H57,8402.46,12659.64,270.000,YES
C78,"Q_CAP_C0402-2.2UF,6.3V,20%,X6SA",2.2UF,20%,C0402,7442.51,12576.81,180.000,YES
C79,"Q_CAP_C0805-10UF,16V,10%,X6S,CA",10UF,10%,C0805_H57,7600.99,12659.64,270.000,YES
C80,"Q_CAP_C0805-10UF,16V,10%,X6S,CA",10UF,10%,C0805_H57,7440.99,12659.64,270.000,YES
C81,"Q_CAP_C0402-2.2UF,6.3V,20%,X6SA",2.2UF,20%,C0402,7737.99,12569.64,180.000,YES
C82,"Q_CAP_C0805-10UF,16V,10%,X6S,CA",10UF,10%,C0805_H57,7737.99,12659.64,270.000,YES
C83,"Q_CAP_C0805-10UF,16V,10%,X6S,CA",10UF,10%,C0805_H57,7897.99,12659.64,270.000,YES
C84,"Q_CAP_C0402-2.2UF,6.3V,20%,X6SA",2.2UF,20%,C0402,6846.99,12569.64,180.000,YES
C85,"Q_CAP_C0805-10UF,16V,10%,X6S,CA",10UF,10%,C0805_H57,7006.99,12659.64,270.000,YES
C86,"Q_CAP_C0805-10UF,16V,10%,X6S,CA",10UF,10%,C0805_H57,6846.99,12659.64,270.000,YES
C87,"Q_CAP_C0402-2.2UF,6.3V,20%,X6SA",2.2UF,20%,C0402,7143.99,12569.64,180.000,YES
C88,"Q_CAP_C0805-10UF,16V,10%,X6S,CA",10UF,10%,C0805_H57,7143.99,12659.64,270.000,YES
C89,"Q_CAP_C0805-10UF,16V,10%,X6S,CA",10UF,10%,C0805_H57,7303.99,12659.64,270.000,YES
C90,"Q_CAP_C0402-2.2UF,6.3V,20%,X6SA",2.2UF,20%,C0402,6247.92,12573.36,0.000,YES
C91,"Q_CAP_C0805-10UF,16V,10%,X6S,CA",10UF,10%,C0805_H57,6252.99,12659.64,270.000,YES
C92,"Q_CAP_C0805-10UF,16V,10%,X6S,CA",10UF,10%,C0805_H57,6412.99,12659.64,270.000,YES
C93,"Q_CAP_C0402-2.2UF,6.3V,20%,X6SA",2.2UF,20%,C0402,6549.99,12569.64,180.000,YES
C94,"Q_CAP_C0805-10UF,16V,10%,X6S,CA",10UF,10%,C0805_H57,6549.99,12659.64,270.000,YES
C95,"Q_CAP_C0805-10UF,16V,10%,X6S,CA",10UF,10%,C0805_H57,6709.99,12659.64,270.000,YES
C96,"Q_CAP_C0402-2.2UF,6.3V,20%,X6SA",2.2UF,20%,C0402,617.99,12569.64,180.000,YES
C97,"Q_CAP_C0805-10UF,16V,10%,X6S,CA",10UF,10%,C0805_H57,777.99,12659.64,270.000,YES
C98,"Q_CAP_C0805-10UF,16V,10%,X6S,CA",10UF,10%,C0805_H57,617.99,12659.64,270.000,YES
C101,"Q_CAP_C0805-47UF,4V,20%,X6S,CHA",47UF,20%,C0805_H57,14287.20,11575.20,0.000,NO
C103,"Q_CAP_0402-27PF  ,50V ,5% ,EMPA",NA,5%,C0402,13178.00,2616.62,180.000,NO
C104,"Q_CAP_0402-27PF  ,50V ,5% ,EMPA",NA,5%,C0402,13265.64,2615.14,0.000,NO
C107,"Q_CAP_C0402-1UF,25V,10%,X6S,CHA",1UF,10%,C0402,10475.00,3858.62,270.000,YES
C108,"Q_CAP_C0603-10UF,6.3V,20%,X6S,A",10UF,20%,C0603,10375.69,3735.77,0.000,NO
C110,"Q_CAP_C0402-0.047UF,25V,10%,X7A",0.047UF,10%,C0402,10195.00,3808.62,0.000,YES
C111,"Q_CAP_C0402-0.047UF,25V,10%,X7A",0.047UF,10%,C0402,9930.00,3833.62,180.000,YES
C112,"Q_CAP_C0402-0.047UF,25V,10%,X7A",0.047UF,10%,C0402,9614.45,3827.54,270.000,YES
C114,"Q_CAP_C0402-0.047UF,25V,10%,X7A",0.047UF,10%,C0402,9930.81,4006.07,180.000,YES
C115,"Q_CAP_C0402-0.047UF,25V,10%,X7A",0.047UF,10%,C0402,10195.00,3943.62,0.000,YES
C116,"Q_CAP_C0402-0.047UF,25V,10%,X7A",0.047UF,10%,C0402,10195.00,3983.62,0.000,YES
C117,"Q_CAP_C0402-0.047UF,25V,10%,X7A",0.047UF,10%,C0402,10093.34,4026.67,90.000,YES
C119,"Q_CAP_C0402-0.047UF,25V,10%,X7A",0.047UF,10%,C0402,10131.05,4027.10,90.000,YES
C120,"Q_CAP_C0402-0.047UF,25V,10%,X7A",0.047UF,10%,C0402,9930.00,3913.62,180.000,YES
C139,Q_CAP_DIFFBUS_C0201-DIFF BUS_0A,,,C0201_DIFF-BUS,13806.74,2385.51,0.000,NO
C141,Q_CAP_DIFFBUS_C0201-DIFF BUS_0A,,,C0201_DIFF-BUS,13743.50,2456.62,0.000,NO
C142,Q_CAP_DIFFBUS_C0201-DIFF BUS_0A,,,C0201_DIFF-BUS,13743.50,2492.62,0.000,NO
C143,Q_CAP_DIFFBUS_C0201-DIFF BUS_0A,,,C0201_DIFF-BUS,13845.50,2537.03,0.000,NO
C144,Q_CAP_DIFFBUS_C0201-DIFF BUS_0A,,,C0201_DIFF-BUS,13845.50,2573.03,0.000,NO
C145,Q_CAP_DIFFBUS_C0201-DIFF BUS_0A,,,C0201_DIFF-BUS,13738.66,2601.36,0.000,NO
C146,Q_CAP_DIFFBUS_C0201-DIFF BUS_0A,,,C0201_DIFF-BUS,13738.66,2637.36,0.000,NO
C147,Q_CAP_DIFFBUS_C0201-DIFF BUS_0A,,,C0201_DIFF-BUS,13740.71,2685.70,0.000,NO
C148,Q_CAP_DIFFBUS_C0201-DIFF BUS_0A,,,C0201_DIFF-BUS,13740.71,2721.70,0.000,NO
C149,Q_CAP_DIFFBUS_C0201-DIFF BUS_0A,,,C0201_DIFF-BUS,13649.85,2731.10,90.000,NO
C150,Q_CAP_DIFFBUS_C0201-DIFF BUS_0A,,,C0201_DIFF-BUS,13613.85,2731.10,90.000,NO
C151,Q_CAP_DIFFBUS_C0201-DIFF BUS_0A,,,C0201_DIFF-BUS,13568.85,2776.40,90.000,NO
C152,Q_CAP_DIFFBUS_C0201-DIFF BUS_0A,,,C0201_DIFF-BUS,13532.85,2776.40,90.000,NO
C153,Q_CAP_DIFFBUS_C0201-DIFF BUS_0A,,,C0201_DIFF-BUS,13481.85,2757.40,90.000,NO
C154,Q_CAP_DIFFBUS_C0201-DIFF BUS_0A,,,C0201_DIFF-BUS,13445.85,2757.40,90.000,NO
C155,Q_CAP_DIFFBUS_C0201-DIFF BUS_0A,,,C0201_DIFF-BUS,13766.76,2562.80,0.000,YES
C156,Q_CAP_DIFFBUS_C0201-DIFF BUS_0A,,,C0201_DIFF-BUS,13766.76,2526.80,0.000,YES
C157,Q_CAP_DIFFBUS_C0201-DIFF BUS_0A,,,C0201_DIFF-BUS,13639.40,2298.55,45.000,YES
C158,Q_CAP_DIFFBUS_C0201-DIFF BUS_0A,,,C0201_DIFF-BUS,13613.94,2324.01,45.000,YES
C159,Q_CAP_DIFFBUS_C0201-DIFF BUS_0A,,,C0201_DIFF-BUS,13640.50,2523.16,90.000,YES
C160,Q_CAP_DIFFBUS_C0201-DIFF BUS_0A,,,C0201_DIFF-BUS,13604.50,2523.16,90.000,YES
C161,Q_CAP_DIFFBUS_C0201-DIFF BUS_0A,,,C0201_DIFF-BUS,13573.02,2443.16,90.000,YES
C162,Q_CAP_DIFFBUS_C0201-DIFF BUS_0A,,,C0201_DIFF-BUS,13537.02,2443.16,90.000,YES
C163,Q_CAP_DIFFBUS_C0201-DIFF BUS_0A,,,C0201_DIFF-BUS,13510.48,2523.16,90.000,YES
C164,Q_CAP_DIFFBUS_C0201-DIFF BUS_0A,,,C0201_DIFF-BUS,13474.48,2523.16,90.000,YES
C165,Q_CAP_DIFFBUS_C0201-DIFF BUS_0A,,,C0201_DIFF-BUS,13401.82,2443.16,90.000,YES
C166,Q_CAP_DIFFBUS_C0201-DIFF BUS_0A,,,C0201_DIFF-BUS,13437.82,2443.16,90.000,YES
C167,Q_CAP_DIFFBUS_C0201-DIFF BUS_0A,,,C0201_DIFF-BUS,13399.90,2615.16,90.000,YES
C168,Q_CAP_DIFFBUS_C0201-DIFF BUS_0A,,,C0201_DIFF-BUS,13363.90,2615.16,90.000,YES
C169,Q_CAP_DIFFBUS_C0201-DIFF BUS_0A,,,C0201_DIFF-BUS,13276.33,2532.12,90.000,YES
C170,Q_CAP_DIFFBUS_C0201-DIFF BUS_0A,,,C0201_DIFF-BUS,13312.33,2532.12,90.000,YES
C171,"Q_CAP_C0402-0.047UF,25V,10%,X7A",0.047UF,10%,C0402,10195.00,3858.62,0.000,YES
C172,"Q_CAP_C0603-10UF,6.3V,20%,X6S,A",10UF,20%,C0603,10473.71,3708.37,90.000,NO
C173,"Q_CAP_C0402-0.047UF,25V,10%,X7A",0.047UF,10%,C0402,10090.00,3818.62,270.000,YES
C174,"Q_CAP_0402-0.1UF,25V,10%,X7R,CA",0.1UF,10%,C0402,4926.18,5479.47,0.000,NO
C188,"Q_CAP_0402-0.1UF,25V,10%,X7R,CA",0.1UF,10%,C0402,15261.18,1146.05,270.000,NO
C204,"Q_CAP_0402-0.1UF,25V,10%,X7R,CA",0.1UF,10%,C0402,9050.10,4922.87,270.000,YES
C205,"Q_CAP_0402-0.1UF,25V,10%,X7R,CA",0.1UF,10%,C0402,9161.11,5105.27,270.000,YES
C206,"Q_CAP_0402-0.1UF,25V,10%,X7R,CA",0.1UF,10%,C0402,9324.87,4876.83,90.000,YES
C207,"Q_CAP_0402-0.1UF,25V,10%,X7R,CA",0.1UF,10%,C0402,9363.68,5059.77,180.000,YES
C208,"Q_CAP_C0603-10UF,6.3V,20%,X6S,A",10UF,20%,C0603,9349.94,4773.11,180.000,YES
C209,"Q_CAP_C0603-10UF,6.3V,20%,X6S,A",10UF,20%,C0603,9247.82,4843.12,90.000,YES
C210,"Q_CAP_0402-0.1UF,25V,10%,X7R,CA",0.1UF,10%,C0402,9363.63,5019.25,180.000,YES
C211,"Q_CAP_0402-0.1UF,25V,10%,X7R,CA",0.1UF,10%,C0402,9289.58,4860.38,90.000,YES
C212,"Q_CAP_C0805-47UF,4V,20%,X6S,CHA",47UF,20%,C0805_H57,13912.20,11575.20,180.000,NO
C213,"Q_CAP_C0805-47UF,4V,20%,X6S,CHA",47UF,20%,C0805_H57,14287.20,11655.70,0.000,NO
C214,"Q_CAP_C0805-47UF,4V,20%,X6S,CHA",47UF,20%,C0805_H57,13912.20,11655.70,180.000,NO
C215,"Q_CAP_C0805-47UF,4V,20%,X6S,CHA",47UF,20%,C0805_H57,14162.20,11575.20,180.000,NO
C216,"Q_CAP_C0805-47UF,4V,20%,X6S,CHA",47UF,20%,C0805_H57,14037.20,11655.70,0.000,NO
C217,"Q_CAP_C0805-47UF,4V,20%,X6S,CHA",47UF,20%,C0805_H57,14037.20,11575.20,0.000,NO
C218,"Q_CAP_C0805-47UF,4V,20%,X6S,CHA",47UF,20%,C0805_H57,14162.20,11655.70,180.000,NO
C219,"Q_CAP_C0805-47UF,4V,20%,X6S,CHA",47UF,20%,C0805_H57,14412.20,11655.70,180.000,NO
C220,"Q_CAP_C0805-47UF,4V,20%,X6S,CHA",47UF,20%,C0805_H57,14412.20,11575.20,180.000,NO
C221,"Q_CAP_C0402-10UF,6.3V,20%,X6S,B",10UF,20%,C0402,4223.91,10186.10,90.000,NO
C222,"Q_CAP_C0402-10UF,6.3V,20%,X6S,B",10UF,20%,C0402,4146.26,9752.57,90.000,NO
C223,"Q_CAP_C0402-10UF,6.3V,20%,X6S,B",10UF,20%,C0402,4627.04,9459.73,90.000,NO
C224,"Q_CAP_C0402-10UF,6.3V,20%,X6S,B",10UF,20%,C0402,4667.04,9607.56,90.000,NO
C225,"Q_CAP_C0805-47UF,4V,20%,X6S,CHA",47UF,20%,C0805_H57,4399.30,11655.70,180.000,NO
C226,"Q_CAP_C0402-10UF,6.3V,20%,X6S,B",10UF,20%,C0402,4185.91,10186.10,90.000,NO
C227,"Q_CAP_C0402-10UF,6.3V,20%,X6S,B",10UF,20%,C0402,4186.71,9752.57,90.000,NO
C228,"Q_CAP_C0402-10UF,6.3V,20%,X6S,B",10UF,20%,C0402,4667.04,10186.10,90.000,NO
C229,"Q_CAP_C0402-10UF,6.3V,20%,X6S,B",10UF,20%,C0402,4667.04,9815.77,270.000,NO
C230,"Q_CAP_C0805-47UF,4V,20%,X6S,CHA",47UF,20%,C0805_H57,4399.30,11575.20,180.000,NO
C231,"Q_CAP_C0402-10UF,6.3V,20%,X6S,B",10UF,20%,C0402,4185.50,10104.50,270.000,NO
C232,"Q_CAP_C0402-10UF,6.3V,20%,X6S,B",10UF,20%,C0402,4108.00,9815.77,270.000,NO
C233,"Q_CAP_C0402-10UF,6.3V,20%,X6S,B",10UF,20%,C0402,4705.04,10186.10,90.000,NO
C234,"Q_CAP_C0402-10UF,6.3V,20%,X6S,B",10UF,20%,C0402,4705.04,9815.77,270.000,NO
C235,"Q_CAP_C0805-47UF,4V,20%,X6S,CHA",47UF,20%,C0805_H57,4524.30,11575.20,0.000,NO
C236,"Q_CAP_C0402-10UF,6.3V,20%,X6S,B",10UF,20%,C0402,4146.00,9815.77,270.000,NO
C237,"Q_CAP_C0402-10UF,6.3V,20%,X6S,B",10UF,20%,C0402,4146.26,9670.64,270.000,NO
C238,"Q_CAP_C0402-10UF,6.3V,20%,X6S,B",10UF,20%,C0402,4705.04,9958.92,270.000,NO
C239,"Q_CAP_C0402-10UF,6.3V,20%,X6S,B",10UF,20%,C0402,4705.04,9607.56,90.000,NO
C240,"Q_CAP_C0805-47UF,4V,20%,X6S,CHA",47UF,20%,C0805_H57,4524.30,11655.70,0.000,NO
C241,"Q_CAP_C0402-10UF,6.3V,20%,X6S,B",10UF,20%,C0402,4108.38,10041.50,90.000,NO
C242,"Q_CAP_C0402-10UF,6.3V,20%,X6S,B",10UF,20%,C0402,4145.95,9526.65,270.000,NO
C243,"Q_CAP_C0402-10UF,6.3V,20%,X6S,B",10UF,20%,C0402,4667.04,9958.92,270.000,NO
C244,"Q_CAP_C0402-10UF,6.3V,20%,X6S,B",10UF,20%,C0402,4667.04,10041.50,90.000,NO
C245,"Q_CAP_C0805-47UF,4V,20%,X6S,CHA",47UF,20%,C0805_H57,4649.30,11655.70,180.000,NO
C246,"Q_CAP_C0402-10UF,6.3V,20%,X6S,B",10UF,20%,C0402,4145.50,10041.50,90.000,NO
C247,"Q_CAP_C0402-10UF,6.3V,20%,X6S,B",10UF,20%,C0402,4107.95,9526.65,270.000,NO
C248,"Q_CAP_C0402-10UF,6.3V,20%,X6S,B",10UF,20%,C0402,4667.04,10104.50,270.000,NO
C249,"Q_CAP_C0402-10UF,6.3V,20%,X6S,B",10UF,20%,C0402,4667.04,9752.57,90.000,NO
C250,"Q_CAP_C0805-47UF,4V,20%,X6S,CHA",47UF,20%,C0805_H57,4149.30,11655.70,180.000,NO
C251,"Q_CAP_C0402-10UF,6.3V,20%,X6S,B",10UF,20%,C0402,4146.00,9896.68,90.000,NO
C252,"Q_CAP_C0402-10UF,6.3V,20%,X6S,B",10UF,20%,C0402,4108.26,9607.56,90.000,NO
C253,"Q_CAP_C0402-10UF,6.3V,20%,X6S,B",10UF,20%,C0402,4705.04,10104.50,270.000,NO
C254,"Q_CAP_C0402-10UF,6.3V,20%,X6S,B",10UF,20%,C0402,4667.04,9526.65,270.000,NO
C255,"Q_CAP_C0805-47UF,4V,20%,X6S,CHA",47UF,20%,C0805_H57,4149.30,11575.20,180.000,NO
C256,"Q_CAP_C0402-10UF,6.3V,20%,X6S,B",10UF,20%,C0402,4108.00,9896.68,90.000,NO
C257,"Q_CAP_C0402-10UF,6.3V,20%,X6S,B",10UF,20%,C0402,4146.26,9607.56,90.000,NO
C258,"Q_CAP_C0402-10UF,6.3V,20%,X6S,B",10UF,20%,C0402,4705.04,9896.68,90.000,NO
C259,"Q_CAP_C0402-10UF,6.3V,20%,X6S,B",10UF,20%,C0402,4627.04,9670.64,270.000,NO
C260,"Q_CAP_C0805-47UF,4V,20%,X6S,CHA",47UF,20%,C0805_H57,4274.30,11655.70,0.000,NO
C261,"Q_CAP_C0402-10UF,6.3V,20%,X6S,B",10UF,20%,C0402,4108.00,9958.92,270.000,NO
C262,"Q_CAP_C0402-10UF,6.3V,20%,X6S,B",10UF,20%,C0402,4186.16,9376.48,270.000,NO
C263,"Q_CAP_C0402-10UF,6.3V,20%,X6S,B",10UF,20%,C0402,4667.04,9896.68,90.000,NO
C264,"Q_CAP_C0402-10UF,6.3V,20%,X6S,B",10UF,20%,C0402,4667.04,9670.64,270.000,NO
C265,"Q_CAP_C0805-47UF,4V,20%,X6S,CHA",47UF,20%,C0805_H57,4274.30,11575.20,0.000,NO
C266,"Q_CAP_C0402-10UF,6.3V,20%,X6S,B",10UF,20%,C0402,4146.00,9958.92,270.000,NO
C267,"Q_CAP_C0402-10UF,6.3V,20%,X6S,B",10UF,20%,C0402,4145.95,9459.73,90.000,NO
C268,"Q_CAP_C0402-10UF,6.3V,20%,X6S,B",10UF,20%,C0402,4705.04,10041.50,90.000,NO
C269,"Q_CAP_C0402-10UF,6.3V,20%,X6S,B",10UF,20%,C0402,4705.04,9526.65,270.000,NO
C270,"Q_CAP_C0805-47UF,4V,20%,X6S,CHA",47UF,20%,C0805_H57,4649.30,11575.20,180.000,NO
C271,"Q_CAP_C0402-22UF,4V,20%,X6S,CHA",22UF,20%,C0402_H32,4186.00,9958.92,270.000,NO
C272,"Q_CAP_C0402-22UF,4V,20%,X6S,CHA",22UF,20%,C0402_H32,4224.26,9670.64,270.000,NO
C273,"Q_CAP_C0402-22UF,4V,20%,X6S,CHA",22UF,20%,C0402_H32,4627.04,9752.57,90.000,NO
C274,"Q_CAP_C0402-22UF,4V,20%,X6S,CHA",22UF,20%,C0402_H32,4627.04,9607.56,90.000,NO
C275,"Q_CAP_C0402-22UF,4V,20%,X6S,CHA",22UF,20%,C0402_H32,4223.50,9958.92,270.000,NO
C276,"Q_CAP_C0402-22UF,4V,20%,X6S,CHA",22UF,20%,C0402_H32,4186.26,9670.64,270.000,NO
C277,"Q_CAP_C0402-22UF,4V,20%,X6S,CHA",22UF,20%,C0402_H32,4589.04,9958.92,270.000,NO
C278,"Q_CAP_C0402-22UF,4V,20%,X6S,CHA",22UF,20%,C0402_H32,4627.04,9815.77,270.000,NO
C279,"Q_CAP_C0402-22UF,4V,20%,X6S,CHA",22UF,20%,C0402_H32,4223.50,10041.50,90.000,NO
C280,"Q_CAP_C0402-22UF,4V,20%,X6S,CHA",22UF,20%,C0402_H32,4185.95,9526.65,270.000,NO
C281,"Q_CAP_C0402-22UF,4V,20%,X6S,CHA",22UF,20%,C0402_H32,4627.04,9958.92,270.000,NO
C282,"Q_CAP_C0402-22UF,4V,20%,X6S,CHA",22UF,20%,C0402_H32,4589.04,9752.57,90.000,NO
C283,"Q_CAP_C0402-22UF,4V,20%,X6S,CHA",22UF,20%,C0402_H32,4185.50,10041.50,90.000,NO
C284,"Q_CAP_C0402-22UF,4V,20%,X6S,CHA",22UF,20%,C0402_H32,4223.95,9526.65,270.000,NO
C285,"Q_CAP_C0402-22UF,4V,20%,X6S,CHA",22UF,20%,C0402_H32,4627.04,10104.50,270.000,NO
C286,"Q_CAP_C0402-22UF,4V,20%,X6S,CHA",22UF,20%,C0402_H32,4589.04,9526.65,270.000,NO
C287,"Q_CAP_C0402-22UF,4V,20%,X6S,CHA",22UF,20%,C0402_H32,4186.00,9896.68,90.000,NO
C288,"Q_CAP_C0402-22UF,4V,20%,X6S,CHA",22UF,20%,C0402_H32,4224.26,9607.56,90.000,NO
C289,"Q_CAP_C0402-22UF,4V,20%,X6S,CHA",22UF,20%,C0402_H32,4589.04,10104.50,270.000,NO
C290,"Q_CAP_C0402-22UF,4V,20%,X6S,CHA",22UF,20%,C0402_H32,4627.04,9526.65,270.000,NO
C291,"Q_CAP_C0402-22UF,4V,20%,X6S,CHA",22UF,20%,C0402_H32,4224.00,9896.68,90.000,NO
C292,"Q_CAP_C0402-22UF,4V,20%,X6S,CHA",22UF,20%,C0402_H32,4185.95,9459.73,90.000,NO
C293,"Q_CAP_C0402-22UF,4V,20%,X6S,CHA",22UF,20%,C0402_H32,4589.04,9896.68,90.000,NO
C294,"Q_CAP_C0402-22UF,4V,20%,X6S,CHA",22UF,20%,C0402_H32,4589.04,9670.64,270.000,NO
C295,"Q_CAP_C0402-22UF,4V,20%,X6S,CHA",22UF,20%,C0402_H32,4224.71,9752.57,90.000,NO
C296,"Q_CAP_C0402-22UF,4V,20%,X6S,CHA",22UF,20%,C0402_H32,4223.95,9459.73,90.000,NO
C297,"Q_CAP_C0402-22UF,4V,20%,X6S,CHA",22UF,20%,C0402_H32,4627.04,9896.68,90.000,NO
C298,"Q_CAP_C0402-22UF,4V,20%,X6S,CHA",22UF,20%,C0402_H32,4589.04,9607.56,90.000,NO
C299,"Q_CAP_C0402-22UF,4V,20%,X6S,CHA",22UF,20%,C0402_H32,4223.50,10104.50,270.000,NO
C300,"Q_CAP_C0402-22UF,4V,20%,X6S,CHA",22UF,20%,C0402_H32,4186.26,9607.56,90.000,NO
C301,"Q_CAP_C0402-22UF,4V,20%,X6S,CHA",22UF,20%,C0402_H32,4627.04,10041.50,90.000,NO
C302,"Q_CAP_C0402-22UF,4V,20%,X6S,CHA",22UF,20%,C0402_H32,4589.04,9459.73,90.000,NO
C303,"Q_CAP_C0402-22UF,4V,20%,X6S,CHA",22UF,20%,C0402_H32,4186.00,9815.77,270.000,NO
C304,"Q_CAP_C0402-22UF,4V,20%,X6S,CHA",22UF,20%,C0402_H32,4223.95,9376.48,270.000,NO
C305,"Q_CAP_C0402-22UF,4V,20%,X6S,CHA",22UF,20%,C0402_H32,4589.04,10041.50,90.000,NO
C306,"Q_CAP_C0402-22UF,4V,20%,X6S,CHA",22UF,20%,C0402_H32,4627.04,10186.10,90.000,NO
C307,"Q_CAP_C0402-22UF,4V,20%,X6S,CHA",22UF,20%,C0402_H32,4224.00,9815.77,270.000,NO
C308,"Q_CAP_C0402-22UF,4V,20%,X6S,CHA",22UF,20%,C0402_H32,4589.04,10186.10,90.000,NO
C309,"Q_CAP_C0402-22UF,4V,20%,X6S,CHA",22UF,20%,C0402_H32,4589.04,9815.77,270.000,NO
C310,"Q_CAP_C0402-22UF,4V,20%,X6S,CHA",22UF,20%,C0402_H32,4146.16,9376.48,90.000,NO
C311,"Q_CAP_C0805-47UF,4V,20%,X6S,CHA",47UF,20%,C0805_H57,4582.80,9493.80,270.000,YES
C312,"Q_CAP_C0805-47UF,4V,20%,X6S,CHA",47UF,20%,C0805_H57,4157.32,10328.70,0.000,YES
C313,"Q_CAP_C0805-47UF,4V,20%,X6S,CHA",47UF,20%,C0805_H57,4090.61,9638.60,270.000,YES
C314,"Q_CAP_C0805-47UF,4V,20%,X6S,CHA",47UF,20%,C0805_H57,4582.80,9783.40,270.000,YES
C315,"Q_CAP_C0805-47UF,4V,20%,X6S,CHA",47UF,20%,C0805_H57,4230.61,9496.80,90.000,YES
C316,"Q_CAP_C0805-47UF,4V,20%,X6S,CHA",47UF,20%,C0805_H57,4160.61,9638.60,270.000,YES
C317,"Q_CAP_C0805-47UF,4V,20%,X6S,CHA",47UF,20%,C0805_H57,4652.80,9638.60,270.000,YES
C318,"Q_CAP_C0805-47UF,4V,20%,X6S,CHA",47UF,20%,C0805_H57,4230.61,9638.60,270.000,YES
C320,"Q_CAP_C0805-47UF,4V,20%,X6S,CHA",47UF,20%,C0805_H57,4582.80,9638.60,270.000,YES
C321,"Q_CAP_C0805-47UF,4V,20%,X6S,CHA",47UF,20%,C0805_H57,4160.61,10073.00,270.000,YES
C322,"Q_CAP_C0805-47UF,4V,20%,X6S,CHA",47UF,20%,C0805_H57,4035.26,11575.20,180.000,YES
C323,"Q_CAP_C0805-47UF,4V,20%,X6S,CHA",47UF,20%,C0805_H57,4652.80,9783.40,270.000,YES
C324,"Q_CAP_C0805-47UF,4V,20%,X6S,CHA",47UF,20%,C0805_H57,4230.61,10073.00,270.000,YES
C325,"Q_CAP_C0805-47UF,4V,20%,X6S,CHA",47UF,20%,C0805_H57,4160.26,11575.20,0.000,YES
C326,"Q_CAP_C0805-47UF,4V,20%,X6S,CHA",47UF,20%,C0805_H57,4582.80,9358.98,90.000,YES
C327,"Q_CAP_C0805-47UF,4V,20%,X6S,CHA",47UF,20%,C0805_H57,4090.61,9928.20,270.000,YES
C328,"Q_CAP_C0805-47UF,4V,20%,X6S,CHA",47UF,20%,C0805_H57,4285.26,11575.20,180.000,YES
C329,"Q_CAP_C0805-47UF,4V,20%,X6S,CHA",47UF,20%,C0805_H57,4582.80,10073.00,270.000,YES
C330,"Q_CAP_C0805-47UF,4V,20%,X6S,CHA",47UF,20%,C0805_H57,4160.61,9928.20,270.000,YES
C332,"Q_CAP_C0805-47UF,4V,20%,X6S,CHA",47UF,20%,C0805_H57,4652.80,10073.00,270.000,YES
C333,"Q_CAP_C0805-47UF,4V,20%,X6S,CHA",47UF,20%,C0805_H57,4230.61,9928.20,270.000,YES
C335,"Q_CAP_C0805-47UF,4V,20%,X6S,CHA",47UF,20%,C0805_H57,4722.80,10073.00,270.000,YES
C336,"Q_CAP_C0805-47UF,4V,20%,X6S,CHA",47UF,20%,C0805_H57,4160.61,9783.40,270.000,YES
C337,"Q_CAP_C0805-47UF,4V,20%,X6S,CHA",47UF,20%,C0805_H57,4651.07,9493.85,270.000,YES
C338,"Q_CAP_C0805-47UF,4V,20%,X6S,CHA",47UF,20%,C0805_H57,4582.80,9928.20,270.000,YES
C339,"Q_CAP_C0805-47UF,4V,20%,X6S,CHA",47UF,20%,C0805_H57,4230.61,9783.40,270.000,YES
C341,"Q_CAP_C0805-47UF,4V,20%,X6S,CHA",47UF,20%,C0805_H57,4410.26,11575.20,0.000,YES
C342,"Q_CAP_C0805-47UF,4V,20%,X6S,CHA",47UF,20%,C0805_H57,4035.26,11655.70,180.000,YES
C343,"Q_CAP_C0805-47UF,4V,20%,X6S,CHA",47UF,20%,C0805_H57,4535.26,11575.20,180.000,YES
C344,"Q_CAP_C0805-47UF,4V,20%,X6S,CHA",47UF,20%,C0805_H57,4160.26,11655.70,0.000,YES
C345,"Q_CAP_C0805-47UF,4V,20%,X6S,CHA",47UF,20%,C0805_H57,4660.26,11575.20,0.000,YES
C346,"Q_CAP_C0805-47UF,4V,20%,X6S,CHA",47UF,20%,C0805_H57,4285.26,11655.70,180.000,YES
C347,"Q_CAP_C0805-47UF,4V,20%,X6S,CHA",47UF,20%,C0805_H57,4785.26,11575.20,180.000,YES
C348,"Q_CAP_C0805-47UF,4V,20%,X6S,CHA",47UF,20%,C0805_H57,4410.26,11655.70,0.000,YES
C349,"Q_CAP_C0805-47UF,4V,20%,X6S,CHA",47UF,20%,C0805_H57,4722.80,9638.60,270.000,YES
C350,"Q_CAP_C0805-47UF,4V,20%,X6S,CHA",47UF,20%,C0805_H57,4535.26,11655.70,180.000,YES
C351,"Q_CAP_C0805-47UF,4V,20%,X6S,CHA",47UF,20%,C0805_H57,4652.80,9928.20,270.000,YES
C352,"Q_CAP_C0805-47UF,4V,20%,X6S,CHA",47UF,20%,C0805_H57,4660.26,11655.70,0.000,YES
C353,"Q_CAP_C0805-47UF,4V,20%,X6S,CHA",47UF,20%,C0805_H57,4722.80,9928.20,270.000,YES
C354,"Q_CAP_C0805-47UF,4V,20%,X6S,CHA",47UF,20%,C0805_H57,4785.26,11655.70,180.000,YES
C355,"Q_CAP_C0805-47UF,4V,20%,X6S,CHA",47UF,20%,C0805_H57,14344.21,10072.99,270.000,YES
C356,"Q_CAP_C0805-47UF,4V,20%,X6S,CHA",47UF,20%,C0805_H57,13918.73,10328.69,0.000,YES
C357,"Q_CAP_C0805-47UF,4V,20%,X6S,CHA",47UF,20%,C0805_H57,13922.02,9783.39,270.000,YES
C358,"Q_CAP_C0805-47UF,4V,20%,X6S,CHA",47UF,20%,C0805_H57,14414.21,10072.99,270.000,YES
C359,"Q_CAP_C0805-47UF,4V,20%,X6S,CHA",47UF,20%,C0805_H57,13922.02,10072.99,270.000,YES
C360,"Q_CAP_C0805-47UF,4V,20%,X6S,CHA",47UF,20%,C0805_H57,13992.02,9493.79,90.000,YES
C361,"Q_CAP_C0805-47UF,4V,20%,X6S,CHA",47UF,20%,C0805_H57,14484.21,10072.99,270.000,YES
C362,"Q_CAP_C0805-47UF,4V,20%,X6S,CHA",47UF,20%,C0805_H57,13992.02,10072.99,270.000,YES
C363,"Q_CAP_C0805-47UF,4V,20%,X6S,CHA",47UF,20%,C0805_H57,14344.21,9358.97,90.000,YES
C364,"Q_CAP_C0805-47UF,4V,20%,X6S,CHA",47UF,20%,C0805_H57,14344.21,9928.19,270.000,YES
C365,"Q_CAP_C0805-47UF,4V,20%,X6S,CHA",47UF,20%,C0805_H57,13852.02,9928.19,270.000,YES
C366,"Q_CAP_C0805-47UF,4V,20%,X6S,CHA",47UF,20%,C0805_H57,13796.67,11575.19,180.000,YES
C367,"Q_CAP_C0805-47UF,4V,20%,X6S,CHA",47UF,20%,C0805_H57,14414.21,9928.19,270.000,YES
C368,"Q_CAP_C0805-47UF,4V,20%,X6S,CHA",47UF,20%,C0805_H57,13922.02,9928.19,270.000,YES
C369,"Q_CAP_C0805-47UF,4V,20%,X6S,CHA",47UF,20%,C0805_H57,13921.67,11575.19,0.000,YES
C370,"Q_CAP_C0805-47UF,4V,20%,X6S,CHA",47UF,20%,C0805_H57,14484.21,9928.19,270.000,YES
C371,"Q_CAP_C0805-47UF,4V,20%,X6S,CHA",47UF,20%,C0805_H57,13992.02,9928.19,270.000,YES
C372,"Q_CAP_C0805-47UF,4V,20%,X6S,CHA",47UF,20%,C0805_H57,14046.67,11575.19,180.000,YES
C373,"Q_CAP_C0805-47UF,4V,20%,X6S,CHA",47UF,20%,C0805_H57,14344.21,9783.39,270.000,YES
C374,"Q_CAP_C0805-47UF,4V,20%,X6S,CHA",47UF,20%,C0805_H57,14171.67,11575.19,0.000,YES
C376,"Q_CAP_C0805-47UF,4V,20%,X6S,CHA",47UF,20%,C0805_H57,14414.21,9783.39,270.000,YES
C377,"Q_CAP_C0805-47UF,4V,20%,X6S,CHA",47UF,20%,C0805_H57,14296.67,11575.19,180.000,YES
C379,"Q_CAP_C0805-47UF,4V,20%,X6S,CHA",47UF,20%,C0805_H57,14344.21,9638.59,270.000,YES
C380,"Q_CAP_C0805-47UF,4V,20%,X6S,CHA",47UF,20%,C0805_H57,14421.67,11575.19,0.000,YES
C381,"Q_CAP_C0805-47UF,4V,20%,X6S,CHA",47UF,20%,C0805_H57,14412.87,9494.75,270.000,YES
C382,"Q_CAP_C0805-47UF,4V,20%,X6S,CHA",47UF,20%,C0805_H57,14414.21,9638.59,270.000,YES
C383,"Q_CAP_C0805-47UF,4V,20%,X6S,CHA",47UF,20%,C0805_H57,14546.67,11575.19,180.000,YES
C385,"Q_CAP_C0805-47UF,4V,20%,X6S,CHA",47UF,20%,C0805_H57,14484.21,9638.59,270.000,YES
C386,"Q_CAP_C0805-47UF,4V,20%,X6S,CHA",47UF,20%,C0805_H57,13796.67,11655.69,180.000,YES
C387,"Q_CAP_C0805-47UF,4V,20%,X6S,CHA",47UF,20%,C0805_H57,14344.21,9493.79,270.000,YES
C388,"Q_CAP_C0805-47UF,4V,20%,X6S,CHA",47UF,20%,C0805_H57,13921.67,11655.69,0.000,YES
C389,"Q_CAP_C0805-47UF,4V,20%,X6S,CHA",47UF,20%,C0805_H57,13992.02,9783.39,270.000,YES
C390,"Q_CAP_C0805-47UF,4V,20%,X6S,CHA",47UF,20%,C0805_H57,14046.67,11655.69,180.000,YES
C391,"Q_CAP_C0805-47UF,4V,20%,X6S,CHA",47UF,20%,C0805_H57,13922.02,9638.59,270.000,YES
C392,"Q_CAP_C0805-47UF,4V,20%,X6S,CHA",47UF,20%,C0805_H57,14171.67,11655.69,0.000,YES
C393,"Q_CAP_C0805-47UF,4V,20%,X6S,CHA",47UF,20%,C0805_H57,13992.02,9638.59,270.000,YES
C394,"Q_CAP_C0805-47UF,4V,20%,X6S,CHA",47UF,20%,C0805_H57,14296.67,11655.69,180.000,YES
C395,"Q_CAP_C0805-47UF,4V,20%,X6S,CHA",47UF,20%,C0805_H57,13992.02,9368.79,270.000,YES
C396,"Q_CAP_C0805-47UF,4V,20%,X6S,CHA",47UF,20%,C0805_H57,14421.67,11655.69,0.000,YES
C397,"Q_CAP_C0805-47UF,4V,20%,X6S,CHA",47UF,20%,C0805_H57,13852.02,9638.59,270.000,YES
C398,"Q_CAP_C0805-47UF,4V,20%,X6S,CHA",47UF,20%,C0805_H57,14546.67,11655.69,180.000,YES
C399,"Q_CAP_C0402-22UF,4V,20%,X6S,CHA",22UF,20%,C0402_H32,14466.45,9752.56,90.000,NO
C400,"Q_CAP_C0402-22UF,4V,20%,X6S,CHA",22UF,20%,C0402_H32,13947.32,10250.59,270.000,NO
C401,"Q_CAP_C0402-22UF,4V,20%,X6S,CHA",22UF,20%,C0402_H32,13869.67,9670.63,270.000,NO
C402,"Q_CAP_C0402-22UF,4V,20%,X6S,CHA",22UF,20%,C0402_H32,14428.45,10250.59,270.000,NO
C403,"Q_CAP_C0402-22UF,4V,20%,X6S,CHA",22UF,20%,C0402_H32,14466.45,9670.63,270.000,NO
C404,"Q_CAP_C0402-22UF,4V,20%,X6S,CHA",22UF,20%,C0402_H32,14466.45,9459.72,90.000,NO
C405,"Q_CAP_C0402-22UF,4V,20%,X6S,CHA",22UF,20%,C0402_H32,13870.12,9752.56,90.000,NO
C406,"Q_CAP_C0402-22UF,4V,20%,X6S,CHA",22UF,20%,C0402_H32,13868.69,10250.59,270.000,NO
C407,"Q_CAP_C0402-22UF,4V,20%,X6S,CHA",22UF,20%,C0402_H32,14350.45,10250.59,270.000,NO
C408,"Q_CAP_C0402-22UF,4V,20%,X6S,CHA",22UF,20%,C0402_H32,14466.45,9376.47,90.000,NO
C409,"Q_CAP_C0402-22UF,4V,20%,X6S,CHA",22UF,20%,C0402_H32,13907.32,10250.59,270.000,NO
C410,"Q_CAP_C0402-22UF,4V,20%,X6S,CHA",22UF,20%,C0402_H32,14350.45,9376.47,90.000,NO
C411,"Q_CAP_C0402-22UF,4V,20%,X6S,CHA",22UF,20%,C0402_H32,14388.45,10250.59,270.000,NO
C412,"Q_CAP_C0402-22UF,4V,20%,X6S,CHA",22UF,20%,C0402_H32,14428.45,9376.47,90.000,NO
C413,"Q_CAP_C0402-22UF,4V,20%,X6S,CHA",22UF,20%,C0402_H32,13985.32,10250.59,270.000,NO
C414,"Q_CAP_C0402-22UF,4V,20%,X6S,CHA",22UF,20%,C0402_H32,14466.45,10250.59,270.000,NO
C415,"Q_CAP_C0402-22UF,4V,20%,X6S,CHA",22UF,20%,C0402_H32,14428.45,9459.72,90.000,NO
C416,"Q_CAP_C0402-22UF,4V,20%,X6S,CHA",22UF,20%,C0402_H32,14388.45,9376.47,90.000,NO
C417,"Q_CAP_C0402-22UF,4V,20%,X6S,CHA",22UF,20%,C0402_H32,13869.57,9376.47,270.000,NO
C418,"Q_CAP_C0402-22UF,4V,20%,X6S,CHA",22UF,20%,C0402_H32,13869.36,9459.72,90.000,NO
C419,"Q_CAP_C0402-22UF,4V,20%,X6S,CHA",22UF,20%,C0402_H32,13907.32,10186.09,90.000,NO
C420,"Q_CAP_C0402-22UF,4V,20%,X6S,CHA",22UF,20%,C0402_H32,13868.69,10186.09,90.000,NO
C421,"Q_CAP_C0402-22UF,4V,20%,X6S,CHA",22UF,20%,C0402_H32,13868.91,10104.49,270.000,NO
C422,"Q_CAP_C0402-22UF,4V,20%,X6S,CHA",22UF,20%,C0402_H32,13906.91,10104.49,270.000,NO
C423,"Q_CAP_C0402-22UF,4V,20%,X6S,CHA",22UF,20%,C0402_H32,4108.26,9670.64,270.000,NO
C424,"Q_CAP_C0402-22UF,4V,20%,X6S,CHA",22UF,20%,C0402_H32,4705.04,9459.73,90.000,NO
C425,"Q_CAP_C0402-22UF,4V,20%,X6S,CHA",22UF,20%,C0402_H32,4108.71,9752.57,90.000,NO
C426,"Q_CAP_C0402-22UF,4V,20%,X6S,CHA",22UF,20%,C0402_H32,4667.04,9459.73,90.000,NO
C427,"Q_CAP_C0402-22UF,4V,20%,X6S,CHA",22UF,20%,C0402_H32,4705.04,9752.57,90.000,NO
C428,"Q_CAP_C0402-22UF,4V,20%,X6S,CHA",22UF,20%,C0402_H32,4108.16,10250.60,270.000,NO
C429,"Q_CAP_C0402-22UF,4V,20%,X6S,CHA",22UF,20%,C0402_H32,4705.04,9670.64,270.000,NO
C430,"Q_CAP_C0402-22UF,4V,20%,X6S,CHA",22UF,20%,C0402_H32,4107.95,9459.73,90.000,NO
C431,"Q_CAP_C0402-22UF,4V,20%,X6S,CHA",22UF,20%,C0402_H32,4108.16,9376.48,270.000,NO
C432,"Q_CAP_C0402-22UF,4V,20%,X6S,CHA",22UF,20%,C0402_H32,4705.04,10250.60,270.000,NO
C433,"Q_CAP_C0402-22UF,4V,20%,X6S,CHA",22UF,20%,C0402_H32,4223.91,10250.60,270.000,NO
C434,"Q_CAP_C0402-22UF,4V,20%,X6S,CHA",22UF,20%,C0402_H32,4589.04,9376.48,90.000,NO
C435,"Q_CAP_C0402-22UF,4V,20%,X6S,CHA",22UF,20%,C0402_H32,4185.91,10250.60,270.000,NO
C436,"Q_CAP_C0402-22UF,4V,20%,X6S,CHA",22UF,20%,C0402_H32,4627.04,9376.48,90.000,NO
C437,"Q_CAP_C0402-22UF,4V,20%,X6S,CHA",22UF,20%,C0402_H32,4145.91,10250.60,270.000,NO
C438,"Q_CAP_C0402-22UF,4V,20%,X6S,CHA",22UF,20%,C0402_H32,4667.04,9376.48,90.000,NO
C439,"Q_CAP_C0402-22UF,4V,20%,X6S,CHA",22UF,20%,C0402_H32,4589.04,10250.60,270.000,NO
C440,"Q_CAP_C0402-22UF,4V,20%,X6S,CHA",22UF,20%,C0402_H32,4705.04,9376.48,90.000,NO
C441,"Q_CAP_C0402-22UF,4V,20%,X6S,CHA",22UF,20%,C0402_H32,4627.04,10250.60,270.000,NO
C442,"Q_CAP_C0402-22UF,4V,20%,X6S,CHA",22UF,20%,C0402_H32,4667.04,10250.60,270.000,NO
C443,"Q_CAP_C0402-22UF,4V,20%,X6S,CHA",22UF,20%,C0402_H32,4145.91,10186.10,90.000,NO
C444,"Q_CAP_C0402-22UF,4V,20%,X6S,CHA",22UF,20%,C0402_H32,4108.16,10186.10,90.000,NO
C445,"Q_CAP_C0402-22UF,4V,20%,X6S,CHA",22UF,20%,C0402_H32,4145.50,10104.50,270.000,NO
C446,"Q_CAP_C0402-22UF,4V,20%,X6S,CHA",22UF,20%,C0402_H32,4108.38,10104.50,270.000,NO
C447,"Q_CAP_C0805-47UF,4V,20%,X6S,CHA",47UF,20%,C0805_H57,4722.80,9783.40,270.000,YES
C448,"Q_CAP_C0805-47UF,4V,20%,X6S,CHA",47UF,20%,C0805_H57,4090.61,10217.84,270.000,YES
C449,"Q_CAP_C0805-47UF,4V,20%,X6S,CHA",47UF,20%,C0805_H57,4652.80,10217.80,90.000,YES
C450,"Q_CAP_C0805-47UF,4V,20%,X6S,CHA",47UF,20%,C0805_H57,4582.80,10217.80,90.000,YES
C451,"Q_CAP_C0805-47UF,4V,20%,X6S,CHA",47UF,20%,C0805_H57,4090.61,9783.40,270.000,YES
C452,"Q_CAP_C0805-47UF,4V,20%,X6S,CHA",47UF,20%,C0805_H57,4090.61,10073.00,90.000,YES
C453,"Q_CAP_C0805-47UF,4V,20%,X6S,CHA",47UF,20%,C0805_H57,2561.72,9873.74,90.000,YES
C454,"Q_CAP_C0805-47UF,4V,20%,X6S,CHA",47UF,20%,C0805_H57,2481.02,10175.79,270.000,YES
C455,"Q_CAP_C0805-47UF,4V,20%,X6S,CHA",47UF,20%,C0805_H57,4382.32,8275.36,0.000,YES
C456,"Q_CAP_C0805-47UF,4V,20%,X6S,CHA",47UF,20%,C0805_H57,4112.72,8275.36,0.000,YES
C457,"Q_CAP_C0805-47UF,4V,20%,X6S,CHA",47UF,20%,C0805_H57,4230.61,10217.80,90.000,YES
C458,"Q_CAP_C0805-47UF,4V,20%,X6S,CHA",47UF,20%,C0805_H57,2396.58,10175.86,270.000,YES
C459,"Q_CAP_C0805-47UF,4V,20%,X6S,CHA",47UF,20%,C0805_H57,4517.12,8275.36,180.000,YES
C460,"Q_CAP_C0805-47UF,4V,20%,X6S,CHA",47UF,20%,C0805_H57,4247.52,8348.42,180.000,YES
C461,"Q_CAP_C0805-47UF,4V,20%,X6S,CHA",47UF,20%,C0805_H57,4160.61,10217.80,90.000,YES
C462,"Q_CAP_C0805-47UF,4V,20%,X6S,CHA",47UF,20%,C0805_H57,2400.72,9872.74,90.000,YES
C463,"Q_CAP_C0805-47UF,4V,20%,X6S,CHA",47UF,20%,C0805_H57,4382.29,8348.42,0.000,YES
C464,"Q_CAP_C0805-47UF,4V,20%,X6S,CHA",47UF,20%,C0805_H57,4112.72,8348.42,0.000,YES
C465,"Q_CAP_C0603-47UF,2.5V,20%,X6S,A",47UF,20%,C0603,4734.80,9358.64,90.000,YES
C466,"Q_CAP_C0805-47UF,4V,20%,X6S,CHA",47UF,20%,C0805_H57,2264.48,10154.28,270.000,YES
C467,"Q_CAP_C0805-47UF,4V,20%,X6S,CHA",47UF,20%,C0805_H57,4517.09,8348.42,180.000,YES
C468,"Q_CAP_C0805-47UF,4V,20%,X6S,CHA",47UF,20%,C0805_H57,4247.52,8275.36,180.000,YES
C470,"Q_CAP_C0805-47UF,4V,20%,X6S,CHA",47UF,20%,C0805_H57,2555.28,10176.09,270.000,YES
C471,"Q_CAP_C0805-47UF,4V,20%,X6S,CHA",47UF,20%,C0805_H57,4719.17,9493.05,90.000,YES
C472,"Q_CAP_C0603-47UF,2.5V,20%,X6S,A",47UF,20%,C0603,3992.32,8284.21,180.000,YES
C473,"Q_CAP_C0805-47UF,4V,20%,X6S,CHA",47UF,20%,C0805_H57,6253.40,10153.35,270.000,YES
C474,"Q_CAP_C0805-47UF,4V,20%,X6S,CHA",47UF,20%,C0805_H57,4093.67,9496.35,90.000,YES
C475,"Q_CAP_C0603-47UF,2.5V,20%,X6S,A",47UF,20%,C0603,3992.32,8348.42,180.000,YES
C476,"Q_CAP_C0805-47UF,4V,20%,X6S,CHA",47UF,20%,C0805_H57,6334.35,10173.21,270.000,YES
C477,"Q_CAP_C0805-47UF,4V,20%,X6S,CHA",47UF,20%,C0805_H57,6253.55,9865.45,90.000,YES
C478,"Q_CAP_C0805-47UF,4V,20%,X6S,CHA",47UF,20%,C0805_H57,4722.80,10217.80,90.000,YES
C479,"Q_CAP_C0805-47UF,4V,20%,X6S,CHA",47UF,20%,C0805_H57,6410.44,10173.21,270.000,YES
C481,"Q_CAP_C0805-47UF,4V,20%,X6S,CHA",47UF,20%,C0805_H57,4651.89,8348.42,0.000,YES
C482,"Q_CAP_C0805-47UF,4V,20%,X6S,CHA",47UF,20%,C0805_H57,6485.27,10097.99,270.000,YES
C483,"Q_CAP_C0805-47UF,4V,20%,X6S,CHA",47UF,20%,C0805_H57,4162.47,9495.85,90.000,YES
C484,"Q_CAP_C0805-47UF,4V,20%,X6S,CHA",47UF,20%,C0805_H57,4786.69,8348.42,180.000,YES
C485,"Q_CAP_C0805-47UF,4V,20%,X6S,CHA",47UF,20%,C0805_H57,6415.60,9854.34,90.000,YES
C486,"Q_CAP_C0805-47UF,4V,20%,X6S,CHA",47UF,20%,C0805_H57,4651.92,8275.36,0.000,YES
C487,"Q_CAP_C0805-47UF,4V,20%,X6S,CHA",47UF,20%,C0805_H57,4786.72,8275.36,180.000,YES
C488,"Q_CAP_C0603-47UF,2.5V,20%,X6S,A",47UF,20%,C0603,4687.80,9358.64,270.000,YES
C489,"Q_CAP_C0603-47UF,2.5V,20%,X6S,A",47UF,20%,C0603,4640.80,9358.64,270.000,YES
C490,"Q_CAP_C0402-22UF,4V,20%,X6S,CHA",22UF,20%,C0402_H32,4730.13,10316.24,270.000,YES
C491,"Q_CAP_C0805-47UF,4V,20%,X6S,CHA",47UF,20%,C0805_H57,14484.21,9783.39,270.000,YES
C492,"Q_CAP_C0805-47UF,4V,20%,X6S,CHA",47UF,20%,C0805_H57,13852.02,10072.99,90.000,YES
C493,"Q_CAP_C0805-47UF,4V,20%,X6S,CHA",47UF,20%,C0805_H57,14414.21,10217.79,90.000,YES
C494,"Q_CAP_C0805-47UF,4V,20%,X6S,CHA",47UF,20%,C0805_H57,16014.82,10153.15,270.000,YES
C495,"Q_CAP_C0805-47UF,4V,20%,X6S,CHA",47UF,20%,C0805_H57,13852.02,9783.39,270.000,YES
C496,"Q_CAP_C0805-47UF,4V,20%,X6S,CHA",47UF,20%,C0805_H57,13852.02,10217.83,270.000,YES
C497,"Q_CAP_C0805-47UF,4V,20%,X6S,CHA",47UF,20%,C0805_H57,14344.21,10217.79,90.000,YES
C498,"Q_CAP_C0805-47UF,4V,20%,X6S,CHA",47UF,20%,C0805_H57,16094.77,10170.01,270.000,YES
C499,"Q_CAP_C0805-47UF,4V,20%,X6S,CHA",47UF,20%,C0805_H57,14143.70,8348.41,0.000,YES
C500,"Q_CAP_C0805-47UF,4V,20%,X6S,CHA",47UF,20%,C0805_H57,13874.13,8275.35,0.000,YES
C501,"Q_CAP_C0805-47UF,4V,20%,X6S,CHA",47UF,20%,C0805_H57,13922.02,10217.79,90.000,YES
C502,"Q_CAP_C0805-47UF,4V,20%,X6S,CHA",47UF,20%,C0805_H57,16013.97,9872.25,90.000,YES
C503,"Q_CAP_C0805-47UF,4V,20%,X6S,CHA",47UF,20%,C0805_H57,14278.50,8348.41,180.000,YES
C504,"Q_CAP_C0805-47UF,4V,20%,X6S,CHA",47UF,20%,C0805_H57,14008.93,8348.41,180.000,YES
C505,"Q_CAP_C0805-47UF,4V,20%,X6S,CHA",47UF,20%,C0805_H57,13992.02,10217.79,90.000,YES
C506,"Q_CAP_C0805-47UF,4V,20%,X6S,CHA",47UF,20%,C0805_H57,16175.26,9873.67,90.000,YES
C507,"Q_CAP_C0805-47UF,4V,20%,X6S,CHA",47UF,20%,C0805_H57,14143.73,8275.35,0.000,YES
C508,"Q_CAP_C0805-47UF,4V,20%,X6S,CHA",47UF,20%,C0805_H57,14008.93,8275.35,180.000,YES
C509,"Q_CAP_C0603-47UF,2.5V,20%,X6S,A",47UF,20%,C0603,14496.21,9358.63,90.000,YES
C510,"Q_CAP_C0805-47UF,4V,20%,X6S,CHA",47UF,20%,C0805_H57,16242.06,10103.79,270.000,YES
C511,"Q_CAP_C0805-47UF,4V,20%,X6S,CHA",47UF,20%,C0805_H57,14278.53,8275.35,180.000,YES
C512,"Q_CAP_C0805-47UF,4V,20%,X6S,CHA",47UF,20%,C0805_H57,13874.13,8348.41,0.000,YES
C513,"Q_CAP_C0805-22UF,16V,20%,X6S,CA",22UF,20%,C0805_H57,12885.08,623.21,0.000,NO
C514,"Q_CAP_C0805-47UF,4V,20%,X6S,CHA",47UF,20%,C0805_H57,16173.86,10165.66,270.000,YES
C515,"Q_CAP_C0805-47UF,4V,20%,X6S,CHA",47UF,20%,C0805_H57,14481.27,9492.75,90.000,YES
C516,"Q_CAP_C0603-47UF,2.5V,20%,X6S,A",47UF,20%,C0603,13753.73,8284.20,180.000,YES
C517,"Q_CAP_C0805-47UF,4V,20%,X6S,CHA",47UF,20%,C0805_H57,12158.41,10172.44,270.000,YES
C518,"Q_CAP_C0805-47UF,4V,20%,X6S,CHA",47UF,20%,C0805_H57,13855.47,9496.05,90.000,YES
C519,"Q_CAP_C0603-47UF,2.5V,20%,X6S,A",47UF,20%,C0603,13753.73,8348.41,180.000,YES
C520,"Q_CAP_C0805-47UF,4V,20%,X6S,CHA",47UF,20%,C0805_H57,12161.52,9873.44,90.000,YES
C521,"Q_CAP_C0805-47UF,4V,20%,X6S,CHA",47UF,20%,C0805_H57,12026.41,10172.44,270.000,YES
C522,"Q_CAP_C0805-47UF,4V,20%,X6S,CHA",47UF,20%,C0805_H57,14484.21,10217.79,90.000,YES
C523,"Q_CAP_C0805-47UF,4V,20%,X6S,CHA",47UF,20%,C0805_H57,12242.41,10172.44,270.000,YES
C525,"Q_CAP_C0805-47UF,4V,20%,X6S,CHA",47UF,20%,C0805_H57,14413.30,8348.41,0.000,YES
C526,"Q_CAP_C0805-47UF,4V,20%,X6S,CHA",47UF,20%,C0805_H57,12323.41,10172.44,270.000,YES
C527,"Q_CAP_C0805-47UF,4V,20%,X6S,CHA",47UF,20%,C0805_H57,13923.57,9493.65,90.000,YES
C528,"Q_CAP_C0805-47UF,4V,20%,X6S,CHA",47UF,20%,C0805_H57,14548.13,8275.35,180.000,YES
C529,"Q_CAP_C0805-47UF,4V,20%,X6S,CHA",47UF,20%,C0805_H57,12322.41,9873.44,90.000,YES
C530,"Q_CAP_C0805-47UF,4V,20%,X6S,CHA",47UF,20%,C0805_H57,14413.33,8275.35,0.000,YES
C531,"Q_CAP_C0805-47UF,4V,20%,X6S,CHA",47UF,20%,C0805_H57,14548.10,8348.41,180.000,YES
C532,"Q_CAP_C0603-47UF,2.5V,20%,X6S,A",47UF,20%,C0603,14449.21,9358.63,270.000,YES
C533,"Q_CAP_C0603-47UF,2.5V,20%,X6S,A",47UF,20%,C0603,14402.21,9358.63,270.000,YES
C534,"Q_CAP_C0402-22UF,4V,20%,X6S,CHA",22UF,20%,C0402_H32,14494.43,10313.13,270.000,YES
C535,"Q_CAP_C0805-22UF,16V,20%,X6S,CA",22UF,20%,C0805_H57,12885.08,541.21,0.000,NO
C537,"Q_CAP_0402-0.1UF,25V,10%,X7R,CA",0.1UF,10%,C0402,3241.06,6008.73,90.000,NO
C538,"Q_CAP_0402-0.1UF,25V,10%,X7R,CA",0.1UF,10%,C0402,11947.73,5887.14,180.000,YES
C539,"Q_CAP_0402-0.1UF,25V,10%,X7R,CA",0.1UF,10%,C0402,8036.77,7639.15,0.000,YES
C540,"Q_CAP_0402-0.1UF,25V,10%,X7R,CA",0.1UF,10%,C0402,8259.64,7643.16,0.000,YES
C541,"Q_CAP_C0402-1UF,25V,10%,X6S,CHA",1UF,10%,C0402,8036.77,7596.65,0.000,YES
C542,"Q_CAP_C0402-1UF,25V,10%,X6S,CHA",1UF,10%,C0402,8258.67,7602.15,0.000,YES
C543,"Q_CAP_0402-0.1UF,25V,10%,X7R,CA",0.1UF,10%,C0402,7644.07,7615.55,0.000,YES
C544,"Q_CAP_0402-0.1UF,25V,10%,X7R,CA",0.1UF,10%,C0402,8418.97,7700.25,0.000,YES
C545,"Q_CAP_C0402-1UF,25V,10%,X6S,CHA",1UF,10%,C0402,14653.83,2424.48,0.000,NO
C546,"Q_CAP_C0402-1UF,25V,10%,X6S,CHA",1UF,10%,C0402,14650.85,2713.78,0.000,NO
C547,"Q_CAP_C0402-1UF,25V,10%,X6S,CHA",1UF,10%,C0402,15185.68,2626.16,180.000,NO
C548,"Q_CAP_0402-0.1UF,25V,10%,X7R,CA",0.1UF,10%,C0402,15905.98,2155.68,180.000,YES
C549,"Q_CAP_0402-0.1UF,25V,10%,X7R,CA",0.1UF,10%,C0402,15903.19,2521.26,0.000,NO
C550,"Q_CAP_C0402-1UF,25V,10%,X6S,CHA",1UF,10%,C0402,15628.90,2419.22,90.000,YES
C551,"Q_CAP_C0402-1UF,25V,10%,X6S,CHA",1UF,10%,C0402,15618.90,2002.52,90.000,YES
C552,"Q_CAP_0402-0.1UF,25V,10%,X7R,CA",0.1UF,10%,C0402,15905.78,2195.26,0.000,NO
C554,"Q_CAP_0402-0.1UF,25V,10%,X7R,CA",0.1UF,10%,C0402,5257.20,2923.62,90.000,NO
C559,"Q_CAP_0402-0.1UF,25V,10%,X7R,CA",0.1UF,10%,C0402,14617.07,7463.05,180.000,YES
C560,"Q_CAP_0402-0.1UF,25V,10%,X7R,CA",0.1UF,10%,C0402,698.90,7631.64,180.000,YES
C561,"Q_CAP_0402-0.1UF,25V,10%,X7R,CA",0.1UF,10%,C0402,14479.47,7463.05,0.000,YES
C562,"Q_CAP_0402-0.1UF,25V,10%,X7R,CA",0.1UF,10%,C0402,408.39,7709.32,270.000,YES
C563,"Q_CAP_C0805-10UF,25V,10%,X6S,CA",10UF,10%,C0805_H61,5312.20,2923.62,90.000,NO
C567,"Q_CAP_0402-0.1UF,25V,10%,X7R,CA",0.1UF,10%,C0402,15572.87,6304.35,90.000,NO
C568,"Q_CAP_0402-0.1UF,25V,10%,X7R,CA",0.1UF,10%,C0402,8807.72,8783.35,270.000,NO
C569,"Q_CAP_0402-0.1UF,25V,10%,X7R,CA",0.1UF,10%,C0402,15567.47,5909.15,270.000,NO
C570,"Q_CAP_0402-0.1UF,25V,10%,X7R,CA",0.1UF,10%,C0402,8813.72,9164.55,90.000,NO
C578,"Q_CAP_0402-0.1UF,25V,10%,X7R,CA",0.1UF,10%,C0402,17788.10,4455.62,270.000,NO
C579,"Q_CAP_0402-0.1UF,25V,10%,X7R,CA",0.1UF,10%,C0402,18172.41,4725.21,0.000,NO
C580,"Q_CAP_0402-0.1UF,25V,10%,X7R,CA",0.1UF,10%,C0402,15276.58,1506.51,180.000,NO
C581,"Q_CAP_0402-0.1UF,25V,10%,X7R,CA",0.1UF,10%,C0402,15439.52,1528.73,0.000,NO
C590,"Q_CAP_C0402-22UF,4V,20%,X6S,CHA",22UF,20%,C0402_H32,13907.19,9376.38,90.000,NO
C592,"Q_CAP_0402-0.1UF,25V,10%,X7R,CA",0.1UF,10%,C0402,18172.99,4214.32,0.000,NO
C593,"Q_CAP_0402-0.1UF,25V,10%,X7R,CA",0.1UF,10%,C0402,18177.99,4079.32,0.000,NO
C605,"Q_CAP_C0402-1UF,25V,10%,X6S,CHA",1UF,10%,C0402,13301.02,638.57,270.000,NO
C606,"Q_CAP_C0402-1UF,25V,10%,X6S,CHA",1UF,10%,C0402,13116.36,740.06,270.000,NO
C607,"Q_CAP_0402-0.1UF,25V,10%,X7R,CA",0.1UF,10%,C0402,13259.02,638.57,270.000,NO
C608,"Q_CAP_0402-0.1UF,25V,10%,X7R,CA",0.1UF,10%,C0402,13156.49,740.05,270.000,NO
C609,"Q_CAP_0402-0.1UF,25V,10%,X7R,CA",0.1UF,10%,C0402,12690.93,1332.62,225.000,NO
C610,"Q_CAP_C0402-1UF,25V,10%,X6S,CHA",1UF,10%,C0402,12802.91,1029.28,180.000,NO
C611,"Q_CAP_C0402-1UF,25V,10%,X6S,CHA",1UF,10%,C0402,11949.76,1278.04,0.000,NO
C613,"Q_CAP_C0402-1UF,25V,10%,EMPTY,A",NA,10%,C0402,7530.09,7622.64,270.000,YES
C614,"Q_CAP_C0402-1UF,25V,10%,EMPTY,A",NA,10%,C0402,1360.29,7595.44,270.000,YES
C615,"Q_CAP_C0402-1UF,25V,10%,EMPTY,A",NA,10%,C0402,997.79,7604.44,270.000,YES
C616,"Q_CAP_C0402-1UF,25V,10%,EMPTY,A",NA,10%,C0402,7369.09,7622.04,270.000,YES
C621,"Q_CAP_C0402-1UF,25V,10%,EMPTY,A",NA,10%,C0402,17028.48,7620.68,270.000,YES
C622,"Q_CAP_C0402-1UF,25V,10%,EMPTY,A",NA,10%,C0402,11158.69,7625.64,270.000,YES
C623,"Q_CAP_C0402-1UF,25V,10%,EMPTY,A",NA,10%,C0402,10577.49,7618.24,270.000,YES
C624,"Q_CAP_C0402-1UF,25V,10%,EMPTY,A",NA,10%,C0402,16586.79,7612.34,270.000,YES
C626,"Q_CAP_0402-1000PF,50V,5%,EMPTYA",NA,5%,C0402,17214.29,4748.59,0.000,NO
C629,"Q_CAP_0402-0.1UF,25V,10%,X7R,CA",0.1UF,10%,C0402,11388.90,3770.11,0.000,NO
C639,"Q_CAP_0402-0.1UF,25V,10%,X7R,CA",0.1UF,10%,C0402,18185.69,3955.52,0.000,NO
C640,"Q_CAP_0402-0.1UF,25V,10%,X7R,CA",0.1UF,10%,C0402,7651.43,3112.49,0.000,NO
C641,"Q_CAP_0402-0.1UF,25V,10%,X7R,CA",0.1UF,10%,C0402,8452.47,2710.49,180.000,NO
C678,Q_CAP_DIFFBUS_C0201-DIFF BUS_0A,,,C0201_DIFF-BUS,3749.97,16083.36,270.000,NO
C679,Q_CAP_DIFFBUS_C0201-DIFF BUS_0A,,,C0201_DIFF-BUS,3785.97,16083.36,270.000,NO
C680,Q_CAP_DIFFBUS_C0201-DIFF BUS_0A,,,C0201_DIFF-BUS,3629.37,16083.36,270.000,NO
C681,Q_CAP_DIFFBUS_C0201-DIFF BUS_0A,,,C0201_DIFF-BUS,3665.37,16083.36,270.000,NO
C682,Q_CAP_DIFFBUS_C0201-DIFF BUS_0A,,,C0201_DIFF-BUS,3508.77,16083.36,270.000,NO
C683,Q_CAP_DIFFBUS_C0201-DIFF BUS_0A,,,C0201_DIFF-BUS,3544.77,16083.36,270.000,NO
C684,Q_CAP_DIFFBUS_C0201-DIFF BUS_0A,,,C0201_DIFF-BUS,3388.17,16083.36,270.000,NO
C685,Q_CAP_DIFFBUS_C0201-DIFF BUS_0A,,,C0201_DIFF-BUS,3424.17,16083.36,270.000,NO
C686,Q_CAP_DIFFBUS_C0201-DIFF BUS_0A,,,C0201_DIFF-BUS,3303.57,16083.36,270.000,NO
C687,Q_CAP_DIFFBUS_C0201-DIFF BUS_0A,,,C0201_DIFF-BUS,3267.57,16083.36,270.000,NO
C688,Q_CAP_DIFFBUS_C0201-DIFF BUS_0A,,,C0201_DIFF-BUS,3146.97,16083.36,270.000,NO
C689,Q_CAP_DIFFBUS_C0201-DIFF BUS_0A,,,C0201_DIFF-BUS,3182.97,16083.36,270.000,NO
C690,Q_CAP_DIFFBUS_C0201-DIFF BUS_0A,,,C0201_DIFF-BUS,3026.37,16083.36,270.000,NO
C691,Q_CAP_DIFFBUS_C0201-DIFF BUS_0A,,,C0201_DIFF-BUS,3062.37,16083.36,270.000,NO
C692,Q_CAP_DIFFBUS_C0201-DIFF BUS_0A,,,C0201_DIFF-BUS,2905.77,16083.36,270.000,NO
C693,Q_CAP_DIFFBUS_C0201-DIFF BUS_0A,,,C0201_DIFF-BUS,2941.77,16083.36,270.000,NO
C694,Q_CAP_DIFFBUS_C0201-DIFF BUS_0A,,,C0201_DIFF-BUS,2785.17,16083.36,270.000,NO
C695,Q_CAP_DIFFBUS_C0201-DIFF BUS_0A,,,C0201_DIFF-BUS,2821.17,16083.36,270.000,NO
C696,Q_CAP_DIFFBUS_C0201-DIFF BUS_0A,,,C0201_DIFF-BUS,2664.57,16083.36,270.000,NO
C697,Q_CAP_DIFFBUS_C0201-DIFF BUS_0A,,,C0201_DIFF-BUS,2700.57,16083.36,270.000,NO
C698,Q_CAP_DIFFBUS_C0201-DIFF BUS_0A,,,C0201_DIFF-BUS,2543.97,16083.36,270.000,NO
C699,Q_CAP_DIFFBUS_C0201-DIFF BUS_0A,,,C0201_DIFF-BUS,2579.97,16083.36,270.000,NO
C700,Q_CAP_DIFFBUS_C0201-DIFF BUS_0A,,,C0201_DIFF-BUS,2423.37,16083.36,270.000,NO
C701,Q_CAP_DIFFBUS_C0201-DIFF BUS_0A,,,C0201_DIFF-BUS,2459.37,16083.36,270.000,NO
C702,Q_CAP_DIFFBUS_C0201-DIFF BUS_0A,,,C0201_DIFF-BUS,2302.77,16083.36,270.000,NO
C703,Q_CAP_DIFFBUS_C0201-DIFF BUS_0A,,,C0201_DIFF-BUS,2338.77,16083.36,270.000,NO
C704,Q_CAP_DIFFBUS_C0201-DIFF BUS_0A,,,C0201_DIFF-BUS,2182.17,16083.36,270.000,NO
C705,Q_CAP_DIFFBUS_C0201-DIFF BUS_0A,,,C0201_DIFF-BUS,2218.17,16083.36,270.000,NO
C706,Q_CAP_DIFFBUS_C0201-DIFF BUS_0A,,,C0201_DIFF-BUS,2097.57,16083.36,270.000,NO
C707,Q_CAP_DIFFBUS_C0201-DIFF BUS_0A,,,C0201_DIFF-BUS,2061.57,16083.36,270.000,NO
C708,Q_CAP_DIFFBUS_C0201-DIFF BUS_0A,,,C0201_DIFF-BUS,1940.97,16083.36,270.000,NO
C709,Q_CAP_DIFFBUS_C0201-DIFF BUS_0A,,,C0201_DIFF-BUS,1976.97,16083.36,270.000,NO
C710,Q_CAP_DIFFBUS_C0201-DIFF BUS_0A,,,C0201_DIFF-BUS,1887.97,15841.38,270.000,NO
C711,Q_CAP_DIFFBUS_C0201-DIFF BUS_0A,,,C0201_DIFF-BUS,1923.97,15841.38,270.000,NO
C712,Q_CAP_DIFFBUS_C0201-DIFF BUS_0A,,,C0201_DIFF-BUS,2008.57,15841.38,270.000,NO
C713,Q_CAP_DIFFBUS_C0201-DIFF BUS_0A,,,C0201_DIFF-BUS,2044.57,15841.38,270.000,NO
C714,Q_CAP_DIFFBUS_C0201-DIFF BUS_0A,,,C0201_DIFF-BUS,2129.17,15841.38,270.000,NO
C715,Q_CAP_DIFFBUS_C0201-DIFF BUS_0A,,,C0201_DIFF-BUS,2165.17,15841.38,270.000,NO
C716,Q_CAP_DIFFBUS_C0201-DIFF BUS_0A,,,C0201_DIFF-BUS,2249.77,15841.38,270.000,NO
C717,Q_CAP_DIFFBUS_C0201-DIFF BUS_0A,,,C0201_DIFF-BUS,2285.77,15841.38,270.000,NO
C718,Q_CAP_DIFFBUS_C0201-DIFF BUS_0A,,,C0201_DIFF-BUS,2370.37,15841.38,270.000,NO
C719,Q_CAP_DIFFBUS_C0201-DIFF BUS_0A,,,C0201_DIFF-BUS,2406.37,15841.38,270.000,NO
C720,Q_CAP_DIFFBUS_C0201-DIFF BUS_0A,,,C0201_DIFF-BUS,2490.97,15841.38,270.000,NO
C721,Q_CAP_DIFFBUS_C0201-DIFF BUS_0A,,,C0201_DIFF-BUS,2526.97,15841.38,270.000,NO
C722,Q_CAP_DIFFBUS_C0201-DIFF BUS_0A,,,C0201_DIFF-BUS,2611.57,15841.38,270.000,NO
C723,Q_CAP_DIFFBUS_C0201-DIFF BUS_0A,,,C0201_DIFF-BUS,2647.57,15841.38,270.000,NO
C724,Q_CAP_DIFFBUS_C0201-DIFF BUS_0A,,,C0201_DIFF-BUS,2732.17,15841.38,270.000,NO
C725,Q_CAP_DIFFBUS_C0201-DIFF BUS_0A,,,C0201_DIFF-BUS,2768.17,15841.38,270.000,NO
C726,Q_CAP_DIFFBUS_C0201-DIFF BUS_0A,,,C0201_DIFF-BUS,2852.77,15841.38,270.000,NO
C727,Q_CAP_DIFFBUS_C0201-DIFF BUS_0A,,,C0201_DIFF-BUS,2888.77,15841.38,270.000,NO
C728,Q_CAP_DIFFBUS_C0201-DIFF BUS_0A,,,C0201_DIFF-BUS,2973.37,15841.38,270.000,NO
C729,Q_CAP_DIFFBUS_C0201-DIFF BUS_0A,,,C0201_DIFF-BUS,3009.37,15841.38,270.000,NO
C730,Q_CAP_DIFFBUS_C0201-DIFF BUS_0A,,,C0201_DIFF-BUS,3093.97,15841.38,270.000,NO
C731,Q_CAP_DIFFBUS_C0201-DIFF BUS_0A,,,C0201_DIFF-BUS,3129.97,15841.38,270.000,NO
C732,Q_CAP_DIFFBUS_C0201-DIFF BUS_0A,,,C0201_DIFF-BUS,3214.57,15841.38,270.000,NO
C733,Q_CAP_DIFFBUS_C0201-DIFF BUS_0A,,,C0201_DIFF-BUS,3250.57,15841.38,270.000,NO
C734,Q_CAP_DIFFBUS_C0201-DIFF BUS_0A,,,C0201_DIFF-BUS,3335.17,15841.38,270.000,NO
C735,Q_CAP_DIFFBUS_C0201-DIFF BUS_0A,,,C0201_DIFF-BUS,3371.17,15841.38,270.000,NO
C736,Q_CAP_DIFFBUS_C0201-DIFF BUS_0A,,,C0201_DIFF-BUS,3455.77,15841.38,270.000,NO
C737,Q_CAP_DIFFBUS_C0201-DIFF BUS_0A,,,C0201_DIFF-BUS,3491.77,15841.38,270.000,NO
C738,Q_CAP_DIFFBUS_C0201-DIFF BUS_0A,,,C0201_DIFF-BUS,3576.37,15841.38,270.000,NO
C739,Q_CAP_DIFFBUS_C0201-DIFF BUS_0A,,,C0201_DIFF-BUS,3612.37,15841.38,270.000,NO
C740,Q_CAP_DIFFBUS_C0201-DIFF BUS_0A,,,C0201_DIFF-BUS,3696.97,15841.38,270.000,NO
C741,Q_CAP_DIFFBUS_C0201-DIFF BUS_0A,,,C0201_DIFF-BUS,3732.97,15841.38,270.000,NO
C742,Q_CAP_DIFFBUS_C0201-DIFF BUS_0A,,,C0201_DIFF-BUS,4765.51,15841.38,270.000,NO
C743,Q_CAP_DIFFBUS_C0201-DIFF BUS_0A,,,C0201_DIFF-BUS,4729.51,15841.38,270.000,NO
C744,Q_CAP_DIFFBUS_C0201-DIFF BUS_0A,,,C0201_DIFF-BUS,4886.11,15841.38,270.000,NO
C745,Q_CAP_DIFFBUS_C0201-DIFF BUS_0A,,,C0201_DIFF-BUS,4850.11,15841.38,270.000,NO
C746,Q_CAP_DIFFBUS_C0201-DIFF BUS_0A,,,C0201_DIFF-BUS,5006.71,15841.38,270.000,NO
C747,Q_CAP_DIFFBUS_C0201-DIFF BUS_0A,,,C0201_DIFF-BUS,4970.71,15841.38,270.000,NO
C748,Q_CAP_DIFFBUS_C0201-DIFF BUS_0A,,,C0201_DIFF-BUS,5127.31,15841.38,270.000,NO
C749,Q_CAP_DIFFBUS_C0201-DIFF BUS_0A,,,C0201_DIFF-BUS,5091.31,15841.38,270.000,NO
C750,Q_CAP_DIFFBUS_C0201-DIFF BUS_0A,,,C0201_DIFF-BUS,5247.91,15841.38,270.000,NO
C751,Q_CAP_DIFFBUS_C0201-DIFF BUS_0A,,,C0201_DIFF-BUS,5211.91,15841.38,270.000,NO
C752,Q_CAP_DIFFBUS_C0201-DIFF BUS_0A,,,C0201_DIFF-BUS,5368.51,15841.38,270.000,NO
C753,Q_CAP_DIFFBUS_C0201-DIFF BUS_0A,,,C0201_DIFF-BUS,5332.51,15841.38,270.000,NO
C754,Q_CAP_DIFFBUS_C0201-DIFF BUS_0A,,,C0201_DIFF-BUS,5489.11,15841.38,270.000,NO
C755,Q_CAP_DIFFBUS_C0201-DIFF BUS_0A,,,C0201_DIFF-BUS,5453.11,15841.38,270.000,NO
C756,Q_CAP_DIFFBUS_C0201-DIFF BUS_0A,,,C0201_DIFF-BUS,5609.71,15841.38,270.000,NO
C757,Q_CAP_DIFFBUS_C0201-DIFF BUS_0A,,,C0201_DIFF-BUS,5573.71,15841.38,270.000,NO
C758,Q_CAP_DIFFBUS_C0201-DIFF BUS_0A,,,C0201_DIFF-BUS,5730.31,15841.38,270.000,NO
C759,Q_CAP_DIFFBUS_C0201-DIFF BUS_0A,,,C0201_DIFF-BUS,5694.31,15841.38,270.000,NO
C760,Q_CAP_DIFFBUS_C0201-DIFF BUS_0A,,,C0201_DIFF-BUS,5850.91,15841.38,270.000,NO
C761,Q_CAP_DIFFBUS_C0201-DIFF BUS_0A,,,C0201_DIFF-BUS,5814.91,15841.38,270.000,NO
C762,Q_CAP_DIFFBUS_C0201-DIFF BUS_0A,,,C0201_DIFF-BUS,5971.51,15841.38,270.000,NO
C763,Q_CAP_DIFFBUS_C0201-DIFF BUS_0A,,,C0201_DIFF-BUS,5935.51,15841.38,270.000,NO
C764,Q_CAP_DIFFBUS_C0201-DIFF BUS_0A,,,C0201_DIFF-BUS,6092.11,15841.38,270.000,NO
C765,Q_CAP_DIFFBUS_C0201-DIFF BUS_0A,,,C0201_DIFF-BUS,6056.11,15841.38,270.000,NO
C766,Q_CAP_DIFFBUS_C0201-DIFF BUS_0A,,,C0201_DIFF-BUS,6212.71,15841.38,270.000,NO
C767,Q_CAP_DIFFBUS_C0201-DIFF BUS_0A,,,C0201_DIFF-BUS,6176.71,15841.38,270.000,NO
C768,Q_CAP_DIFFBUS_C0201-DIFF BUS_0A,,,C0201_DIFF-BUS,6333.31,15841.38,270.000,NO
C769,Q_CAP_DIFFBUS_C0201-DIFF BUS_0A,,,C0201_DIFF-BUS,6297.31,15841.38,270.000,NO
C770,Q_CAP_DIFFBUS_C0201-DIFF BUS_0A,,,C0201_DIFF-BUS,6453.91,15841.38,270.000,NO
C771,Q_CAP_DIFFBUS_C0201-DIFF BUS_0A,,,C0201_DIFF-BUS,6417.91,15841.38,270.000,NO
C772,Q_CAP_DIFFBUS_C0201-DIFF BUS_0A,,,C0201_DIFF-BUS,6574.51,15841.38,270.000,NO
C773,Q_CAP_DIFFBUS_C0201-DIFF BUS_0A,,,C0201_DIFF-BUS,6538.51,15841.38,270.000,NO
C806,Q_CAP_DIFFBUS_C0201-DIFF BUS_0A,,,C0201_DIFF-BUS,646.57,633.84,90.000,NO
C807,Q_CAP_DIFFBUS_C0201-DIFF BUS_0A,,,C0201_DIFF-BUS,610.57,633.84,90.000,NO
C808,Q_CAP_DIFFBUS_C0201-DIFF BUS_0A,,,C0201_DIFF-BUS,720.57,693.84,90.000,NO
C809,Q_CAP_DIFFBUS_C0201-DIFF BUS_0A,,,C0201_DIFF-BUS,756.57,693.84,90.000,NO
C810,Q_CAP_DIFFBUS_C0201-DIFF BUS_0A,,,C0201_DIFF-BUS,866.57,633.84,90.000,NO
C811,Q_CAP_DIFFBUS_C0201-DIFF BUS_0A,,,C0201_DIFF-BUS,830.57,633.84,90.000,NO
C812,Q_CAP_DIFFBUS_C0201-DIFF BUS_0A,,,C0201_DIFF-BUS,940.57,693.84,90.000,NO
C813,Q_CAP_DIFFBUS_C0201-DIFF BUS_0A,,,C0201_DIFF-BUS,976.57,693.84,90.000,NO
C814,Q_CAP_DIFFBUS_C0201-DIFF BUS_0A,,,C0201_DIFF-BUS,1086.57,633.84,90.000,NO
C815,Q_CAP_DIFFBUS_C0201-DIFF BUS_0A,,,C0201_DIFF-BUS,1050.57,633.84,90.000,NO
C816,Q_CAP_DIFFBUS_C0201-DIFF BUS_0A,,,C0201_DIFF-BUS,1160.57,693.84,90.000,NO
C817,Q_CAP_DIFFBUS_C0201-DIFF BUS_0A,,,C0201_DIFF-BUS,1196.57,693.84,90.000,NO
C818,Q_CAP_DIFFBUS_C0201-DIFF BUS_0A,,,C0201_DIFF-BUS,1306.57,633.84,90.000,NO
C819,Q_CAP_DIFFBUS_C0201-DIFF BUS_0A,,,C0201_DIFF-BUS,1270.57,633.84,90.000,NO
C820,Q_CAP_DIFFBUS_C0201-DIFF BUS_0A,,,C0201_DIFF-BUS,1380.57,693.84,90.000,NO
C821,Q_CAP_DIFFBUS_C0201-DIFF BUS_0A,,,C0201_DIFF-BUS,1416.57,693.84,90.000,NO
C822,Q_CAP_DIFFBUS_C0201-DIFF BUS_0A,,,C0201_DIFF-BUS,1526.57,633.84,90.000,NO
C823,Q_CAP_DIFFBUS_C0201-DIFF BUS_0A,,,C0201_DIFF-BUS,1490.57,633.84,90.000,NO
C824,Q_CAP_DIFFBUS_C0201-DIFF BUS_0A,,,C0201_DIFF-BUS,1612.61,693.84,90.000,NO
C825,Q_CAP_DIFFBUS_C0201-DIFF BUS_0A,,,C0201_DIFF-BUS,1648.61,693.84,90.000,NO
C826,Q_CAP_DIFFBUS_C0201-DIFF BUS_0A,,,C0201_DIFF-BUS,1758.61,633.84,90.000,NO
C827,Q_CAP_DIFFBUS_C0201-DIFF BUS_0A,,,C0201_DIFF-BUS,1722.61,633.84,90.000,NO
C828,Q_CAP_DIFFBUS_C0201-DIFF BUS_0A,,,C0201_DIFF-BUS,1832.61,693.84,90.000,NO
C829,Q_CAP_DIFFBUS_C0201-DIFF BUS_0A,,,C0201_DIFF-BUS,1868.61,693.84,90.000,NO
C830,Q_CAP_DIFFBUS_C0201-DIFF BUS_0A,,,C0201_DIFF-BUS,1978.61,633.84,90.000,NO
C831,Q_CAP_DIFFBUS_C0201-DIFF BUS_0A,,,C0201_DIFF-BUS,1942.61,633.84,90.000,NO
C832,Q_CAP_DIFFBUS_C0201-DIFF BUS_0A,,,C0201_DIFF-BUS,2053.95,693.84,90.000,NO
C833,Q_CAP_DIFFBUS_C0201-DIFF BUS_0A,,,C0201_DIFF-BUS,2089.95,693.84,90.000,NO
C834,Q_CAP_DIFFBUS_C0201-DIFF BUS_0A,,,C0201_DIFF-BUS,2199.95,633.84,90.000,NO
C835,Q_CAP_DIFFBUS_C0201-DIFF BUS_0A,,,C0201_DIFF-BUS,2163.95,633.84,90.000,NO
C836,Q_CAP_DIFFBUS_C0201-DIFF BUS_0A,,,C0201_DIFF-BUS,2273.95,693.84,90.000,NO
C837,Q_CAP_DIFFBUS_C0201-DIFF BUS_0A,,,C0201_DIFF-BUS,2309.95,693.84,90.000,NO
C838,Q_CAP_DIFFBUS_C0201-DIFF BUS_0A,,,C0201_DIFF-BUS,15390.96,633.41,90.000,NO
C839,Q_CAP_DIFFBUS_C0201-DIFF BUS_0A,,,C0201_DIFF-BUS,15354.96,633.41,90.000,NO
C840,Q_CAP_DIFFBUS_C0201-DIFF BUS_0A,,,C0201_DIFF-BUS,15464.96,693.41,90.000,NO
C841,Q_CAP_DIFFBUS_C0201-DIFF BUS_0A,,,C0201_DIFF-BUS,15500.96,693.41,90.000,NO
C842,Q_CAP_DIFFBUS_C0201-DIFF BUS_0A,,,C0201_DIFF-BUS,15610.96,633.41,90.000,NO
C843,Q_CAP_DIFFBUS_C0201-DIFF BUS_0A,,,C0201_DIFF-BUS,15574.96,633.41,90.000,NO
C844,Q_CAP_DIFFBUS_C0201-DIFF BUS_0A,,,C0201_DIFF-BUS,15684.96,693.41,90.000,NO
C845,Q_CAP_DIFFBUS_C0201-DIFF BUS_0A,,,C0201_DIFF-BUS,15720.96,693.41,90.000,NO
C846,Q_CAP_DIFFBUS_C0201-DIFF BUS_0A,,,C0201_DIFF-BUS,15830.96,633.41,90.000,NO
C847,Q_CAP_DIFFBUS_C0201-DIFF BUS_0A,,,C0201_DIFF-BUS,15794.96,633.41,90.000,NO
C848,Q_CAP_DIFFBUS_C0201-DIFF BUS_0A,,,C0201_DIFF-BUS,15904.96,693.41,90.000,NO
C849,Q_CAP_DIFFBUS_C0201-DIFF BUS_0A,,,C0201_DIFF-BUS,15940.96,693.41,90.000,NO
C850,Q_CAP_DIFFBUS_C0201-DIFF BUS_0A,,,C0201_DIFF-BUS,16050.96,633.41,90.000,NO
C851,Q_CAP_DIFFBUS_C0201-DIFF BUS_0A,,,C0201_DIFF-BUS,16014.96,633.41,90.000,NO
C852,Q_CAP_DIFFBUS_C0201-DIFF BUS_0A,,,C0201_DIFF-BUS,16124.96,693.41,90.000,NO
C853,Q_CAP_DIFFBUS_C0201-DIFF BUS_0A,,,C0201_DIFF-BUS,16160.96,693.41,90.000,NO
C854,Q_CAP_DIFFBUS_C0201-DIFF BUS_0A,,,C0201_DIFF-BUS,16270.96,633.41,90.000,NO
C855,Q_CAP_DIFFBUS_C0201-DIFF BUS_0A,,,C0201_DIFF-BUS,16234.96,633.41,90.000,NO
C856,Q_CAP_DIFFBUS_C0201-DIFF BUS_0A,,,C0201_DIFF-BUS,16357.00,693.41,90.000,NO
C857,Q_CAP_DIFFBUS_C0201-DIFF BUS_0A,,,C0201_DIFF-BUS,16393.00,693.41,90.000,NO
C858,Q_CAP_DIFFBUS_C0201-DIFF BUS_0A,,,C0201_DIFF-BUS,16503.00,633.41,90.000,NO
C859,Q_CAP_DIFFBUS_C0201-DIFF BUS_0A,,,C0201_DIFF-BUS,16467.00,633.41,90.000,NO
C860,Q_CAP_DIFFBUS_C0201-DIFF BUS_0A,,,C0201_DIFF-BUS,16577.00,693.41,90.000,NO
C861,Q_CAP_DIFFBUS_C0201-DIFF BUS_0A,,,C0201_DIFF-BUS,16613.00,693.41,90.000,NO
C862,Q_CAP_DIFFBUS_C0201-DIFF BUS_0A,,,C0201_DIFF-BUS,16723.00,633.41,90.000,NO
C863,Q_CAP_DIFFBUS_C0201-DIFF BUS_0A,,,C0201_DIFF-BUS,16687.00,633.41,90.000,NO
C864,Q_CAP_DIFFBUS_C0201-DIFF BUS_0A,,,C0201_DIFF-BUS,16798.34,693.41,90.000,NO
C865,Q_CAP_DIFFBUS_C0201-DIFF BUS_0A,,,C0201_DIFF-BUS,16834.34,693.41,90.000,NO
C866,Q_CAP_DIFFBUS_C0201-DIFF BUS_0A,,,C0201_DIFF-BUS,16944.34,633.41,90.000,NO
C867,Q_CAP_DIFFBUS_C0201-DIFF BUS_0A,,,C0201_DIFF-BUS,16908.34,633.41,90.000,NO
C868,Q_CAP_DIFFBUS_C0201-DIFF BUS_0A,,,C0201_DIFF-BUS,17054.34,693.41,90.000,NO
C869,Q_CAP_DIFFBUS_C0201-DIFF BUS_0A,,,C0201_DIFF-BUS,17018.34,693.41,90.000,NO
C870,Q_CAP_DIFFBUS_C0201-DIFF BUS_0A,,,C0201_DIFF-BUS,14674.95,16083.36,270.000,NO
C871,Q_CAP_DIFFBUS_C0201-DIFF BUS_0A,,,C0201_DIFF-BUS,14710.95,16083.36,270.000,NO
C872,Q_CAP_DIFFBUS_C0201-DIFF BUS_0A,,,C0201_DIFF-BUS,14795.55,16083.36,270.000,NO
C873,Q_CAP_DIFFBUS_C0201-DIFF BUS_0A,,,C0201_DIFF-BUS,14831.55,16083.36,270.000,NO
C874,Q_CAP_DIFFBUS_C0201-DIFF BUS_0A,,,C0201_DIFF-BUS,14916.15,16083.36,270.000,NO
C875,Q_CAP_DIFFBUS_C0201-DIFF BUS_0A,,,C0201_DIFF-BUS,14952.15,16083.36,270.000,NO
C876,Q_CAP_DIFFBUS_C0201-DIFF BUS_0A,,,C0201_DIFF-BUS,15036.75,16083.36,270.000,NO
C877,Q_CAP_DIFFBUS_C0201-DIFF BUS_0A,,,C0201_DIFF-BUS,15072.75,16083.36,270.000,NO
C878,Q_CAP_DIFFBUS_C0201-DIFF BUS_0A,,,C0201_DIFF-BUS,15157.35,16083.36,270.000,NO
C879,Q_CAP_DIFFBUS_C0201-DIFF BUS_0A,,,C0201_DIFF-BUS,15193.35,16083.36,270.000,NO
C880,Q_CAP_DIFFBUS_C0201-DIFF BUS_0A,,,C0201_DIFF-BUS,15277.95,16083.36,270.000,NO
C881,Q_CAP_DIFFBUS_C0201-DIFF BUS_0A,,,C0201_DIFF-BUS,15313.95,16083.36,270.000,NO
C882,Q_CAP_DIFFBUS_C0201-DIFF BUS_0A,,,C0201_DIFF-BUS,15398.55,16083.36,270.000,NO
C883,Q_CAP_DIFFBUS_C0201-DIFF BUS_0A,,,C0201_DIFF-BUS,15434.55,16083.36,270.000,NO
C884,Q_CAP_DIFFBUS_C0201-DIFF BUS_0A,,,C0201_DIFF-BUS,15519.15,16083.36,270.000,NO
C885,Q_CAP_DIFFBUS_C0201-DIFF BUS_0A,,,C0201_DIFF-BUS,15555.15,16083.36,270.000,NO
C886,Q_CAP_DIFFBUS_C0201-DIFF BUS_0A,,,C0201_DIFF-BUS,15639.75,16083.36,270.000,NO
C887,Q_CAP_DIFFBUS_C0201-DIFF BUS_0A,,,C0201_DIFF-BUS,15675.75,16083.36,270.000,NO
C888,Q_CAP_DIFFBUS_C0201-DIFF BUS_0A,,,C0201_DIFF-BUS,15760.35,16083.36,270.000,NO
C889,Q_CAP_DIFFBUS_C0201-DIFF BUS_0A,,,C0201_DIFF-BUS,15796.35,16083.36,270.000,NO
C890,Q_CAP_DIFFBUS_C0201-DIFF BUS_0A,,,C0201_DIFF-BUS,15880.95,16083.36,270.000,NO
C891,Q_CAP_DIFFBUS_C0201-DIFF BUS_0A,,,C0201_DIFF-BUS,15916.95,16083.36,270.000,NO
C892,Q_CAP_DIFFBUS_C0201-DIFF BUS_0A,,,C0201_DIFF-BUS,16001.55,16083.36,270.000,NO
C893,Q_CAP_DIFFBUS_C0201-DIFF BUS_0A,,,C0201_DIFF-BUS,16037.55,16083.36,270.000,NO
C894,Q_CAP_DIFFBUS_C0201-DIFF BUS_0A,,,C0201_DIFF-BUS,16122.15,16083.36,270.000,NO
C895,Q_CAP_DIFFBUS_C0201-DIFF BUS_0A,,,C0201_DIFF-BUS,16158.15,16083.36,270.000,NO
C896,Q_CAP_DIFFBUS_C0201-DIFF BUS_0A,,,C0201_DIFF-BUS,16242.75,16083.36,270.000,NO
C897,Q_CAP_DIFFBUS_C0201-DIFF BUS_0A,,,C0201_DIFF-BUS,16278.75,16083.36,270.000,NO
C898,Q_CAP_DIFFBUS_C0201-DIFF BUS_0A,,,C0201_DIFF-BUS,16363.35,16083.36,270.000,NO
C899,Q_CAP_DIFFBUS_C0201-DIFF BUS_0A,,,C0201_DIFF-BUS,16399.35,16083.36,270.000,NO
C900,Q_CAP_DIFFBUS_C0201-DIFF BUS_0A,,,C0201_DIFF-BUS,16519.95,16083.36,270.000,NO
C901,Q_CAP_DIFFBUS_C0201-DIFF BUS_0A,,,C0201_DIFF-BUS,16483.95,16083.36,270.000,NO
C902,Q_CAP_DIFFBUS_C0201-DIFF BUS_0A,,,C0201_DIFF-BUS,12019.72,16083.36,270.000,NO
C903,Q_CAP_DIFFBUS_C0201-DIFF BUS_0A,,,C0201_DIFF-BUS,12055.72,16083.36,270.000,NO
C904,Q_CAP_DIFFBUS_C0201-DIFF BUS_0A,,,C0201_DIFF-BUS,12140.32,16083.36,270.000,NO
C905,Q_CAP_DIFFBUS_C0201-DIFF BUS_0A,,,C0201_DIFF-BUS,12176.32,16083.36,270.000,NO
C906,Q_CAP_DIFFBUS_C0201-DIFF BUS_0A,,,C0201_DIFF-BUS,12260.92,16083.36,270.000,NO
C907,Q_CAP_DIFFBUS_C0201-DIFF BUS_0A,,,C0201_DIFF-BUS,12296.92,16083.36,270.000,NO
C908,Q_CAP_DIFFBUS_C0201-DIFF BUS_0A,,,C0201_DIFF-BUS,12381.52,16083.36,270.000,NO
C909,Q_CAP_DIFFBUS_C0201-DIFF BUS_0A,,,C0201_DIFF-BUS,12417.52,16083.36,270.000,NO
C910,Q_CAP_DIFFBUS_C0201-DIFF BUS_0A,,,C0201_DIFF-BUS,12502.12,16083.36,270.000,NO
C911,Q_CAP_DIFFBUS_C0201-DIFF BUS_0A,,,C0201_DIFF-BUS,12538.12,16083.36,270.000,NO
C912,Q_CAP_DIFFBUS_C0201-DIFF BUS_0A,,,C0201_DIFF-BUS,12622.72,16083.36,270.000,NO
C913,Q_CAP_DIFFBUS_C0201-DIFF BUS_0A,,,C0201_DIFF-BUS,12658.72,16083.36,270.000,NO
C914,Q_CAP_DIFFBUS_C0201-DIFF BUS_0A,,,C0201_DIFF-BUS,12743.32,16083.36,270.000,NO
C915,Q_CAP_DIFFBUS_C0201-DIFF BUS_0A,,,C0201_DIFF-BUS,12779.32,16083.36,270.000,NO
C916,Q_CAP_DIFFBUS_C0201-DIFF BUS_0A,,,C0201_DIFF-BUS,12863.92,16083.36,270.000,NO
C917,Q_CAP_DIFFBUS_C0201-DIFF BUS_0A,,,C0201_DIFF-BUS,12899.92,16083.36,270.000,NO
C918,Q_CAP_DIFFBUS_C0201-DIFF BUS_0A,,,C0201_DIFF-BUS,12984.52,16083.36,270.000,NO
C919,Q_CAP_DIFFBUS_C0201-DIFF BUS_0A,,,C0201_DIFF-BUS,13020.52,16083.36,270.000,NO
C920,Q_CAP_DIFFBUS_C0201-DIFF BUS_0A,,,C0201_DIFF-BUS,13105.12,16083.36,270.000,NO
C921,Q_CAP_DIFFBUS_C0201-DIFF BUS_0A,,,C0201_DIFF-BUS,13141.12,16083.36,270.000,NO
C922,Q_CAP_DIFFBUS_C0201-DIFF BUS_0A,,,C0201_DIFF-BUS,13225.72,16083.36,270.000,NO
C923,Q_CAP_DIFFBUS_C0201-DIFF BUS_0A,,,C0201_DIFF-BUS,13261.72,16083.36,270.000,NO
C924,Q_CAP_DIFFBUS_C0201-DIFF BUS_0A,,,C0201_DIFF-BUS,13346.32,16083.36,270.000,NO
C925,Q_CAP_DIFFBUS_C0201-DIFF BUS_0A,,,C0201_DIFF-BUS,13382.32,16083.36,270.000,NO
C926,Q_CAP_DIFFBUS_C0201-DIFF BUS_0A,,,C0201_DIFF-BUS,13466.92,16083.36,270.000,NO
C927,Q_CAP_DIFFBUS_C0201-DIFF BUS_0A,,,C0201_DIFF-BUS,13502.92,16083.36,270.000,NO
C928,Q_CAP_DIFFBUS_C0201-DIFF BUS_0A,,,C0201_DIFF-BUS,13587.52,16083.36,270.000,NO
C929,Q_CAP_DIFFBUS_C0201-DIFF BUS_0A,,,C0201_DIFF-BUS,13623.52,16083.36,270.000,NO
C930,Q_CAP_DIFFBUS_C0201-DIFF BUS_0A,,,C0201_DIFF-BUS,13708.12,16083.36,270.000,NO
C931,Q_CAP_DIFFBUS_C0201-DIFF BUS_0A,,,C0201_DIFF-BUS,13744.12,16083.36,270.000,NO
C932,Q_CAP_DIFFBUS_C0201-DIFF BUS_0A,,,C0201_DIFF-BUS,13828.72,16083.36,270.000,NO
C933,Q_CAP_DIFFBUS_C0201-DIFF BUS_0A,,,C0201_DIFF-BUS,13864.72,16083.36,270.000,NO
C934,Q_CAP_DIFFBUS_C0201-DIFF BUS_0A,,,C0201_DIFF-BUS,14621.95,15841.38,270.000,NO
C935,Q_CAP_DIFFBUS_C0201-DIFF BUS_0A,,,C0201_DIFF-BUS,14657.95,15841.38,270.000,NO
C936,Q_CAP_DIFFBUS_C0201-DIFF BUS_0A,,,C0201_DIFF-BUS,14778.55,15841.38,270.000,NO
C937,Q_CAP_DIFFBUS_C0201-DIFF BUS_0A,,,C0201_DIFF-BUS,14742.55,15841.38,270.000,NO
C938,Q_CAP_DIFFBUS_C0201-DIFF BUS_0A,,,C0201_DIFF-BUS,14899.15,15841.38,270.000,NO
C939,Q_CAP_DIFFBUS_C0201-DIFF BUS_0A,,,C0201_DIFF-BUS,14863.15,15841.38,270.000,NO
C940,Q_CAP_DIFFBUS_C0201-DIFF BUS_0A,,,C0201_DIFF-BUS,15019.75,15841.38,270.000,NO
C941,Q_CAP_DIFFBUS_C0201-DIFF BUS_0A,,,C0201_DIFF-BUS,14983.75,15841.38,270.000,NO
C942,Q_CAP_DIFFBUS_C0201-DIFF BUS_0A,,,C0201_DIFF-BUS,15140.35,15841.38,270.000,NO
C943,Q_CAP_DIFFBUS_C0201-DIFF BUS_0A,,,C0201_DIFF-BUS,15104.35,15841.38,270.000,NO
C944,Q_CAP_DIFFBUS_C0201-DIFF BUS_0A,,,C0201_DIFF-BUS,15260.95,15841.38,270.000,NO
C945,Q_CAP_DIFFBUS_C0201-DIFF BUS_0A,,,C0201_DIFF-BUS,15224.95,15841.38,270.000,NO
C946,Q_CAP_DIFFBUS_C0201-DIFF BUS_0A,,,C0201_DIFF-BUS,15381.55,15841.38,270.000,NO
C947,Q_CAP_DIFFBUS_C0201-DIFF BUS_0A,,,C0201_DIFF-BUS,15345.55,15841.38,270.000,NO
C948,Q_CAP_DIFFBUS_C0201-DIFF BUS_0A,,,C0201_DIFF-BUS,15502.15,15841.38,270.000,NO
C949,Q_CAP_DIFFBUS_C0201-DIFF BUS_0A,,,C0201_DIFF-BUS,15466.15,15841.38,270.000,NO
C950,Q_CAP_DIFFBUS_C0201-DIFF BUS_0A,,,C0201_DIFF-BUS,15622.75,15841.38,270.000,NO
C951,Q_CAP_DIFFBUS_C0201-DIFF BUS_0A,,,C0201_DIFF-BUS,15586.75,15841.38,270.000,NO
C952,Q_CAP_DIFFBUS_C0201-DIFF BUS_0A,,,C0201_DIFF-BUS,15743.35,15841.38,270.000,NO
C953,Q_CAP_DIFFBUS_C0201-DIFF BUS_0A,,,C0201_DIFF-BUS,15707.35,15841.38,270.000,NO
C954,Q_CAP_DIFFBUS_C0201-DIFF BUS_0A,,,C0201_DIFF-BUS,15863.95,15841.38,270.000,NO
C955,Q_CAP_DIFFBUS_C0201-DIFF BUS_0A,,,C0201_DIFF-BUS,15827.95,15841.38,270.000,NO
C956,Q_CAP_DIFFBUS_C0201-DIFF BUS_0A,,,C0201_DIFF-BUS,15984.55,15841.38,270.000,NO
C957,Q_CAP_DIFFBUS_C0201-DIFF BUS_0A,,,C0201_DIFF-BUS,15948.55,15841.38,270.000,NO
C958,Q_CAP_DIFFBUS_C0201-DIFF BUS_0A,,,C0201_DIFF-BUS,16105.15,15841.38,270.000,NO
C959,Q_CAP_DIFFBUS_C0201-DIFF BUS_0A,,,C0201_DIFF-BUS,16069.15,15841.38,270.000,NO
C960,Q_CAP_DIFFBUS_C0201-DIFF BUS_0A,,,C0201_DIFF-BUS,16225.75,15841.38,270.000,NO
C961,Q_CAP_DIFFBUS_C0201-DIFF BUS_0A,,,C0201_DIFF-BUS,16189.75,15841.38,270.000,NO
C962,Q_CAP_DIFFBUS_C0201-DIFF BUS_0A,,,C0201_DIFF-BUS,16346.35,15841.38,270.000,NO
C963,Q_CAP_DIFFBUS_C0201-DIFF BUS_0A,,,C0201_DIFF-BUS,16310.35,15841.38,270.000,NO
C964,Q_CAP_DIFFBUS_C0201-DIFF BUS_0A,,,C0201_DIFF-BUS,16466.95,15841.38,270.000,NO
C965,Q_CAP_DIFFBUS_C0201-DIFF BUS_0A,,,C0201_DIFF-BUS,16430.95,15841.38,270.000,NO
C966,"Q_CAP_C0402-10UF,6.3V,20%,X6S,B",10UF,20%,C0402,13947.32,10186.09,90.000,NO
C967,"Q_CAP_C0402-10UF,6.3V,20%,X6S,B",10UF,20%,C0402,13986.12,9815.76,270.000,NO
C968,"Q_CAP_C0402-10UF,6.3V,20%,X6S,B",10UF,20%,C0402,14350.45,10186.09,90.000,NO
C969,"Q_CAP_C0402-10UF,6.3V,20%,X6S,B",10UF,20%,C0402,14350.45,9815.76,270.000,NO
C970,"Q_CAP_C0402-10UF,6.3V,20%,X6S,B",10UF,20%,C0402,13985.32,10186.09,90.000,NO
C971,"Q_CAP_C0402-10UF,6.3V,20%,X6S,B",10UF,20%,C0402,13908.12,9752.56,90.000,NO
C972,"Q_CAP_C0402-10UF,6.3V,20%,X6S,B",10UF,20%,C0402,14388.45,10186.09,90.000,NO
C973,"Q_CAP_C0402-10UF,6.3V,20%,X6S,B",10UF,20%,C0402,14388.45,9815.76,270.000,NO
C974,"Q_CAP_C0402-10UF,6.3V,20%,X6S,B",10UF,20%,C0402,13946.91,10104.49,270.000,NO
C975,"Q_CAP_C0402-10UF,6.3V,20%,X6S,B",10UF,20%,C0402,13948.12,9752.56,90.000,NO
C976,"Q_CAP_C0402-10UF,6.3V,20%,X6S,B",10UF,20%,C0402,14428.45,10186.09,90.000,NO
C977,"Q_CAP_C0402-10UF,6.3V,20%,X6S,B",10UF,20%,C0402,14428.45,9815.76,270.000,NO
C978,"Q_CAP_C0402-10UF,6.3V,20%,X6S,B",10UF,20%,C0402,13984.91,10104.49,270.000,NO
C979,"Q_CAP_C0402-10UF,6.3V,20%,X6S,B",10UF,20%,C0402,13986.12,9752.56,90.000,NO
C980,"Q_CAP_C0402-10UF,6.3V,20%,X6S,B",10UF,20%,C0402,14466.45,10186.09,90.000,NO
C981,"Q_CAP_C0402-10UF,6.3V,20%,X6S,B",10UF,20%,C0402,14466.45,9815.76,270.000,NO
C982,"Q_CAP_C0402-10UF,6.3V,20%,X6S,B",10UF,20%,C0402,13868.91,10041.49,90.000,NO
C983,"Q_CAP_C0402-10UF,6.3V,20%,X6S,B",10UF,20%,C0402,13907.67,9670.63,270.000,NO
C984,"Q_CAP_C0402-10UF,6.3V,20%,X6S,B",10UF,20%,C0402,14350.45,10104.49,270.000,NO
C985,"Q_CAP_C0402-10UF,6.3V,20%,X6S,B",10UF,20%,C0402,14350.45,9752.56,90.000,NO
C986,"Q_CAP_C0402-10UF,6.3V,20%,X6S,B",10UF,20%,C0402,13906.91,10041.49,90.000,NO
C987,"Q_CAP_C0402-10UF,6.3V,20%,X6S,B",10UF,20%,C0402,13947.67,9670.63,270.000,NO
C988,"Q_CAP_C0402-10UF,6.3V,20%,X6S,B",10UF,20%,C0402,14388.45,10104.49,270.000,NO
C989,"Q_CAP_C0402-10UF,6.3V,20%,X6S,B",10UF,20%,C0402,14388.45,9752.56,90.000,NO
C990,"Q_CAP_C0402-10UF,6.3V,20%,X6S,B",10UF,20%,C0402,13946.91,10041.49,90.000,NO
C991,"Q_CAP_C0402-10UF,6.3V,20%,X6S,B",10UF,20%,C0402,13985.67,9670.63,270.000,NO
C992,"Q_CAP_C0402-10UF,6.3V,20%,X6S,B",10UF,20%,C0402,14428.45,10104.49,270.000,NO
C993,"Q_CAP_C0402-10UF,6.3V,20%,X6S,B",10UF,20%,C0402,14428.45,9752.56,90.000,NO
C994,"Q_CAP_C0402-10UF,6.3V,20%,X6S,B",10UF,20%,C0402,13984.91,10041.49,90.000,NO
C995,"Q_CAP_C0402-10UF,6.3V,20%,X6S,B",10UF,20%,C0402,13869.67,9607.55,90.000,NO
C996,"Q_CAP_C0402-10UF,6.3V,20%,X6S,B",10UF,20%,C0402,14466.45,10104.49,270.000,NO
C997,"Q_CAP_C0402-10UF,6.3V,20%,X6S,B",10UF,20%,C0402,14350.45,9670.63,270.000,NO
C998,"Q_CAP_C0402-10UF,6.3V,20%,X6S,B",10UF,20%,C0402,13869.41,9958.91,270.000,NO
C999,"Q_CAP_C0402-10UF,6.3V,20%,X6S,B",10UF,20%,C0402,13907.67,9607.55,90.000,NO
C1000,"Q_CAP_C0402-10UF,6.3V,20%,X6S,B",10UF,20%,C0402,14350.45,10041.49,90.000,NO
C1001,"Q_CAP_C0402-10UF,6.3V,20%,X6S,B",10UF,20%,C0402,14388.45,9670.63,270.000,NO
C1002,"Q_CAP_C0402-10UF,6.3V,20%,X6S,B",10UF,20%,C0402,13907.41,9958.91,270.000,NO
C1003,"Q_CAP_C0402-10UF,6.3V,20%,X6S,B",10UF,20%,C0402,13947.67,9607.55,90.000,NO
C1004,"Q_CAP_C0402-10UF,6.3V,20%,X6S,B",10UF,20%,C0402,14388.45,10041.49,90.000,NO
C1005,"Q_CAP_C0402-10UF,6.3V,20%,X6S,B",10UF,20%,C0402,14428.45,9670.63,270.000,NO
C1006,"Q_CAP_C0402-22UF,4V,20%,X6S,CHA",22UF,20%,C0402_H32,13947.41,9958.91,270.000,NO
C1007,"Q_CAP_C0402-22UF,4V,20%,X6S,CHA",22UF,20%,C0402_H32,13985.67,9607.55,90.000,NO
C1008,"Q_CAP_C0402-22UF,4V,20%,X6S,CHA",22UF,20%,C0402_H32,14428.45,10041.49,90.000,NO
C1009,"Q_CAP_C0402-22UF,4V,20%,X6S,CHA",22UF,20%,C0402_H32,14350.45,9607.55,90.000,NO
C1010,"Q_CAP_C0402-22UF,4V,20%,X6S,CHA",22UF,20%,C0402_H32,13985.41,9958.91,270.000,NO
C1011,"Q_CAP_C0402-22UF,4V,20%,X6S,CHA",22UF,20%,C0402_H32,13869.36,9526.64,270.000,NO
C1012,"Q_CAP_C0402-22UF,4V,20%,X6S,CHA",22UF,20%,C0402_H32,14466.45,10041.49,90.000,NO
C1013,"Q_CAP_C0402-22UF,4V,20%,X6S,CHA",22UF,20%,C0402_H32,14388.45,9607.55,90.000,NO
C1014,"Q_CAP_C0402-22UF,4V,20%,X6S,CHA",22UF,20%,C0402_H32,13869.41,9896.67,90.000,NO
C1015,"Q_CAP_C0402-22UF,4V,20%,X6S,CHA",22UF,20%,C0402_H32,13907.36,9526.64,270.000,NO
C1016,"Q_CAP_C0402-22UF,4V,20%,X6S,CHA",22UF,20%,C0402_H32,14350.45,9958.91,270.000,NO
C1017,"Q_CAP_C0402-22UF,4V,20%,X6S,CHA",22UF,20%,C0402_H32,14428.45,9607.55,90.000,NO
C1018,"Q_CAP_C0402-22UF,4V,20%,X6S,CHA",22UF,20%,C0402_H32,13907.41,9896.67,90.000,NO
C1019,"Q_CAP_C0402-22UF,4V,20%,X6S,CHA",22UF,20%,C0402_H32,13947.36,9526.64,270.000,NO
C1020,"Q_CAP_C0402-22UF,4V,20%,X6S,CHA",22UF,20%,C0402_H32,14388.45,9958.91,270.000,NO
C1021,"Q_CAP_C0402-22UF,4V,20%,X6S,CHA",22UF,20%,C0402_H32,14466.45,9607.55,90.000,NO
C1022,"Q_CAP_C0402-22UF,4V,20%,X6S,CHA",22UF,20%,C0402_H32,13947.41,9896.67,90.000,NO
C1023,"Q_CAP_C0402-22UF,4V,20%,X6S,CHA",22UF,20%,C0402_H32,13985.36,9526.64,270.000,NO
C1024,"Q_CAP_C0402-22UF,4V,20%,X6S,CHA",22UF,20%,C0402_H32,14428.45,9958.91,270.000,NO
C1025,"Q_CAP_C0402-22UF,4V,20%,X6S,CHA",22UF,20%,C0402_H32,14350.45,9526.64,270.000,NO
C1026,"Q_CAP_C0402-22UF,4V,20%,X6S,CHA",22UF,20%,C0402_H32,13985.41,9896.67,90.000,NO
C1027,"Q_CAP_C0402-22UF,4V,20%,X6S,CHA",22UF,20%,C0402_H32,13907.36,9459.72,90.000,NO
C1028,"Q_CAP_C0402-22UF,4V,20%,X6S,CHA",22UF,20%,C0402_H32,14466.45,9958.91,270.000,NO
C1029,"Q_CAP_C0402-22UF,4V,20%,X6S,CHA",22UF,20%,C0402_H32,14388.45,9526.64,270.000,NO
C1030,"Q_CAP_C0402-22UF,4V,20%,X6S,CHA",22UF,20%,C0402_H32,13870.12,9815.76,270.000,NO
C1031,"Q_CAP_C0402-22UF,4V,20%,X6S,CHA",22UF,20%,C0402_H32,13947.36,9459.72,90.000,NO
C1032,"Q_CAP_C0402-22UF,4V,20%,X6S,CHA",22UF,20%,C0402_H32,14350.45,9896.67,90.000,NO
C1033,"Q_CAP_C0402-22UF,4V,20%,X6S,CHA",22UF,20%,C0402_H32,14428.45,9526.64,270.000,NO
C1034,"Q_CAP_C0402-22UF,4V,20%,X6S,CHA",22UF,20%,C0402_H32,13908.12,9815.76,270.000,NO
C1035,"Q_CAP_C0402-22UF,4V,20%,X6S,CHA",22UF,20%,C0402_H32,13985.36,9459.72,90.000,NO
C1036,"Q_CAP_C0402-22UF,4V,20%,X6S,CHA",22UF,20%,C0402_H32,14388.45,9896.67,90.000,NO
C1037,"Q_CAP_C0402-22UF,4V,20%,X6S,CHA",22UF,20%,C0402_H32,14466.45,9526.64,270.000,NO
C1038,"Q_CAP_C0402-22UF,4V,20%,X6S,CHA",22UF,20%,C0402_H32,13948.12,9815.76,270.000,NO
C1039,"Q_CAP_C0402-22UF,4V,20%,X6S,CHA",22UF,20%,C0402_H32,13947.57,9376.47,270.000,NO
C1040,"Q_CAP_C0402-22UF,4V,20%,X6S,CHA",22UF,20%,C0402_H32,14428.45,9896.67,90.000,NO
C1041,"Q_CAP_C0402-22UF,4V,20%,X6S,CHA",22UF,20%,C0402_H32,14350.45,9459.72,90.000,NO
C1042,"Q_CAP_C0402-100NF,50V,10%,X7R,A",100NF,10%,C0402,17560.25,14759.51,0.000,NO
C1043,"Q_CAP_C0402-22UF,4V,20%,X6S,CHA",22UF,20%,C0402_H32,13985.57,9376.47,270.000,NO
C1044,"Q_CAP_C0402-22UF,4V,20%,X6S,CHA",22UF,20%,C0402_H32,14466.45,9896.67,90.000,NO
C1045,"Q_CAP_C0402-22UF,4V,20%,X6S,CHA",22UF,20%,C0402_H32,14388.45,9459.72,90.000,NO
C1096,"Q_CAP_C0201-0.1UF,6.3V,10%,X6SA",0.1UF,10%,C0201,4923.34,983.73,180.000,YES
C1097,"Q_CAP_C0201-0.1UF,6.3V,10%,X6SA",0.1UF,10%,C0201,4923.34,1014.73,180.000,YES
C1098,Q_CAP_DIFFBUS_C0201-DIFF BUS_0A,,,C0201_DIFF-BUS,7107.42,1771.87,180.000,NO
C1099,Q_CAP_DIFFBUS_C0201-DIFF BUS_0A,,,C0201_DIFF-BUS,7107.42,1735.87,180.000,NO
C1100,Q_CAP_DIFFBUS_C0201-DIFF BUS_0A,,,C0201_DIFF-BUS,7107.42,1891.87,180.000,NO
C1101,Q_CAP_DIFFBUS_C0201-DIFF BUS_0A,,,C0201_DIFF-BUS,7107.42,1855.87,180.000,NO
C1102,Q_CAP_DIFFBUS_C0201-DIFF BUS_0A,,,C0201_DIFF-BUS,7107.42,2006.87,180.000,NO
C1103,Q_CAP_DIFFBUS_C0201-DIFF BUS_0A,,,C0201_DIFF-BUS,7107.42,1970.87,180.000,NO
C1104,Q_CAP_DIFFBUS_C0201-DIFF BUS_0A,,,C0201_DIFF-BUS,7107.42,2125.21,180.000,NO
C1105,Q_CAP_DIFFBUS_C0201-DIFF BUS_0A,,,C0201_DIFF-BUS,7107.42,2089.21,180.000,NO
C1113,"Q_CAP_C0402-0.01UF,50V,10%,X7RA",0.01UF,10%,C0402,7076.99,4369.11,270.000,YES
C1118,"Q_CAP_C0402-0.01UF,50V,10%,X7RA",0.01UF,10%,C0402,7108.49,4369.11,270.000,YES
C1122,"Q_CAP_0402-0.1UF,25V,10%,X7R,CA",0.1UF,10%,C0402,7155.73,4447.85,0.000,YES
C1124,"Q_CAP_C0402-0.01UF,50V,10%,X7RA",0.01UF,10%,C0402,7234.47,4148.64,90.000,YES
C1127,"Q_CAP_C0402-0.01UF,50V,10%,X7RA",0.01UF,10%,C0402,7155.73,4510.84,0.000,YES
C1133,"Q_CAP_C0402-0.01UF,50V,10%,X7RA",0.01UF,10%,C0402,7155.73,4542.34,0.000,YES
C1138,"Q_CAP_C0402-0.01UF,50V,10%,X7RA",0.01UF,10%,C0402,7155.73,4384.86,0.000,YES
C1142,"Q_CAP_C0402-0.01UF,50V,10%,X7RA",0.01UF,10%,C0402,7155.73,4416.36,0.000,YES
C1146,"Q_CAP_C0402-0.01UF,50V,10%,X7RA",0.01UF,10%,C0402,7155.73,4479.35,0.000,YES
C1150,"Q_CAP_0402-0.1UF,25V,10%,X7R,CA",0.1UF,10%,C0402,6966.76,4479.35,0.000,YES
C1152,"Q_CAP_C0402-0.01UF,50V,10%,X7RA",0.01UF,10%,C0402,7092.74,4416.36,180.000,YES
C1154,"Q_CAP_C0402-0.01UF,50V,10%,X7RA",0.01UF,10%,C0402,7092.74,4510.84,180.000,YES
C1170,"Q_CAP_C0805-10UF,16V,10%,X6S,CA",10UF,10%,C0805_H57,17566.45,14893.71,0.000,NO
C1171,"Q_CAP_C0805-10UF,16V,10%,EMPTYA",NA,10%,C0805_H57,17566.45,14821.71,0.000,NO
C1172,"Q_CAP_C0402-100NF,50V,10%,X7R,A",100NF,10%,C0402,16434.55,1804.60,180.000,NO
C1173,"Q_CAP_0402-0.1UF,25V,10%,X7R,CA",0.1UF,10%,C0402,18047.90,1565.57,0.000,NO
C1175,"Q_CAP_0402-0.1UF,25V,10%,X7R,CA",0.1UF,10%,C0402,18373.35,1827.12,0.000,NO
C1177,"Q_CAP_C0402-1UF,25V,10%,X6S,CHA",1UF,10%,C0402,11952.78,1375.49,270.000,NO
C1178,"Q_CAP_C0603-22UF,4V,20%,X6S,CHA",22UF,20%,C0603,11898.38,2087.33,180.000,YES
C1181,"Q_CAP_C0603-22UF,4V,20%,X6S,CHA",22UF,20%,C0603,13078.64,2302.09,270.000,YES
C1182,"Q_CAP_C0603-22UF,4V,20%,X6S,CHA",22UF,20%,C0603,11710.40,2058.42,0.000,YES
C1183,"Q_CAP_C0402-2.2UF,10V,10%,X6S,A",2.2UF,10%,C0402,13225.22,1914.70,90.000,YES
C1184,"Q_CAP_C0603-22UF,6.3V,20%,X6S,A",22UF,20%,C0603,12530.01,2560.98,0.000,YES
C1185,"Q_CAP_C0603-22UF,4V,20%,X6S,CHA",22UF,20%,C0603,11713.62,1905.88,0.000,YES
C1186,"Q_CAP_C0603-22UF,4V,20%,X6S,CHA",22UF,20%,C0603,13132.64,2302.09,270.000,YES
C1187,"Q_CAP_C0603-22UF,4V,20%,X6S,CHA",22UF,20%,C0603,11710.40,1977.42,0.000,YES
C1189,"Q_CAP_C0402-2.2UF,10V,10%,X6S,A",2.2UF,10%,C0402,13173.10,1930.02,0.000,YES
C1191,"Q_CAP_C0603-22UF,6.3V,20%,X6S,A",22UF,20%,C0603,12821.45,2631.51,270.000,YES
C1192,"Q_CAP_C0603-22UF,4V,20%,X6S,CHA",22UF,20%,C0603,11898.38,2141.33,180.000,YES
C1197,"Q_CAP_C0603-22UF,4V,20%,X6S,CHA",22UF,20%,C0603,13186.27,2301.79,270.000,YES
C1198,"Q_CAP_C0603-22UF,4V,20%,X6S,CHA",22UF,20%,C0603,11903.60,1855.82,180.000,YES
C1200,"Q_CAP_C0402-2.2UF,10V,10%,X6S,A",2.2UF,10%,C0402,13356.97,1910.09,180.000,YES
C1201,"Q_CAP_C0603-22UF,6.3V,20%,X6S,A",22UF,20%,C0603,12769.01,2631.25,270.000,YES
C1202,"Q_CAP_C0603-22UF,4V,20%,X6S,CHA",22UF,20%,C0603,13238.96,2302.62,270.000,YES
C1203,"Q_CAP_C0402-10UF,6.3V,20%,X6S,A",10UF,20%,C0402,13235.20,1712.77,0.000,YES
C1204,"Q_CAP_C0402-2.2UF,10V,10%,X6S,A",2.2UF,10%,C0402,13234.50,1674.72,0.000,YES
C1205,"Q_CAP_C0402-10UF,6.3V,20%,X6S,A",10UF,20%,C0402,13356.09,1830.68,180.000,YES
C1206,"Q_CAP_C0402-10UF,6.3V,20%,X6S,A",10UF,20%,C0402,13141.22,1770.16,0.000,YES
C1207,"Q_CAP_C0402-10UF,6.3V,20%,X6S,A",10UF,20%,C0402,13174.35,2021.41,0.000,YES
C1209,"Q_CAP_0402-100PF,50V,5%,NPO,CHA",100PF,5%,C0402,12287.04,1075.62,270.000,YES
C1210,"Q_CAP_C0402-10UF,6.3V,20%,X6S,A",10UF,20%,C0402,13225.01,1845.99,270.000,YES
C1211,"Q_CAP_0402-100PF,50V,5%,NPO,CHA",100PF,5%,C0402,6902.20,5128.62,90.000,NO
C1213,"Q_CAP_C0805-22UF,16V,20%,X6S,CB",22UF,20%,C0805_H57,17328.26,719.30,180.000,NO
C1214,"Q_CAP_C0402-2.2UF,10V,10%,X6S,A",2.2UF,10%,C0402,13224.77,1776.76,90.000,YES
C1226,"Q_CAP_C0402-0.22UF,25V,10%,X7RA",0.22UF,10%,C0402,6549.27,5266.80,90.000,NO
C1227,"Q_CAP_C0402-100NF,50V,10%,X7R,A",100NF,10%,C0402,17429.35,14518.41,0.000,NO
C1228,"Q_CAP_C0402-10UF,6.3V,20%,X6S,A",10UF,20%,C0402,13357.35,1870.59,180.000,YES
C1231,"Q_CAP_C0402-10UF,6.3V,20%,X6S,A",10UF,20%,C0402,11901.58,2203.62,180.000,YES
C1232,"Q_CAP_C0805-22UF,16V,20%,X6S,CB",22UF,20%,C0805_H57,17328.26,719.30,0.000,YES
C1233,"Q_CAP_0402-0.1UF,25V,10%,X7R,CA",0.1UF,10%,C0402,17337.94,616.39,180.000,NO
C1234,"Q_CAP_0402-0.1UF,25V,10%,X7R,CA",0.1UF,10%,C0402,17337.94,616.39,0.000,YES
C1235,"Q_CAP_0402-0.1UF,25V,10%,X7R,CA",0.1UF,10%,C0402,17338.42,657.49,0.000,YES
C1236,"Q_CAP_0402-0.1UF,25V,10%,X7R,CA",0.1UF,10%,C0402,17338.42,657.49,180.000,NO
C1237,"Q_CAP_0402-0.1UF,25V,10%,X7R,CA",0.1UF,10%,C0402,17147.63,516.54,180.000,YES
C1238,"Q_CAP_0402-0.1UF,25V,10%,X7R,CA",0.1UF,10%,C0402,17147.63,476.54,180.000,YES
C1239,"Q_CAP_0402-0.1UF,25V,10%,X7R,CA",0.1UF,10%,C0402,17147.63,436.54,180.000,YES
C1240,"Q_CAP_0402-0.1UF,25V,10%,X7R,CA",0.1UF,10%,C0402,17147.63,396.54,180.000,YES
C1242,"Q_CAP_C0402-2.2UF,10V,10%,X6S,A",2.2UF,10%,C0402,13280.20,1777.21,270.000,YES
C1243,"Q_CAP_C0805-47UF,6.3V,20%,X6S,A",47UF,20%,C0805_H57,12633.33,2636.06,270.000,YES
C1244,"Q_CAP_C0805-47UF,4V,20%,X6S,CHA",47UF,20%,C0805_H57,11895.73,2004.86,180.000,YES
C1245,"Q_CAP_C0805-47UF,6.3V,20%,X6S,A",47UF,20%,C0805_H57,12704.04,2635.32,270.000,YES
C1246,"Q_CAP_C0805-47UF,4V,20%,X6S,CHA",47UF,20%,C0805_H57,11709.44,1826.85,0.000,YES
C1247,"Q_CAP_C0805-47UF,4V,20%,X6S,CHA",47UF,20%,C0805_H57,11895.69,1931.80,180.000,YES
C1248,"Q_CAP_C0805-47UF,4V,20%,X6S,CHA",47UF,20%,C0805_H57,11920.00,1823.62,0.000,NO
C1249,"Q_CAP_C0805-47UF,4V,20%,X6S,CHA",47UF,20%,C0805_H57,11915.00,1983.62,0.000,NO
C1250,"Q_CAP_0402-1UF,6.3V,10%,EMPTY,A",NA,10%,C0402,12863.93,2764.07,0.000,YES
C1251,"Q_CAP_C0603-10UF,6.3V,20%,X6S,A",10UF,20%,C0603,12957.48,2568.80,45.000,YES
C1252,"Q_CAP_C0603-10UF,6.3V,20%,X6S,A",10UF,20%,C0603,13623.09,2145.19,90.000,YES
C1253,"Q_CAP_0402-1UF,6.3V,10%,EMPTY,A",NA,10%,C0402,13174.35,1980.88,0.000,YES
C1254,"Q_CAP_C0603-10UF,6.3V,20%,X6S,A",10UF,20%,C0603,12998.70,2529.96,45.000,YES
C1255,"Q_CAP_C0603-10UF,6.3V,20%,X6S,A",10UF,20%,C0603,13677.11,2145.04,90.000,YES
C1256,"Q_CAP_0402-1UF,6.3V,10%,EMPTY,A",NA,10%,C0402,13356.09,1790.62,180.000,YES
C1257,"Q_CAP_0402-1UF,6.3V,10%,EMPTY,A",NA,10%,C0402,13482.41,2055.21,270.000,YES
C1258,"Q_CAP_C0805-47UF,4V,20%,X6S,CHA",47UF,20%,C0805_H57,13043.81,2485.16,45.000,YES
C1259,"Q_CAP_C0805-47UF,4V,20%,X6S,CHA",47UF,20%,C0805_H57,13862.12,2143.14,90.000,YES
C1260,"Q_CAP_C0603-10UF,6.3V,20%,X6S,A",10UF,20%,C0603,12918.98,2608.06,45.000,YES
C1261,"Q_CAP_C0603-10UF,6.3V,20%,X6S,A",10UF,20%,C0603,13731.11,2145.52,90.000,YES
C1262,"Q_CAP_C0402-10UF,6.3V,20%,X6S,A",10UF,20%,C0402,13348.14,1995.23,90.000,YES
C1263,"Q_CAP_C0402-10UF,6.3V,20%,X6S,A",10UF,20%,C0402,13420.86,1955.30,180.000,YES
C1264,"Q_CAP_0402-1UF,6.3V,10%,EMPTY,A",NA,10%,C0402,13307.73,1995.23,90.000,YES
C1265,"Q_CAP_0402-1UF,6.3V,10%,EMPTY,A",NA,10%,C0402,13430.12,2050.43,270.000,YES
C1266,"Q_CAP_C0402-10UF,6.3V,20%,X6S,A",10UF,20%,C0402,13420.37,1995.34,180.000,YES
C1272,"Q_CAP_C0805-47UF,4V,20%,X6S,CHA",47UF,20%,C0805_H57,13096.74,2433.91,45.000,YES
C1273,"Q_CAP_C0805-47UF,4V,20%,X6S,CHA",47UF,20%,C0805_H57,13792.12,2143.14,90.000,YES
C1274,"Q_CAP_0402-0.1UF,25V,10%,X7R,CA",0.1UF,10%,C0402,8346.15,1057.81,270.000,NO
C1275,"Q_CAP_0402-0.1UF,25V,10%,X7R,CA",0.1UF,10%,C0402,8329.61,586.32,0.000,NO
C1276,"Q_CAP_C0805-22UF,16V,20%,X6S,CA",22UF,20%,C0805_H57,9584.52,1611.03,270.000,NO
C1277,"Q_CAP_C0805-22UF,16V,20%,X6S,CA",22UF,20%,C0805_H57,9797.08,1543.85,270.000,NO
C1278,"Q_CAP_0402-0.1UF,25V,10%,X7R,CA",0.1UF,10%,C0402,9611.37,1973.49,90.000,NO
C1279,"Q_CAP_0402-0.1UF,25V,10%,X7R,CA",0.1UF,10%,C0402,9570.27,1973.97,90.000,NO
C1282,"Q_CAP_0402-0.1UF,25V,10%,X7R,CA",0.1UF,10%,C0402,9317.95,1933.86,0.000,YES
C1283,"Q_CAP_0402-0.1UF,25V,10%,X7R,CA",0.1UF,10%,C0402,9315.95,1893.86,0.000,YES
C1288,"Q_CAP_0402-0.1UF,25V,10%,X7R,CA",0.1UF,10%,C0402,4254.20,2365.62,0.000,NO
C1289,"Q_CAP_C0402-1UF,25V,10%,X6S,CHA",1UF,10%,C0402,4254.20,2325.62,0.000,NO
C1290,"Q_CAP_C0402-1UF,25V,10%,X6S,CHA",1UF,10%,C0402,15009.04,3842.68,270.000,NO
C1291,"Q_CAP_C0402-1UF,25V,10%,X6S,CHA",1UF,10%,C0402,14517.80,4089.22,90.000,NO
C1292,"Q_CAP_0402-0.1UF,25V,10%,X7R,CA",0.1UF,10%,C0402,4247.20,2253.62,0.000,NO
C1293,"Q_CAP_C0402-1UF,25V,10%,X6S,CHA",1UF,10%,C0402,3802.20,2173.62,180.000,NO
C1296,"Q_CAP_0402-1000PF,50V,5%,X7R,TA",1000PF,5%,C0402,17058.96,7079.47,90.000,YES
C1297,"Q_CAP_0402-1000PF,50V,5%,X7R,TA",1000PF,5%,C0402,903.96,6939.13,270.000,YES
C1300,"Q_CAP_0402-1000PF,50V,5%,EMPTYA",NA,5%,C0402,14632.49,13973.95,90.000,YES
C1301,"Q_CAP_0402-1000PF,50V,5%,X7R,TA",1000PF,5%,C0402,14434.22,14002.04,180.000,NO
C1302,"Q_CAP_C0402-22UF,4V,20%,X6S,CHA",22UF,20%,C0402_H32,6480.00,933.62,0.000,NO
C1305,"Q_CAP_0402-0.1UF,25V,10%,X7R,CA",0.1UF,10%,C0402,6292.20,2343.62,180.000,NO
C1307,"Q_CAP_0402-1000PF,50V,5%,EMPTYA",NA,5%,C0402,17060.17,6974.65,90.000,YES
C1308,"Q_CAP_0402-1000PF,50V,5%,EMPTYA",NA,5%,C0402,809.71,6945.81,270.000,YES
C1309,"Q_CAP_C0603-10UF,6.3V,20%,X6S,A",10UF,20%,C0603,9567.08,3840.66,270.000,YES
C1310,"Q_CAP_C0603-10UF,6.3V,20%,X6S,A",10UF,20%,C0603,10301.41,3973.05,180.000,YES
C1311,"Q_CAP_C0402-1UF,25V,10%,X6S,CHA",1UF,10%,C0402,9930.00,3873.62,180.000,YES
C1312,"Q_CAP_C0402-1UF,25V,10%,X6S,CHA",1UF,10%,C0402,10041.89,4026.98,90.000,YES
C1313,"Q_CAP_C0603-10UF,6.3V,20%,X6S,A",10UF,20%,C0603,9935.00,3961.17,180.000,YES
C1314,"Q_CAP_C0603-10UF,6.3V,20%,X6S,A",10UF,20%,C0603,10319.00,4214.17,270.000,YES
C1315,"Q_CAP_C0402-1UF,25V,10%,X6S,CHA",1UF,10%,C0402,8587.70,5195.82,0.000,NO
C1316,"Q_CAP_C0402-0.047UF,25V,10%,X7A",0.047UF,10%,C0402,8587.70,5155.82,0.000,NO
C1317,"Q_CAP_0402-0.1UF,25V,10%,X7R,CA",0.1UF,10%,C0402,8402.20,4953.62,0.000,NO
C1318,"Q_CAP_C0402-1UF,25V,10%,EMPTY,A",NA,10%,C0402,8586.20,5031.62,0.000,NO
C1319,"Q_CAP_C0402-1UF,25V,10%,X6S,CHA",1UF,10%,C0402,8257.70,4980.82,0.000,NO
C1320,"Q_CAP_0402-0.1UF,25V,10%,X7R,CA",0.1UF,10%,C0402,7772.20,4398.62,270.000,NO
C1321,"Q_CAP_0402-0.1UF,25V,10%,X7R,CA",0.1UF,10%,C0402,4677.36,2953.98,270.000,NO
C1322,"Q_CAP_0402-0.1UF,25V,10%,X7R,CA",0.1UF,10%,C0402,5011.36,2946.98,270.000,NO
C1323,"Q_CAP_0402-0.1UF,25V,10%,X7R,CA",0.1UF,10%,C0402,5832.20,2308.62,180.000,NO
C1324,"Q_CAP_0402-0.1UF,25V,10%,EMPTYA",NA,10%,C0402,9923.45,4143.96,270.000,YES
C1325,"Q_CAP_0402-0.1UF,25V,10%,X7R,CA",0.1UF,10%,C0402,7613.40,4888.62,0.000,NO
C1331,"Q_CAP_C0805-10UF,16V,10%,X6S,CA",10UF,10%,C0805_H57,17437.45,14576.71,0.000,NO
C1332,"Q_CAP_C0402-100NF,50V,10%,X7R,A",100NF,10%,C0402,17523.24,2019.92,270.000,NO
C1333,"Q_CAP_C0805-10UF,16V,10%,X6S,CA",10UF,10%,C0805_H57,17470.50,2010.22,270.000,NO
C1336,"Q_CAP_C0402-10UF,6.3V,20%,X6S,B",10UF,20%,C0402,791.90,6485.74,0.000,NO
C1337,"Q_CAP_0402-0.1UF,25V,10%,X7R,CA",0.1UF,10%,C0402,775.88,6581.52,90.000,NO
C1338,"Q_CAP_C0805-10UF,16V,10%,EMPTYA",NA,10%,C0805_H57,17401.20,2010.92,270.000,NO
C1339,"Q_CAP_C0402-100NF,50V,10%,X7R,A",100NF,10%,C0402,17039.32,2280.19,90.000,NO
C1340,"Q_CAP_C0805-10UF,16V,10%,X6S,CA",10UF,10%,C0805_H57,16981.70,2284.82,90.000,NO
C1344,"Q_CAP_0402-100PF,50V,5%,EMPTY,A",NA,5%,C0402,1289.82,3960.71,180.000,NO
C1347,"Q_CAP_0402-0.1UF,25V,10%,EMPTYA",NA,10%,C0402,1184.82,4045.71,180.000,NO
C1353,"Q_CAP_C0402-22UF,4V,20%,X6S,CHA",22UF,20%,C0402_H32,4190.47,9291.66,0.000,YES
C1362,"Q_CAP_C0402-22UF,4V,20%,X6S,CHA",22UF,20%,C0402_H32,13954.59,9288.06,0.000,YES
C1363,"Q_CAP_C0402-22UF,4V,20%,X6S,CHA",22UF,20%,C0402_H32,17597.12,7246.48,180.000,YES
C1364,"Q_CAP_C0402-22UF,4V,20%,X6S,CHA",22UF,20%,C0402_H32,17596.12,7164.48,180.000,YES
C1365,"Q_CAP_C0402-22UF,4V,20%,X6S,CHA",22UF,20%,C0402_H32,1447.48,7032.70,180.000,YES
C1366,"Q_CAP_C0402-22UF,4V,20%,X6S,CHA",22UF,20%,C0402_H32,1448.48,6949.70,180.000,YES
C1387,"Q_CAP_C0805-47UF,4V,20%,X6S,CHA",47UF,20%,C0805_H57,4230.61,9371.80,270.000,YES
C1388,"Q_CAP_C0805-47UF,4V,20%,X6S,CHA",47UF,20%,C0805_H57,4649.51,10328.70,180.000,YES
C1389,"Q_CAP_C0603-47UF,2.5V,20%,X6S,A",47UF,20%,C0603,4078.61,9361.98,270.000,YES
C1390,"Q_CAP_C0805-47UF,4V,20%,X6S,CHA",47UF,20%,C0805_H57,5661.17,13213.70,0.000,YES
C1391,"Q_CAP_C0603-47UF,2.5V,20%,X6S,A",47UF,20%,C0603,4172.61,9361.98,270.000,YES
C1392,"Q_CAP_C0805-47UF,4V,20%,X6S,CHA",47UF,20%,C0805_H57,5661.17,13301.70,0.000,YES
C1393,"Q_CAP_C0603-47UF,2.5V,20%,X6S,A",47UF,20%,C0603,4125.61,9361.98,270.000,YES
C1396,"Q_CAP_C0805-47UF,4V,20%,X6S,CHA",47UF,20%,C0805_H57,14410.92,10328.69,180.000,YES
C1397,"Q_CAP_C0805-47UF,4V,20%,X6S,CHA",47UF,20%,C0805_H57,15410.08,13301.20,0.000,YES
C1398,"Q_CAP_C0805-47UF,4V,20%,X6S,CHA",47UF,20%,C0805_H57,15410.08,13389.20,0.000,YES
C1399,"Q_CAP_C0805-47UF,4V,20%,X6S,CHA",47UF,20%,C0805_H57,17587.71,7081.21,180.000,YES
C1400,"Q_CAP_C0805-47UF,4V,20%,X6S,CHA",47UF,20%,C0805_H57,17589.77,6999.40,180.000,YES
C1403,"Q_CAP_C0805-47UF,4V,20%,X6S,CHA",47UF,20%,C0805_H57,1586.63,7108.40,180.000,NO
C1404,"Q_CAP_C0805-47UF,4V,20%,X6S,CHA",47UF,20%,C0805_H57,1586.87,7176.60,180.000,NO
C1405,"Q_CAP_C0603-47UF,2.5V,20%,X6S,A",47UF,20%,C0603,13934.02,9358.63,270.000,YES
C1406,"Q_CAP_C0603-47UF,2.5V,20%,X6S,A",47UF,20%,C0603,13887.02,9358.63,270.000,YES
C1407,"Q_CAP_C0603-47UF,2.5V,20%,X6S,A",47UF,20%,C0603,13840.02,9358.63,270.000,YES
C1409,"Q_CAP_C0603-10UF,6.3V,20%,X6S,A",10UF,20%,C0603,9004.60,4929.22,270.000,YES
C1436,"Q_CAP_C0201-0.22UF,6.3V,10%,X6A",0.22UF,10%,C0201,15409.77,13245.55,0.000,YES
C1437,"Q_CAP_C0201-0.22UF,6.3V,10%,X6A",0.22UF,10%,C0201,5659.38,13162.79,0.000,YES
C1507,"Q_CAP_0402-18PF,50V,5%,C0G,CH0A",18PF,5%,C0402,12847.37,1286.93,315.000,NO
C1508,"Q_CAP_0402-18PF,50V,5%,C0G,CH0A",18PF,5%,C0402,12792.00,1345.62,135.000,NO
C1516,Q_CAP_DIFFBUS_C0201-DIFF BUS_0A,,,C0201_DIFF-BUS,4782.51,16083.36,270.000,NO
C1517,Q_CAP_DIFFBUS_C0201-DIFF BUS_0A,,,C0201_DIFF-BUS,4818.51,16083.36,270.000,NO
C1518,Q_CAP_DIFFBUS_C0201-DIFF BUS_0A,,,C0201_DIFF-BUS,4903.11,16083.36,270.000,NO
C1519,Q_CAP_DIFFBUS_C0201-DIFF BUS_0A,,,C0201_DIFF-BUS,4939.11,16083.36,270.000,NO
C1520,Q_CAP_DIFFBUS_C0201-DIFF BUS_0A,,,C0201_DIFF-BUS,5023.71,16083.36,270.000,NO
C1521,Q_CAP_DIFFBUS_C0201-DIFF BUS_0A,,,C0201_DIFF-BUS,5059.71,16083.36,270.000,NO
C1522,Q_CAP_DIFFBUS_C0201-DIFF BUS_0A,,,C0201_DIFF-BUS,5144.31,16083.36,270.000,NO
C1523,Q_CAP_DIFFBUS_C0201-DIFF BUS_0A,,,C0201_DIFF-BUS,5180.31,16083.36,270.000,NO
C1524,Q_CAP_DIFFBUS_C0201-DIFF BUS_0A,,,C0201_DIFF-BUS,5264.91,16083.36,270.000,NO
C1525,Q_CAP_DIFFBUS_C0201-DIFF BUS_0A,,,C0201_DIFF-BUS,5300.91,16083.36,270.000,NO
C1526,Q_CAP_DIFFBUS_C0201-DIFF BUS_0A,,,C0201_DIFF-BUS,5385.51,16083.36,270.000,NO
C1527,Q_CAP_DIFFBUS_C0201-DIFF BUS_0A,,,C0201_DIFF-BUS,5421.51,16083.36,270.000,NO
C1528,Q_CAP_DIFFBUS_C0201-DIFF BUS_0A,,,C0201_DIFF-BUS,5506.11,16083.36,270.000,NO
C1529,Q_CAP_DIFFBUS_C0201-DIFF BUS_0A,,,C0201_DIFF-BUS,5542.11,16083.36,270.000,NO
C1530,Q_CAP_DIFFBUS_C0201-DIFF BUS_0A,,,C0201_DIFF-BUS,5626.71,16083.36,270.000,NO
C1531,Q_CAP_DIFFBUS_C0201-DIFF BUS_0A,,,C0201_DIFF-BUS,5662.71,16083.36,270.000,NO
C1532,Q_CAP_DIFFBUS_C0201-DIFF BUS_0A,,,C0201_DIFF-BUS,5747.31,16083.36,270.000,NO
C1533,Q_CAP_DIFFBUS_C0201-DIFF BUS_0A,,,C0201_DIFF-BUS,5783.31,16083.36,270.000,NO
C1534,Q_CAP_DIFFBUS_C0201-DIFF BUS_0A,,,C0201_DIFF-BUS,5867.91,16083.36,270.000,NO
C1535,Q_CAP_DIFFBUS_C0201-DIFF BUS_0A,,,C0201_DIFF-BUS,5903.91,16083.36,270.000,NO
C1536,Q_CAP_DIFFBUS_C0201-DIFF BUS_0A,,,C0201_DIFF-BUS,5988.51,16083.36,270.000,NO
C1537,Q_CAP_DIFFBUS_C0201-DIFF BUS_0A,,,C0201_DIFF-BUS,6024.51,16083.36,270.000,NO
C1538,Q_CAP_DIFFBUS_C0201-DIFF BUS_0A,,,C0201_DIFF-BUS,6109.11,16083.36,270.000,NO
C1539,Q_CAP_DIFFBUS_C0201-DIFF BUS_0A,,,C0201_DIFF-BUS,6145.11,16083.36,270.000,NO
C1540,Q_CAP_DIFFBUS_C0201-DIFF BUS_0A,,,C0201_DIFF-BUS,6229.71,16083.36,270.000,NO
C1541,Q_CAP_DIFFBUS_C0201-DIFF BUS_0A,,,C0201_DIFF-BUS,6265.71,16083.36,270.000,NO
C1542,Q_CAP_DIFFBUS_C0201-DIFF BUS_0A,,,C0201_DIFF-BUS,6350.31,16083.36,270.000,NO
C1543,Q_CAP_DIFFBUS_C0201-DIFF BUS_0A,,,C0201_DIFF-BUS,6386.31,16083.36,270.000,NO
C1544,Q_CAP_DIFFBUS_C0201-DIFF BUS_0A,,,C0201_DIFF-BUS,6470.91,16083.36,270.000,NO
C1545,Q_CAP_DIFFBUS_C0201-DIFF BUS_0A,,,C0201_DIFF-BUS,6506.91,16083.36,270.000,NO
C1546,Q_CAP_DIFFBUS_C0201-DIFF BUS_0A,,,C0201_DIFF-BUS,6627.51,16083.36,270.000,NO
C1547,Q_CAP_DIFFBUS_C0201-DIFF BUS_0A,,,C0201_DIFF-BUS,6591.51,16083.36,270.000,NO
C1548,Q_CAP_DIFFBUS_C0201-DIFF BUS_0A,,,C0201_DIFF-BUS,13775.72,15841.38,270.000,NO
C1549,Q_CAP_DIFFBUS_C0201-DIFF BUS_0A,,,C0201_DIFF-BUS,13811.72,15841.38,270.000,NO
C1550,Q_CAP_DIFFBUS_C0201-DIFF BUS_0A,,,C0201_DIFF-BUS,13655.12,15841.38,270.000,NO
C1552,Q_CAP_DIFFBUS_C0201-DIFF BUS_0A,,,C0201_DIFF-BUS,13534.52,15841.38,270.000,NO
C1553,Q_CAP_DIFFBUS_C0201-DIFF BUS_0A,,,C0201_DIFF-BUS,13570.52,15841.38,270.000,NO
C1554,Q_CAP_DIFFBUS_C0201-DIFF BUS_0A,,,C0201_DIFF-BUS,13413.92,15841.38,270.000,NO
C1555,Q_CAP_DIFFBUS_C0201-DIFF BUS_0A,,,C0201_DIFF-BUS,13449.92,15841.38,270.000,NO
C1556,Q_CAP_DIFFBUS_C0201-DIFF BUS_0A,,,C0201_DIFF-BUS,13329.32,15841.38,270.000,NO
C1557,Q_CAP_DIFFBUS_C0201-DIFF BUS_0A,,,C0201_DIFF-BUS,13293.32,15841.38,270.000,NO
C1558,Q_CAP_DIFFBUS_C0201-DIFF BUS_0A,,,C0201_DIFF-BUS,13172.72,15841.38,270.000,NO
C1559,Q_CAP_DIFFBUS_C0201-DIFF BUS_0A,,,C0201_DIFF-BUS,13208.72,15841.38,270.000,NO
C1560,Q_CAP_DIFFBUS_C0201-DIFF BUS_0A,,,C0201_DIFF-BUS,13052.12,15841.38,270.000,NO
C1561,"Q_CAP_C0402-1UF,25V,10%,X6S,CHA",1UF,10%,C0402,8664.86,3946.20,0.000,NO
C1562,"Q_CAP_C0402-1UF,25V,10%,EMPTY,A",NA,10%,C0402,8289.77,4092.60,180.000,NO
C1563,Q_CAP_DIFFBUS_C0201-DIFF BUS_0A,,,C0201_DIFF-BUS,12967.52,15841.38,270.000,NO
C1564,Q_CAP_DIFFBUS_C0201-DIFF BUS_0A,,,C0201_DIFF-BUS,12810.92,15841.38,270.000,NO
C1565,Q_CAP_DIFFBUS_C0201-DIFF BUS_0A,,,C0201_DIFF-BUS,12846.92,15841.38,270.000,NO
C1566,Q_CAP_DIFFBUS_C0201-DIFF BUS_0A,,,C0201_DIFF-BUS,12690.32,15841.38,270.000,NO
C1567,Q_CAP_DIFFBUS_C0201-DIFF BUS_0A,,,C0201_DIFF-BUS,12726.32,15841.38,270.000,NO
C1568,Q_CAP_DIFFBUS_C0201-DIFF BUS_0A,,,C0201_DIFF-BUS,12569.72,15841.38,270.000,NO
C1569,Q_CAP_DIFFBUS_C0201-DIFF BUS_0A,,,C0201_DIFF-BUS,12605.72,15841.38,270.000,NO
C1570,Q_CAP_DIFFBUS_C0201-DIFF BUS_0A,,,C0201_DIFF-BUS,12449.12,15841.38,270.000,NO
C1571,Q_CAP_DIFFBUS_C0201-DIFF BUS_0A,,,C0201_DIFF-BUS,12485.12,15841.38,270.000,NO
C1572,Q_CAP_DIFFBUS_C0201-DIFF BUS_0A,,,C0201_DIFF-BUS,12328.52,15841.38,270.000,NO
C1573,Q_CAP_DIFFBUS_C0201-DIFF BUS_0A,,,C0201_DIFF-BUS,12364.52,15841.38,270.000,NO
C1574,Q_CAP_DIFFBUS_C0201-DIFF BUS_0A,,,C0201_DIFF-BUS,12207.92,15841.38,270.000,NO
C1575,Q_CAP_DIFFBUS_C0201-DIFF BUS_0A,,,C0201_DIFF-BUS,12243.92,15841.38,270.000,NO
C1576,Q_CAP_DIFFBUS_C0201-DIFF BUS_0A,,,C0201_DIFF-BUS,12123.32,15841.38,270.000,NO
C1577,Q_CAP_DIFFBUS_C0201-DIFF BUS_0A,,,C0201_DIFF-BUS,12087.32,15841.38,270.000,NO
C1578,Q_CAP_DIFFBUS_C0201-DIFF BUS_0A,,,C0201_DIFF-BUS,11966.72,15841.38,270.000,NO
C1579,Q_CAP_DIFFBUS_C0201-DIFF BUS_0A,,,C0201_DIFF-BUS,12002.72,15841.38,270.000,NO
C1592,"Q_CAP_0402-0.1UF,25V,10%,X7R,CA",0.1UF,10%,C0402,6270.64,2547.02,90.000,NO
C1612,"Q_CAP_C0402-1UF,25V,10%,X6S,CHA",1UF,10%,C0402,12099.00,2455.73,90.000,NO
C1613,"Q_CAP_0402-0.1UF,25V,10%,X7R,CA",0.1UF,10%,C0402,5901.52,2885.27,180.000,NO
C1614,"Q_CAP_0402-0.1UF,25V,10%,X7R,CA",0.1UF,10%,C0402,5769.34,2626.32,0.000,NO
C1619,"Q_CAP_0402-0.1UF,25V,10%,X7R,CA",0.1UF,10%,C0402,5681.89,3052.47,0.000,NO
C1647,"Q_CAP_0402-0.1UF,25V,10%,X7R,CA",0.1UF,10%,C0402,13119.60,540.08,270.000,NO
C1663,"Q_CAP_0402-0.1UF,25V,10%,X7R,CA",0.1UF,10%,C0402,12146.01,538.60,180.000,NO
C1664,"Q_CAP_0402-0.1UF,25V,10%,X7R,CA",0.1UF,10%,C0402,14904.00,4219.82,0.000,NO
C1707,"Q_CAP_0402-0.1UF,25V,10%,X7R,CA",0.1UF,10%,C0402,6542.25,16591.94,270.000,NO
C1708,"Q_CAP_0402-0.1UF,25V,10%,EMPTYA",NA,10%,C0402,14402.60,15707.72,0.000,YES
C1713,"Q_CAP_0402-0.1UF,25V,10%,X7R,CA",0.1UF,10%,C0402,473.33,16583.34,90.000,NO
C1751,"Q_CAP_0402-0.1UF,25V,10%,X7R,CA",0.1UF,10%,C0402,7117.19,16413.51,270.000,NO
C1754,"Q_CAP_0402-1000PF,50V,5%,EMPTYA",NA,5%,C0402,16700.98,15378.62,180.000,NO
C1756,"Q_CAP_0402-1000PF,50V,5%,EMPTYA",NA,5%,C0402,946.73,16343.62,180.000,NO
C1757,"Q_CAP_0402-0.1UF,25V,10%,EMPTYA",NA,10%,C0402,1824.82,4050.71,0.000,NO
C1766,"Q_CAP_0402-0.1UF,25V,10%,X7R,CA",0.1UF,10%,C0402,1948.68,17196.97,0.000,NO
C1767,"Q_CAP_C0805-10UF,16V,10%,EMPTYA",NA,10%,C0805_H57,1064.82,4050.71,180.000,NO
C1768,"Q_CAP_C0805-10UF,16V,10%,EMPTYA",NA,10%,C0805_H57,1843.66,4105.49,0.000,NO
C1769,"Q_CAP_0402-0.1UF,25V,10%,X7R,CA",0.1UF,10%,C0402,6886.20,16708.62,0.000,NO
C1770,"Q_CAP_0402-0.1UF,25V,10%,X7R,CA",0.1UF,10%,C0402,4649.30,16532.32,90.000,NO
C1772,"Q_CAP_0402-1000PF,50V,5%,EMPTYA",NA,5%,C0402,16700.98,14973.62,180.000,NO
C1773,"Q_CAP_0402-1000PF,50V,5%,EMPTYA",NA,5%,C0402,4679.13,16146.82,0.000,NO
C1774,"Q_CAP_0402-1000PF,50V,5%,EMPTYA",NA,5%,C0402,16700.98,15128.62,180.000,NO
C1775,"Q_CAP_0402-0.1UF,25V,10%,X7R,CA",0.1UF,10%,C0402,7622.15,16985.21,180.000,NO
C1791,Q_CAP_DIFFBUS_C0201-DIFF BUS_0A,,,C0201_DIFF-BUS,13806.74,2421.51,0.000,NO
C1792,Q_CAP_DIFFBUS_C0201-DIFF BUS_0A,,,C0201_DIFF-BUS,13691.12,15841.38,270.000,NO
C1793,Q_CAP_DIFFBUS_C0201-DIFF BUS_0A,,,C0201_DIFF-BUS,13088.12,15841.38,270.000,NO
C1794,Q_CAP_DIFFBUS_C0201-DIFF BUS_0A,,,C0201_DIFF-BUS,12931.52,15841.38,270.000,NO
C1796,"Q_CAP_0402-0.1UF,25V,10%,X7R,CA",0.1UF,10%,C0402,1400.67,17200.92,180.000,NO
C1797,"Q_CAP_0402-0.1UF,25V,10%,X7R,CA",0.1UF,10%,C0402,7466.55,16823.62,180.000,NO
C1802,"Q_CAP_0402-1000PF,50V,5%,EMPTYA",NA,5%,C0402,4560.20,15764.37,90.000,NO
C1803,"Q_CAP_0402-0.1UF,25V,10%,X7R,CA",0.1UF,10%,C0402,14416.80,15903.82,0.000,NO
C1804,"Q_CAP_0402-1000PF,50V,5%,EMPTYA",NA,5%,C0402,4380.20,15664.37,90.000,NO
C1809,"Q_CAP_0402-0.1UF,25V,10%,X7R,CA",0.1UF,10%,C0402,1125.12,3003.54,0.000,NO
C1810,"Q_CAP_0402-0.1UF,25V,10%,X7R,CA",0.1UF,10%,C0402,1125.12,2829.95,0.000,NO
C1817,"Q_CAP_0402-0.1UF,25V,10%,X7R,CA",0.1UF,10%,C0402,5704.15,4985.46,0.000,NO
C1818,"Q_CAP_0402-0.1UF,25V,10%,X7R,CA",0.1UF,10%,C0402,5203.10,4550.62,180.000,NO
C1819,"Q_CAP_0402-0.1UF,25V,10%,X7R,CA",0.1UF,10%,C0402,3066.00,1467.02,180.000,NO
C1820,"Q_CAP_0402-0.1UF,25V,10%,X7R,CA",0.1UF,10%,C0402,3651.00,1562.02,0.000,NO
C1821,"Q_CAP_0402-0.1UF,25V,10%,X7R,CA",0.1UF,10%,C0402,4098.59,1611.62,0.000,NO
C1822,"Q_CAP_0402-0.1UF,25V,10%,X7R,CA",0.1UF,10%,C0402,10857.21,696.02,180.000,NO
C1823,"Q_CAP_0402-0.1UF,25V,10%,X7R,CA",0.1UF,10%,C0402,4378.40,1237.71,90.000,NO
C1824,"Q_CAP_0402-0.1UF,25V,10%,X7R,CA",0.1UF,10%,C0402,10962.19,652.62,0.000,NO
C1825,"Q_CAP_0402-0.1UF,25V,10%,X7R,CA",0.1UF,10%,C0402,5968.00,5035.32,90.000,NO
C1826,"Q_CAP_0402-0.1UF,25V,10%,X7R,CA",0.1UF,10%,C0402,8026.69,3127.73,0.000,YES
C1827,"Q_CAP_0402-0.1UF,25V,10%,X7R,CA",0.1UF,10%,C0402,7590.39,2866.32,0.000,YES
C1829,"Q_CAP_C0805-22UF,16V,20%,X6S,CB",22UF,20%,C0805_H57,2594.65,706.36,180.000,NO
C1830,"Q_CAP_C0805-22UF,16V,20%,X6S,CB",22UF,20%,C0805_H57,2594.65,706.36,0.000,YES
C1831,"Q_CAP_0402-0.1UF,25V,10%,X7R,CA",0.1UF,10%,C0402,2604.81,644.55,180.000,NO
C1832,"Q_CAP_0402-0.1UF,25V,10%,X7R,CA",0.1UF,10%,C0402,2604.81,644.55,0.000,YES
C1833,"Q_CAP_0402-0.1UF,25V,10%,X7R,CA",0.1UF,10%,C0402,2604.33,603.45,180.000,NO
C1834,"Q_CAP_0402-0.1UF,25V,10%,X7R,CA",0.1UF,10%,C0402,2604.33,603.45,0.000,YES
C1835,"Q_CAP_0402-0.1UF,25V,10%,X7R,CA",0.1UF,10%,C0402,2541.22,353.70,90.000,YES
C1836,"Q_CAP_0402-0.1UF,25V,10%,X7R,CA",0.1UF,10%,C0402,2422.20,353.62,90.000,YES
C1837,"Q_CAP_0402-0.1UF,25V,10%,X7R,CA",0.1UF,10%,C0402,2462.20,353.62,90.000,YES
C1838,"Q_CAP_0402-0.1UF,25V,10%,X7R,CA",0.1UF,10%,C0402,2502.20,353.62,90.000,YES
C1839,"Q_CAP_0402-0.1UF,25V,10%,X7R,CA",0.1UF,10%,C0402,2604.36,561.60,0.000,YES
C1840,"Q_CAP_0402-0.1UF,25V,10%,X7R,CA",0.1UF,10%,C0402,18187.32,3713.29,0.000,NO
C1841,"Q_CAP_0402-0.1UF,25V,10%,X7R,CA",0.1UF,10%,C0402,5942.20,4323.62,270.000,NO
C1842,"Q_CAP_C0402-10UF,6.3V,20%,X6S,A",10UF,20%,C0402,7192.20,4083.62,0.000,YES
C1859,"Q_CAP_0402-0.1UF,25V,10%,X7R,CA",0.1UF,10%,C0402,4250.75,1174.91,0.000,NO
C1860,"Q_CAP_0402-0.1UF,25V,10%,X7R,CA",0.1UF,10%,C0402,17280.34,1812.34,180.000,NO
C1861,"Q_CAP_0402-0.1UF,25V,10%,X7R,CA",0.1UF,10%,C0402,3871.60,1198.22,180.000,NO
C1862,"Q_CAP_0402-0.1UF,25V,10%,X7R,CA",0.1UF,10%,C0402,17526.59,1875.09,180.000,NO
C1863,"Q_CAP_0402-0.1UF,25V,10%,X7R,CA",0.1UF,10%,C0402,967.74,15275.94,270.000,NO
C1864,"Q_CAP_0402-0.1UF,25V,10%,X7R,CA",0.1UF,10%,C0402,947.00,15412.72,90.000,YES
C1865,"Q_CAP_0402-0.1UF,25V,10%,X7R,CA",0.1UF,10%,C0402,752.74,15480.94,90.000,NO
C1866,"Q_CAP_0402-0.1UF,25V,10%,X7R,CA",0.1UF,10%,C0402,1512.62,15460.09,180.000,YES
C1867,"Q_CAP_C0805-10UF,25V,10%,X6S,CA",10UF,10%,C0805_H61,865.20,15347.62,270.000,YES
C1868,"Q_CAP_0402-0.1UF,25V,10%,X7R,CA",0.1UF,10%,C0402,935.71,15188.12,270.000,NO
C1869,"Q_CAP_0402-0.1UF,25V,10%,X7R,CA",0.1UF,10%,C0402,884.26,15188.12,270.000,NO
C1870,"Q_CAP_0402-0.1UF,25V,10%,X7R,CA",0.1UF,10%,C0402,733.89,15590.97,90.000,NO
C1871,"Q_CAP_0402-0.1UF,25V,10%,X7R,CA",0.1UF,10%,C0402,784.56,15591.02,90.000,NO
C1873,"Q_CAP_0402-0.1UF,25V,10%,X7R,CA",0.1UF,10%,C0402,5967.20,1746.12,0.000,NO
C1874,"Q_CAP_0402-0.1UF,25V,10%,X7R,CA",0.1UF,10%,C0402,17650.10,1643.62,0.000,NO
C1875,"Q_CAP_0402-0.1UF,25V,10%,X7R,CA",0.1UF,10%,C0402,346.80,3024.72,0.000,NO
C1876,"Q_CAP_0402-0.1UF,25V,10%,X7R,CA",0.1UF,10%,C0402,643.06,3029.26,0.000,NO
C1877,"Q_CAP_0402-0.1UF,25V,10%,X7R,CA",0.1UF,10%,C0402,5715.40,1579.32,180.000,NO
C1878,"Q_CAP_0402-0.1UF,25V,10%,X7R,CA",0.1UF,10%,C0402,5898.20,1296.42,0.000,NO
C1879,"Q_CAP_0402-0.1UF,25V,10%,X7R,CA",0.1UF,10%,C0402,5539.70,1317.56,0.000,NO
C1880,"Q_CAP_0402-0.1UF,25V,10%,X7R,CA",0.1UF,10%,C0402,5489.70,1498.02,0.000,NO
C1881,"Q_CAP_0402-1000PF,50V,5%,EMPTYA",NA,5%,C0402,946.88,15858.52,180.000,NO
C1882,"Q_CAP_0402-0.1UF,25V,10%,X7R,CA",0.1UF,10%,C0402,4828.21,1588.64,0.000,NO
C1883,"Q_CAP_C0805-10UF,25V,10%,X6S,CA",10UF,10%,C0805_H61,9372.61,9751.62,180.000,YES
C1884,"Q_CAP_C0402-1UF,25V,10%,X6S,CHA",1UF,10%,C0402,9193.00,9916.52,270.000,YES
C1886,"Q_CAP_0402-0.1UF,25V,10%,X7R,CA",0.1UF,10%,C0402,9340.20,9925.72,90.000,YES
C1889,"Q_CAP_0402-0.1UF,25V,10%,X7R,CA",0.1UF,10%,C0402,9327.78,9861.43,0.000,YES
C1893,"Q_CAP_C0402-0.01UF,50V,10%,X7RA",0.01UF,10%,C0402,7045.50,4369.11,270.000,YES
C1894,"Q_CAP_C0402-0.01UF,50V,10%,X7RA",0.01UF,10%,C0402,7313.22,4605.33,180.000,YES
C1895,"Q_CAP_C0402-0.01UF,50V,10%,X7RA",0.01UF,10%,C0402,6762.03,4463.60,90.000,YES
C1896,"Q_CAP_C0402-0.01UF,50V,10%,X7RA",0.01UF,10%,C0402,6856.52,4778.56,270.000,YES
C1897,"Q_CAP_C0402-0.01UF,50V,10%,X7RA",0.01UF,10%,C0402,7092.74,4479.35,180.000,YES
C1898,"Q_CAP_C0402-0.01UF,50V,10%,X7RA",0.01UF,10%,C0402,6951.01,4369.11,270.000,YES
C1899,"Q_CAP_C0402-0.01UF,50V,10%,X7RA",0.01UF,10%,C0402,7083.00,4203.25,270.000,YES
C1900,"Q_CAP_C0402-0.01UF,50V,10%,X7RA",0.01UF,10%,C0402,7265.97,4463.60,270.000,YES
C1901,"Q_CAP_C0402-0.01UF,50V,10%,X7RA",0.01UF,10%,C0402,6714.79,4321.87,0.000,YES
C1902,"Q_CAP_C0402-0.01UF,50V,10%,X7RA",0.01UF,10%,C0402,7029.75,4668.32,0.000,YES
C1903,"Q_CAP_C0402-0.01UF,50V,10%,X7RA",0.01UF,10%,C0402,6966.76,4416.36,0.000,YES
C1904,"Q_CAP_C0402-0.01UF,50V,10%,X7RA",0.01UF,10%,C0402,6982.51,4369.11,270.000,YES
C1905,"Q_CAP_0402-0.1UF,25V,10%,X7R,CA",0.1UF,10%,C0402,6903.77,4384.86,180.000,YES
C1906,"Q_CAP_0402-0.1UF,25V,10%,X7R,CA",0.1UF,10%,C0402,7108.49,4558.09,90.000,YES
C1907,"Q_CAP_0402-0.1UF,25V,10%,X7R,CA",0.1UF,10%,C0402,6966.76,4510.84,0.000,YES
C1908,"Q_CAP_C0402-0.01UF,50V,10%,X7RA",0.01UF,10%,C0402,7014.00,4369.11,270.000,YES
C1909,"Q_CAP_C0402-0.01UF,50V,10%,X7RA",0.01UF,10%,C0402,7313.22,4321.87,180.000,YES
C1910,"Q_CAP_C0402-0.01UF,50V,10%,X7RA",0.01UF,10%,C0402,6714.79,4605.33,0.000,YES
C1911,"Q_CAP_C0402-0.01UF,50V,10%,X7RA",0.01UF,10%,C0402,7234.47,4778.56,270.000,YES
C1912,"Q_CAP_C0402-0.01UF,50V,10%,X7RA",0.01UF,10%,C0402,7092.74,4447.85,180.000,YES
C1913,"Q_CAP_C0402-0.01UF,50V,10%,X7RA",0.01UF,10%,C0402,6856.52,4148.64,90.000,YES
C1914,"Q_CAP_C0402-0.01UF,50V,10%,X7RA",0.01UF,10%,C0402,6903.77,4416.36,180.000,YES
C1915,"Q_CAP_C0402-0.01UF,50V,10%,X7RA",0.01UF,10%,C0402,7076.99,4558.09,90.000,YES
C1916,"Q_CAP_C0402-0.01UF,50V,10%,X7RA",0.01UF,10%,C0402,7014.00,4495.10,270.000,YES
C1917,"Q_CAP_C0402-0.01UF,50V,10%,X7RA",0.01UF,10%,C0402,6903.77,4447.85,180.000,YES
C1918,"Q_CAP_C0402-0.01UF,50V,10%,X7RA",0.01UF,10%,C0402,7045.50,4558.09,90.000,YES
C1919,"Q_CAP_C0402-0.01UF,50V,10%,X7RA",0.01UF,10%,C0402,7045.50,4495.10,270.000,YES
C1920,"Q_CAP_C0603-22UF,6.3V,20%,X6S,A",22UF,20%,C0603,6514.90,2237.02,90.000,NO
C1921,"Q_CAP_C0603-22UF,6.3V,20%,X6S,A",22UF,20%,C0603,6569.26,2236.97,90.000,NO
C1922,"Q_CAP_C0603-22UF,6.3V,20%,X6S,A",22UF,20%,C0603,6697.70,1972.72,180.000,YES
C1923,"Q_CAP_0402-0.1UF,25V,10%,X7R,CA",0.1UF,10%,C0402,6679.80,2103.62,180.000,YES
C1924,"Q_CAP_0402-0.1UF,25V,10%,X7R,CA",0.1UF,10%,C0402,6679.80,2063.62,180.000,YES
C1925,"Q_CAP_0402-0.1UF,25V,10%,X7R,CA",0.1UF,10%,C0402,6679.80,2023.62,180.000,YES
C1926,"Q_CAP_C0402-0.01UF,50V,10%,X7RA",0.01UF,10%,C0402,6903.77,4542.34,180.000,YES
C1927,"Q_CAP_C0402-0.01UF,50V,10%,X7RA",0.01UF,10%,C0402,7014.00,4558.09,90.000,YES
C1928,"Q_CAP_C0402-0.01UF,50V,10%,X7RA",0.01UF,10%,C0402,7045.50,4432.10,90.000,YES
C1929,"Q_CAP_C0402-0.01UF,50V,10%,X7RA",0.01UF,10%,C0402,6903.77,4479.35,180.000,YES
C1930,"Q_CAP_C0402-0.01UF,50V,10%,X7RA",0.01UF,10%,C0402,6982.51,4558.09,90.000,YES
C1931,"Q_CAP_C0402-0.01UF,50V,10%,X7RA",0.01UF,10%,C0402,7014.00,4432.10,90.000,YES
C1932,"Q_CAP_C0402-0.01UF,50V,10%,X7RA",0.01UF,10%,C0402,6903.77,4510.84,180.000,YES
C1933,"Q_CAP_C0402-0.01UF,50V,10%,X7RA",0.01UF,10%,C0402,6951.01,4558.09,90.000,YES
C1934,"Q_CAP_C0402-0.01UF,50V,10%,X7RA",0.01UF,10%,C0402,6966.76,4447.85,0.000,YES
C1935,"Q_CAP_C0402-10UF,6.3V,20%,X6S,A",10UF,20%,C0402,7012.20,4083.62,0.000,YES
C1936,"Q_CAP_C0402-10UF,6.3V,20%,X6S,A",10UF,20%,C0402,7097.20,4888.62,180.000,YES
C1937,"Q_CAP_C0402-10UF,6.3V,20%,X6S,A",10UF,20%,C0402,7397.20,4083.62,180.000,YES
C1938,"Q_CAP_C0402-10UF,6.3V,20%,X6S,A",10UF,20%,C0402,6647.20,4043.62,0.000,YES
C1939,"Q_CAP_C0402-10UF,6.3V,20%,X6S,A",10UF,20%,C0402,6907.20,4879.87,270.000,YES
C1940,"Q_CAP_C0402-10UF,6.3V,20%,X6S,A",10UF,20%,C0402,6812.95,4083.62,0.000,YES
C1941,"Q_CAP_0402-0.1UF,25V,10%,X7R,CA",0.1UF,10%,C0402,7192.20,4043.62,0.000,YES
C1942,"Q_CAP_0402-0.1UF,25V,10%,X7R,CA",0.1UF,10%,C0402,7012.20,4043.62,0.000,YES
C1943,"Q_CAP_0402-0.1UF,25V,10%,X7R,CA",0.1UF,10%,C0402,7097.20,4848.62,180.000,YES
C1944,"Q_CAP_0402-0.1UF,25V,10%,X7R,CA",0.1UF,10%,C0402,7397.20,4043.62,180.000,YES
C1945,"Q_CAP_0402-0.1UF,25V,10%,X7R,CA",0.1UF,10%,C0402,6647.20,4083.62,0.000,YES
C1946,"Q_CAP_0402-0.1UF,25V,10%,X7R,CA",0.1UF,10%,C0402,6947.20,4879.87,270.000,YES
C1947,"Q_CAP_0402-0.1UF,25V,10%,X7R,CA",0.1UF,10%,C0402,6812.95,4043.62,0.000,YES
C1957,"Q_CAP_0402-0.1UF,25V,10%,X7R,CA",0.1UF,10%,C0402,1147.20,16818.62,270.000,NO
C1958,"Q_CAP_0402-0.1UF,25V,10%,X7R,CA",0.1UF,10%,C0402,6652.20,17203.62,0.000,NO
C1963,"Q_CAP_0402-0.1UF,25V,10%,X7R,CA",0.1UF,10%,C0402,4060.50,15499.42,180.000,NO
C1973,"Q_CAP_0402-1000PF,50V,5%,EMPTYA",NA,5%,C0402,6670.18,16475.57,180.000,NO
C1974,"Q_CAP_0402-1000PF,50V,5%,EMPTYA",NA,5%,C0402,946.88,15938.67,180.000,NO
C1975,"Q_CAP_0402-1000PF,50V,5%,EMPTYA",NA,5%,C0402,6932.22,16446.67,0.000,NO
C1976,"Q_CAP_0402-1000PF,50V,5%,EMPTYA",NA,5%,C0402,16700.98,15535.57,180.000,NO
C1977,"Q_CAP_0402-0.1UF,25V,10%,X7R,CA",0.1UF,10%,C0402,1162.20,16963.62,0.000,NO
C1978,"Q_CAP_0402-1000PF,50V,5%,EMPTYA",NA,5%,C0402,1088.00,16104.00,270.000,NO
C1979,"Q_CAP_0402-0.1UF,25V,10%,X7R,CA",0.1UF,10%,C0402,4428.83,16001.54,180.000,NO
C1988,"Q_CAP_0402-1000PF,50V,5%,EMPTYA",NA,5%,C0402,947.63,16118.21,180.000,NO
C1989,Q_CAP_DIFFBUS_C0201-DIFF BUS_0A,,,C0201_DIFF-BUS,9415.46,2296.35,180.000,NO
C1990,Q_CAP_DIFFBUS_C0201-DIFF BUS_0A,,,C0201_DIFF-BUS,9415.46,2260.35,180.000,NO
C1991,Q_CAP_DIFFBUS_C0201-DIFF BUS_0A,,,C0201_DIFF-BUS,9482.46,2225.48,180.000,NO
C1992,Q_CAP_DIFFBUS_C0201-DIFF BUS_0A,,,C0201_DIFF-BUS,9482.46,2189.48,180.000,NO
C1993,Q_CAP_DIFFBUS_C0201-DIFF BUS_0A,,,C0201_DIFF-BUS,9415.46,2118.97,180.000,NO
C1994,Q_CAP_DIFFBUS_C0201-DIFF BUS_0A,,,C0201_DIFF-BUS,9415.46,2154.97,180.000,NO
C1995,Q_CAP_DIFFBUS_C0201-DIFF BUS_0A,,,C0201_DIFF-BUS,9415.46,2047.75,180.000,NO
C1996,Q_CAP_DIFFBUS_C0201-DIFF BUS_0A,,,C0201_DIFF-BUS,9415.46,2083.75,180.000,NO
C1997,"Q_CAP_0402-0.1UF,25V,10%,X7R,CA",0.1UF,10%,C0402,8503.20,1627.62,0.000,NO
C1998,"Q_CAP_0402-0.1UF,25V,10%,X7R,CA",0.1UF,10%,C0402,8727.20,1663.62,0.000,NO
C2007,"Q_CAP_C0402-1UF,25V,10%,X6S,CHA",1UF,10%,C0402,5527.20,1663.62,90.000,NO
C2010,"Q_CAP_0402-0.1UF,25V,10%,X7R,CA",0.1UF,10%,C0402,14735.27,16595.49,270.000,NO
C2012,"Q_CAP_0402-0.1UF,25V,10%,X7R,CA",0.1UF,10%,C0402,2980.53,1517.03,0.000,NO
C2013,"Q_CAP_0402-0.1UF,25V,10%,X7R,CA",0.1UF,10%,C0402,6129.56,2028.78,0.000,NO
C2014,"Q_CAP_0402-0.1UF,25V,10%,X7R,CA",0.1UF,10%,C0402,8266.14,1486.98,90.000,NO
C2015,"Q_CAP_0402-0.1UF,25V,10%,X7R,CA",0.1UF,10%,C0402,17255.00,3793.62,90.000,NO
C2017,"Q_CAP_0402-0.1UF,25V,10%,X7R,CA",0.1UF,10%,C0402,2980.53,1562.03,0.000,NO
C2018,"Q_CAP_0402-0.1UF,25V,10%,X7R,CA",0.1UF,10%,C0402,6129.56,2073.78,0.000,NO
C2019,"Q_CAP_0402-0.1UF,25V,10%,X7R,CA",0.1UF,10%,C0402,8211.20,1409.62,90.000,YES
C2020,"Q_CAP_0402-0.1UF,25V,10%,X7R,CA",0.1UF,10%,C0402,2982.11,1792.79,90.000,YES
C2021,"Q_CAP_0402-0.1UF,25V,10%,X7R,CA",0.1UF,10%,C0402,6215.36,2100.76,270.000,NO
C2022,"Q_CAP_0402-0.1UF,25V,10%,X7R,CA",0.1UF,10%,C0402,8082.20,1415.62,90.000,YES
C2024,"Q_CAP_0402-0.1UF,25V,10%,X7R,CA",0.1UF,10%,C0402,17225.00,3703.62,90.000,NO
C2027,"Q_CAP_0402-0.1UF,25V,10%,X7R,CA",0.1UF,10%,C0402,17161.90,3649.62,0.000,NO
C2029,"Q_CAP_0402-18PF,50V,5%,C0G,CH0A",18PF,5%,C0402,365.24,3937.71,90.000,NO
C2030,"Q_CAP_0402-18PF,50V,5%,C0G,CH0A",18PF,5%,C0402,365.95,3865.52,270.000,NO
C2031,"Q_CAP_C0402-1UF,25V,10%,X6S,CHA",1UF,10%,C0402,575.44,3984.96,90.000,YES
C2032,"Q_CAP_0402-0.1UF,25V,10%,X7R,CA",0.1UF,10%,C0402,638.13,3884.62,0.000,YES
C2033,"Q_CAP_0402-0.1UF,25V,10%,X7R,CA",0.1UF,10%,C0402,472.58,3934.08,180.000,YES
C2034,"Q_CAP_0402-0.1UF,25V,10%,X7R,CA",0.1UF,10%,C0402,470.91,3869.93,180.000,YES
C2035,"Q_CAP_C0402-1UF,25V,10%,X6S,CHA",1UF,10%,C0402,537.38,3984.70,90.000,YES
C2036,"Q_CAP_C0402-8.2PF,50V,0.1P,NP0A",8.2PF,0.1P,C0402,9792.94,3569.10,0.000,NO
C2037,"Q_CAP_C0402-8.2PF,50V,0.1P,NP0A",8.2PF,0.1P,C0402,9715.93,3568.96,180.000,NO
C2038,"Q_CAP_C0402-10UF,6.3V,20%,X6S,A",10UF,20%,C0402,638.11,3930.79,0.000,YES
C2039,"Q_CAP_0402-0.1UF,25V,10%,X7R,CA",0.1UF,10%,C0402,653.97,3831.28,90.000,YES
C2040,"Q_CAP_0402-0.1UF,25V,10%,X7R,CA",0.1UF,10%,C0402,699.98,3832.37,90.000,YES
C2041,"Q_CAP_C0402-1UF,25V,10%,X6S,CHA",1UF,10%,C0402,468.34,3649.12,270.000,NO
C2042,"Q_CAP_0402-100PF,50V,5%,EMPTY,A",NA,5%,C0402,1824.82,3890.71,0.000,NO
C2043,"Q_CAP_0402-100PF,50V,5%,EMPTY,A",NA,5%,C0402,1824.82,3850.71,0.000,NO
C2044,"Q_CAP_0402-100PF,50V,5%,EMPTY,A",NA,5%,C0402,1289.82,3840.71,180.000,NO
C2045,"Q_CAP_0402-100PF,50V,5%,EMPTY,A",NA,5%,C0402,1824.82,3930.71,0.000,NO
C2046,"Q_CAP_0402-0.1UF,25V,10%,X7R,CA",0.1UF,10%,C0402,1453.96,4433.83,0.000,NO
C2047,"Q_CAP_0402-0.1UF,25V,10%,X7R,CA",0.1UF,10%,C0402,1453.96,4233.83,0.000,NO
C2048,"Q_CAP_0402-0.1UF,25V,10%,X7R,CA",0.1UF,10%,C0402,1453.96,4273.83,0.000,NO
C2049,"Q_CAP_0402-0.1UF,25V,10%,X7R,CA",0.1UF,10%,C0402,1453.96,4313.83,0.000,NO
C2050,"Q_CAP_0402-0.1UF,25V,10%,X7R,CA",0.1UF,10%,C0402,1453.96,4193.83,0.000,NO
C2051,"Q_CAP_0402-0.1UF,25V,10%,X7R,CA",0.1UF,10%,C0402,794.91,4365.19,180.000,NO
C2052,"Q_CAP_0402-0.1UF,25V,10%,X7R,CA",0.1UF,10%,C0402,794.91,4325.19,180.000,NO
C2056,"Q_CAP_0402-0.1UF,25V,10%,X7R,CA",0.1UF,10%,C0402,2582.70,4586.17,0.000,NO
C2067,"Q_CAP_0402-0.1UF,25V,10%,X7R,CA",0.1UF,10%,C0402,8512.20,2093.62,0.000,YES
C2069,"Q_CAP_0402-0.1UF,25V,10%,X7R,CA",0.1UF,10%,C0402,8511.20,2163.62,0.000,YES
C2071,"Q_CAP_0402-0.1UF,25V,10%,X7R,CA",0.1UF,10%,C0402,8587.83,2259.83,270.000,NO
C2073,Q_CAP_DIFFBUS_C0201-DIFF BUS_0A,,,C0201_DIFF-BUS,3914.17,15924.67,270.000,YES
C2074,Q_CAP_DIFFBUS_C0201-DIFF BUS_0A,,,C0201_DIFF-BUS,3878.42,15924.67,270.000,YES
C2075,Q_CAP_DIFFBUS_C0201-DIFF BUS_0A,,,C0201_DIFF-BUS,4027.81,16125.10,90.000,NO
C2076,Q_CAP_DIFFBUS_C0201-DIFF BUS_0A,,,C0201_DIFF-BUS,4059.19,16125.10,90.000,NO
C2077,Q_CAP_DIFFBUS_C0201-DIFF BUS_0A,,,C0201_DIFF-BUS,6668.89,372.37,270.000,YES
C2078,Q_CAP_DIFFBUS_C0201-DIFF BUS_0A,,,C0201_DIFF-BUS,6635.61,372.36,270.000,YES
C2148,"Q_CAP_C0402-0.01UF,50V,10%,EMPA",NA,10%,C0402,3185.57,958.03,180.000,NO
C2175,"Q_CAP_0402-100PF,50V,5%,EMPTY,A",NA,5%,C0402,1289.82,3880.71,180.000,NO
C2176,"Q_CAP_0402-100PF,50V,5%,EMPTY,A",NA,5%,C0402,1289.82,3920.71,180.000,NO
C2177,"Q_CAP_0402-0.1UF,25V,10%,X7R,CA",0.1UF,10%,C0402,1453.96,4353.83,0.000,NO
C2178,"Q_CAP_0402-0.1UF,25V,10%,X7R,CA",0.1UF,10%,C0402,1453.96,4393.83,0.000,NO
C2179,"Q_CAP_C0402-100NF,50V,10%,X7R,A",100NF,10%,C0402,7219.45,15640.88,180.000,NO
C2194,"Q_CAP_0402-0.1UF,25V,10%,X7R,CA",0.1UF,10%,C0402,1453.96,4150.62,0.000,NO
C2195,"Q_CAP_0402-100PF,50V,5%,EMPTY,A",NA,5%,C0402,1685.62,3960.03,270.000,YES
C2243,"Q_CAP_C0402-1UF,25V,10%,X6S,CHA",1UF,10%,C0402,4672.11,3677.33,270.000,NO
C2246,"Q_CAP_C0402-1UF,25V,10%,X6S,CHA",1UF,10%,C0402,4629.21,4265.03,270.000,NO
C2247,"Q_CAP_C0402-1UF,25V,10%,X6S,CHA",1UF,10%,C0402,4995.70,4263.62,270.000,NO
C2248,"Q_CAP_C0402-1UF,25V,10%,X6S,CHA",1UF,10%,C0402,5715.56,3765.49,270.000,NO
C2249,"Q_CAP_0402-0.1UF,25V,10%,X7R,CA",0.1UF,10%,C0402,4557.20,4097.62,90.000,NO
C2252,"Q_CAP_0402-0.1UF,25V,10%,X7R,CA",0.1UF,10%,C0402,4515.20,4808.37,90.000,NO
C2253,"Q_CAP_0402-0.1UF,25V,10%,X7R,CA",0.1UF,10%,C0402,4881.69,4806.96,90.000,NO
C2254,"Q_CAP_0402-0.1UF,25V,10%,X7R,CA",0.1UF,10%,C0402,5668.25,4243.92,180.000,NO
C2255,"Q_CAP_C0402-8.2PF,50V,0.1P,NP0A",8.2PF,0.1P,C0402,9472.75,9784.07,270.000,NO
C2256,"Q_CAP_C0402-8.2PF,50V,0.1P,NP0A",8.2PF,0.1P,C0402,9473.48,9870.77,90.000,NO
C2257,"Q_CAP_0402-0.1UF,25V,10%,X7R,CA",0.1UF,10%,C0402,9326.40,9804.62,0.000,YES
C2258,"Q_CAP_0402-0.1UF,25V,10%,X7R,CA",0.1UF,10%,C0402,9263.80,9811.82,270.000,YES
C2259,"Q_CAP_0402-0.1UF,25V,10%,X7R,CA",0.1UF,10%,C0402,9209.00,9862.42,180.000,YES
C2264,"Q_CAP_0402-1000PF,50V,5%,EMPTYA",NA,5%,C0402,11974.00,16500.25,270.000,NO
C2265,"Q_CAP_0402-1000PF,50V,5%,EMPTYA",NA,5%,C0402,11868.30,16497.15,270.000,NO
C2266,"Q_CAP_0402-1000PF,50V,5%,EMPTYA",NA,5%,C0402,12188.10,16958.15,270.000,NO
C2267,"Q_CAP_0402-1000PF,50V,5%,EMPTYA",NA,5%,C0402,11972.40,16955.05,270.000,NO
C2268,"Q_CAP_0402-1000PF,50V,5%,EMPTYA",NA,5%,C0402,11758.30,16497.15,270.000,NO
C2269,"Q_CAP_0402-1000PF,50V,5%,EMPTYA",NA,5%,C0402,12080.10,16955.50,270.000,NO
C2270,"Q_CAP_0402-1000PF,50V,5%,EMPTYA",NA,5%,C0402,11648.30,16497.15,270.000,NO
C2271,"Q_CAP_0402-1000PF,50V,5%,EMPTYA",NA,5%,C0402,14074.33,15164.35,180.000,NO
C2272,"Q_CAP_0402-1000PF,50V,5%,EMPTYA",NA,5%,C0402,14078.23,15434.75,180.000,NO
C2273,"Q_CAP_0402-1000PF,50V,5%,EMPTYA",NA,5%,C0402,14076.73,15322.55,180.000,NO
C2274,"Q_CAP_0402-0.1UF,25V,10%,X7R,CA",0.1UF,10%,C0402,4529.93,759.85,0.000,NO
C2275,"Q_CAP_0402-0.1UF,25V,10%,X7R,CA",0.1UF,10%,C0402,4075.57,16568.85,90.000,NO
C2276,"Q_CAP_0402-0.1UF,25V,10%,X7R,CA",0.1UF,10%,C0402,11505.37,736.79,180.000,NO
C2283,"Q_CAP_0402-0.1UF,25V,10%,X7R,CA",0.1UF,10%,C0402,12124.05,16739.63,0.000,NO
C2284,"Q_CAP_C0805-22UF,16V,20%,X6S,CB",22UF,20%,C0805_H57,5108.50,975.42,180.000,NO
C2285,"Q_CAP_0402-0.1UF,25V,10%,X7R,CA",0.1UF,10%,C0402,5108.30,1076.72,270.000,NO
C2286,"Q_CAP_0402-0.1UF,25V,10%,X7R,CA",0.1UF,10%,C0402,5010.80,935.82,0.000,NO
C2287,"Q_CAP_C0402-0.01UF,50V,10%,X7RA",0.01UF,10%,C0402,15182.58,2809.56,180.000,NO
C2289,"Q_CAP_C0201-0.1UF,6.3V,10%,X6SA",0.1UF,10%,C0201,5194.30,948.82,180.000,YES
C2290,"Q_CAP_C0201-0.1UF,6.3V,10%,X6SA",0.1UF,10%,C0201,5194.30,980.12,180.000,YES
C2291,"Q_CAP_C0201-0.1UF,6.3V,10%,X6SA",0.1UF,10%,C0201,4865.30,1112.82,0.000,YES
C2292,"Q_CAP_C0201-0.1UF,6.3V,10%,X6SA",0.1UF,10%,C0201,4865.30,1079.72,0.000,YES
C2293,"Q_CAP_0402-0.1UF,25V,10%,EMPTYA",NA,10%,C0402,9421.00,16653.00,90.000,YES
C2294,"Q_CAP_0402-0.1UF,25V,10%,EMPTYA",NA,10%,C0402,9223.20,16653.62,90.000,YES
C2295,"Q_CAP_0402-0.1UF,25V,10%,EMPTYA",NA,10%,C0402,9261.20,16653.62,90.000,YES
C2296,"Q_CAP_0402-0.1UF,25V,10%,EMPTYA",NA,10%,C0402,9461.00,16653.00,90.000,YES
C2297,"Q_CAP_0402-0.1UF,25V,10%,EMPTYA",NA,10%,C0402,9382.20,16652.62,90.000,YES
C2313,"Q_CAP_C0402-10UF,6.3V,20%,EMPTA",NA,20%,C0402,6290.02,1645.87,270.000,YES
C2314,"Q_CAP_0402-0.1UF,25V,10%,EMPTYA",NA,10%,C0402,6248.31,1646.32,270.000,YES
C2315,"Q_CAP_0402-0.1UF,25V,10%,EMPTYA",NA,10%,C0402,6270.81,1515.59,0.000,YES
C2316,"Q_CAP_C0402-1UF,25V,10%,EMPTY,A",NA,10%,C0402,6270.83,1469.42,0.000,YES
C2317,"Q_CAP_C0402-1UF,25V,10%,EMPTY,A",NA,10%,C0402,6060.79,1233.92,270.000,NO
C2318,"Q_CAP_0402-0.1UF,25V,10%,EMPTYA",NA,10%,C0402,6170.08,1569.50,90.000,YES
C2319,"Q_CAP_0402-0.1UF,25V,10%,EMPTYA",NA,10%,C0402,6208.14,1569.76,90.000,YES
C2320,"Q_CAP_0402-0.1UF,25V,10%,EMPTYA",NA,10%,C0402,6105.28,1518.88,180.000,YES
C2321,"Q_CAP_0402-0.1UF,25V,10%,EMPTYA",NA,10%,C0402,5689.65,1141.32,180.000,YES
C2322,"Q_CAP_C0402-1UF,25V,10%,EMPTY,A",NA,10%,C0402,6103.61,1454.73,180.000,YES
C2323,"Q_CAP_C0402-1UF,25V,10%,EMPTY,A",NA,10%,C0402,5463.70,1187.32,270.000,YES
C2324,"Q_CAP_0402-0.1UF,25V,10%,EMPTYA",NA,10%,C0402,5425.30,1187.32,270.000,YES
C2325,"Q_CAP_0402-0.1UF,25V,10%,EMPTYA",NA,10%,C0402,5378.25,1125.92,0.000,YES
C2326,"Q_CAP_C0402-12PF,50V,5%,EMPTY,A",NA,5%,C0402,5987.24,1518.71,90.000,NO
C2327,"Q_CAP_C0402-12PF,50V,5%,EMPTY,A",NA,5%,C0402,5987.95,1446.52,270.000,NO
C2328,"Q_CAP_C0603-10UF,6.3V,20%,X6S,A",10UF,20%,C0603,4382.55,16120.77,90.000,YES
C2329,"Q_CAP_0402-0.1UF,25V,10%,X7R,CA",0.1UF,10%,C0402,4365.14,16379.17,90.000,YES
C2330,"Q_CAP_0402-0.1UF,25V,10%,X7R,CA",0.1UF,10%,C0402,4343.25,16264.19,180.000,YES
C2331,"Q_CAP_C0603-10UF,6.3V,20%,X6S,A",10UF,20%,C0603,4296.28,16340.47,90.000,YES
C2332,"Q_CAP_C0603-10UF,6.3V,20%,X6S,A",10UF,20%,C0603,4484.95,16365.01,0.000,YES
C2333,"Q_CAP_0402-0.1UF,25V,10%,X7R,CA",0.1UF,10%,C0402,4402.80,16379.87,90.000,YES
C2334,"Q_CAP_0402-0.1UF,25V,10%,X7R,CA",0.1UF,10%,C0402,4446.00,16209.32,270.000,YES
C2335,"Q_CAP_0402-0.1UF,25V,10%,X7R,CA",0.1UF,10%,C0402,4493.60,16263.52,0.000,YES
C2336,"Q_CAP_0402-0.1UF,25V,10%,X7R,CA",0.1UF,10%,C0402,4328.51,16198.37,270.000,YES
C2337,"Q_CAP_0402-0.1UF,25V,10%,X7R,CA",0.1UF,10%,C0402,10751.64,5096.45,0.000,NO
C2338,"Q_CAP_0402-0.1UF,25V,10%,X7R,CA",0.1UF,10%,C0402,10398.69,5096.06,180.000,NO
C2339,"Q_CAP_0402-0.1UF,25V,10%,X7R,CA",0.1UF,10%,C0402,4402.70,16207.72,270.000,YES
C2340,"Q_CAP_0402-1000PF,50V,5%,EMPTYA",NA,5%,C0402,3837.40,16619.82,270.000,YES
C2341,"Q_CAP_0402-0.1UF,25V,10%,X7R,CA",0.1UF,10%,C0402,14222.70,16032.62,0.000,NO
C2342,"Q_CAP_0402-1000PF,50V,5%,EMPTYA",NA,5%,C0402,11204.72,16192.60,270.000,NO
C2343,"Q_CAP_0402-1000PF,50V,5%,EMPTYA",NA,5%,C0402,14040.00,16303.62,180.000,NO
C2344,"Q_CAP_0402-0.1UF,25V,10%,X7R,CA",0.1UF,10%,C0402,3652.00,1301.62,0.000,NO
C2345,"Q_CAP_0402-0.1UF,25V,10%,X7R,CA",0.1UF,10%,C0402,14427.00,600.62,180.000,NO
C2346,"Q_CAP_0402-0.1UF,25V,10%,X7R,CA",0.1UF,10%,C0402,15180.00,1164.62,0.000,NO
C2347,"Q_CAP_0402-0.1UF,25V,10%,X7R,CA",0.1UF,10%,C0402,3224.00,1615.62,180.000,NO
C2348,"Q_CAP_0402-0.1UF,25V,10%,X7R,CA",0.1UF,10%,C0402,5025.00,2283.62,0.000,NO
C2349,Q_CAP_DIFFBUS_C0402-DIFF BUS_0A,,,C0402_DIFF-BUS,5186.90,1110.60,0.000,YES
C2350,Q_CAP_DIFFBUS_C0402-DIFF BUS_0A,,,C0402_DIFF-BUS,5186.90,1075.50,0.000,YES
C2351,"Q_CAP_0402-0.1UF,25V,10%,EMPTYA",NA,10%,C0402,733.89,15622.47,270.000,NO
C2352,"Q_CAP_0402-0.1UF,25V,10%,EMPTYA",NA,10%,C0402,784.56,15622.52,270.000,NO
C2353,"Q_CAP_0402-0.1UF,25V,10%,EMPTYA",NA,10%,C0402,935.71,15156.62,90.000,NO
C2354,"Q_CAP_0402-0.1UF,25V,10%,EMPTYA",NA,10%,C0402,884.26,15156.62,90.000,NO
C2355,"Q_CAP_C0402-1UF,25V,10%,X6S,CHA",1UF,10%,C0402,1401.04,15560.77,270.000,YES
C2356,"Q_CAP_C0805-10UF,16V,10%,X6S,CA",10UF,10%,C0805_H57,1339.14,15587.34,270.000,YES
C2357,"Q_CAP_0402-0.1UF,25V,10%,X7R,CA",0.1UF,10%,C0402,1585.70,15250.05,270.000,NO
C2358,"Q_CAP_0402-0.1UF,25V,10%,X7R,CA",0.1UF,10%,C0402,1545.81,15249.64,270.000,NO
C2359,"Q_CAP_C0402-0.22UF,25V,10%,X7RA",0.22UF,10%,C0402,16961.50,2024.70,180.000,YES
C2360,"Q_CAP_0402-0.1UF,25V,10%,X7R,CA",0.1UF,10%,C0402,16731.80,2016.70,180.000,NO
C2363,"Q_CAP_0402-0.1UF,25V,10%,EMPTYA",NA,10%,C0402,11850.30,16289.61,90.000,NO
C2364,"Q_CAP_0402-0.1UF,25V,10%,EMPTYA",NA,10%,C0402,11850.80,16204.89,270.000,NO
C2369,"Q_CAP_C0402-1UF,25V,10%,EMPTY,A",NA,10%,C0402,8509.00,4730.00,180.000,NO
C2370,"Q_CAP_0402-0.1UF,25V,10%,EMPTYA",NA,10%,C0402,8208.40,4768.00,180.000,NO
C2371,"Q_CAP_0402-0.1UF,25V,10%,EMPTYA",NA,10%,C0402,9183.00,16654.00,90.000,YES
C2372,"Q_CAP_0402-1000PF,50V,5%,EMPTYA",NA,5%,C0402,4127.00,16035.00,180.000,NO
C2373,"Q_CAP_0402-1000PF,50V,5%,EMPTYA",NA,5%,C0402,14009.00,15825.00,180.000,NO
C2374,"Q_CAP_0402-1000PF,50V,5%,EMPTYA",NA,5%,C0402,14424.00,15984.00,180.000,NO
C2376,"Q_CAP_0402-0.1UF,25V,10%,X7R,CA",0.1UF,10%,C0402,17302.90,4188.40,90.000,NO
C2377,"Q_CAP_0402-0.1UF,25V,10%,X7R,CA",0.1UF,10%,C0402,5665.17,4517.10,0.000,NO
C2378,"Q_CAP_0402-0.1UF,25V,10%,X7R,CA",0.1UF,10%,C0402,8675.00,1965.00,180.000,NO
C2379,"Q_CAP_C0402-100NF,50V,10%,EMPTA",NA,10%,C0402,7946.00,3647.00,270.000,NO
C2380,"Q_CAP_C0402-100NF,50V,10%,EMPTA",NA,10%,C0402,8193.00,4492.00,180.000,NO
C2381,"Q_CAP_C0402-100NF,50V,10%,EMPTA",NA,10%,C0402,8022.00,3647.00,270.000,NO
C2382,"Q_CAP_C0402-100NF,50V,10%,EMPTA",NA,10%,C0402,8442.00,4229.00,270.000,NO
C2383,"Q_CAP_C0402-100NF,50V,10%,EMPTA",NA,10%,C0402,7895.00,3853.00,180.000,NO
C2384,"Q_CAP_C0402-100NF,50V,10%,EMPTA",NA,10%,C0402,8370.00,4468.00,0.000,NO
C2385,"Q_CAP_C0402-100NF,50V,10%,EMPTA",NA,10%,C0402,12102.00,936.00,180.000,NO
C2386,"Q_CAP_C0402-100NF,50V,10%,EMPTA",NA,10%,C0402,11968.00,974.00,180.000,NO
C2387,"Q_CAP_C0402-100NF,50V,10%,EMPTA",NA,10%,C0402,12114.00,1132.00,180.000,NO
C2388,"Q_CAP_C0402-100NF,50V,10%,EMPTA",NA,10%,C0402,7157.80,16189.30,270.000,NO
C2389,"Q_CAP_C0402-100NF,50V,10%,EMPTA",NA,10%,C0402,7197.70,16189.20,270.000,NO
C2390,"Q_CAP_C0402-100NF,50V,10%,EMPTA",NA,10%,C0402,7197.70,16445.50,0.000,NO
C2391,"Q_CAP_0402-1000PF,50V,5%,EMPTYA",NA,5%,C0402,14378.00,16329.00,0.000,NO
C2392,"Q_CAP_0402-0.1UF,25V,10%,EMPTYA",NA,10%,C0402,8289.77,4052.60,180.000,NO
C2393,"Q_CAP_0402-0.1UF,25V,10%,EMPTYA",NA,10%,C0402,11000.30,16759.70,0.000,NO
C2394,"Q_CAP_0402-0.1UF,25V,10%,X7R,CA",0.1UF,10%,C0402,8664.86,3906.20,0.000,NO
C2443,"Q_CAP_C0402-10UF,6.3V,20%,X6S,B",10UF,20%,C0402,17366.11,4922.67,90.000,NO
C2444,"Q_CAP_0402-0.1UF,25V,10%,X7R,CA",0.1UF,10%,C0402,17377.01,4868.37,0.000,NO
C2445,"Q_CAP_0402-1000PF,50V,5%,EMPTYA",NA,5%,C0402,4794.57,13984.02,0.000,YES
C2446,"Q_CAP_0402-1000PF,50V,5%,X7R,TA",1000PF,5%,C0402,4099.80,13954.53,270.000,NO
C2447,"Q_CAP_0402-1000PF,50V,5%,EMPTYA",NA,5%,C0402,4048.99,14112.31,180.000,NO
C2448,"Q_CAP_C0603-10UF,4V,20%,EMPTY,A",NA,20%,C0603,3978.19,14060.08,270.000,NO
C2449,"Q_CAP_C0402-100NF,50V,10%,X7R,A",100NF,10%,C0402,3936.99,14040.38,270.000,NO
C2450,"Q_CAP_0402-1000PF,50V,5%,EMPTYA",NA,5%,C0402,1454.97,4988.10,0.000,NO
C2451,"Q_CAP_0402-1000PF,50V,5%,X7R,TA",1000PF,5%,C0402,1454.97,5028.10,0.000,NO
C2452,"Q_CAP_0402-1000PF,50V,5%,X7R,TA",1000PF,5%,C0402,1454.97,5228.10,0.000,NO
C2453,"Q_CAP_0402-1000PF,50V,5%,EMPTYA",NA,5%,C0402,1454.98,5227.71,180.000,YES
C2454,"Q_CAP_0402-1000PF,50V,5%,EMPTYA",NA,5%,C0402,891.40,6677.34,180.000,NO
C2458,"Q_CAP_0402-0.1UF,25V,10%,EMPTYA",NA,10%,C0402,11509.70,16189.60,0.000,NO
C2459,"Q_CAP_0603-1000PF,50V,10%,EMPTA",NA,10%,C0603,11332.20,16092.90,270.000,NO
C2460,"Q_CAP_0402-1000PF,50V,5%,X7R,TA",1000PF,5%,C0402,4698.47,14004.35,180.000,NO
C2541,"Q_CAP_C0402-0.22UF,25V,10%,X7RA",0.22UF,10%,C0402,17705.66,3019.59,90.000,YES
C2859,"Q_CAP_0402-1000PF,50V,5%,EMPTYA",NA,5%,C0402,4071.25,14210.03,90.000,NO
C2860,"Q_CAP_0402-1000PF,50V,5%,X7R,TA",1000PF,5%,C0402,4184.31,14152.75,180.000,YES
C3266,"Q_CAP_0402-1000PF,50V,5%,EMPTYA",NA,5%,C0402,13850.66,14210.03,90.000,NO
C3267,"Q_CAP_0402-1000PF,50V,5%,X7R,TA",1000PF,5%,C0402,13945.72,14152.75,180.000,YES
C3268,"Q_CAP_0402-1000PF,50V,5%,X7R,TA",1000PF,5%,C0402,13861.81,13956.53,270.000,NO
C3269,"Q_CAP_0402-1000PF,50V,5%,EMPTYA",NA,5%,C0402,13810.40,14112.31,180.000,NO
C3270,"Q_CAP_C0603-10UF,4V,20%,EMPTY,A",NA,20%,C0603,13741.26,14064.54,180.000,YES
C3271,"Q_CAP_C0402-100NF,50V,10%,X7R,A",100NF,10%,C0402,13719.66,14023.34,180.000,YES
C3273,"Q_CAP_0402-1000PF,50V,5%,EMPTYA",NA,5%,C0402,16952.76,5255.07,0.000,NO
C3274,"Q_CAP_0402-1000PF,50V,5%,X7R,TA",1000PF,5%,C0402,16952.76,5295.07,0.000,NO
C3275,"Q_CAP_0402-1000PF,50V,5%,X7R,TA",1000PF,5%,C0402,16952.76,5495.07,0.000,NO
C3276,"Q_CAP_0402-1000PF,50V,5%,EMPTYA",NA,5%,C0402,16952.76,5375.07,180.000,YES
C4562,"Q_CAP_C0402-1UF,25V,10%,EMPTY,A",NA,10%,C0402,11000.30,16798.70,0.000,NO
C5229,"Q_CAP_C0402-1UF,25V,10%,EMPTY,A",NA,10%,C0402,567.22,4370.26,90.000,YES
C5232,"Q_CAP_0402-0.1UF,25V,10%,EMPTYA",NA,10%,C0402,322.55,4411.30,0.000,YES
C5234,"Q_CAP_0402-0.1UF,25V,10%,EMPTYA",NA,10%,C0402,607.61,4369.59,90.000,YES
C5236,"Q_CAP_0402-0.1UF,25V,10%,EMPTYA",NA,10%,C0402,639.28,4436.77,180.000,YES
D0,"Q_LED_SMLF-LED_BLUE,LTST-C281TA",,,LED2S_0402,8653.20,4374.62,180.000,NO
D6,"Q_LED_SMLF-LED_YELLOW,LTST-C19A",,,LED_1921XA,7743.30,3173.92,0.000,NO
D7,"BAT547F-BAT547F,SMLF,IC,BC0BATA",,,SOT23_123XB,16606.36,1832.50,270.000,NO
D42,"SCHOTTKY_12-B0530WS7F,SMLF,IC,A",,,SOD323XB,12161.49,12446.85,270.000,YES
D43,"SCHOTTKY_12-B0530WS7F,SMLF,IC,A",,,SOD323XB,11270.69,12419.95,270.000,YES
D44,"SCHOTTKY_12-B0530WS7F,SMLF,IC,A",,,SOD323XB,17053.10,12358.79,180.000,YES
D45,"SCHOTTKY_12-B0530WS7F,SMLF,IC,A",,,SOD323XB,18093.49,12411.85,270.000,YES
D46,"SCHOTTKY_12-B0530WS7F,SMLF,IC,A",,,SOD323XB,2685.97,12597.85,270.000,YES
D47,"SCHOTTKY_12-B0530WS7F,SMLF,IC,A",,,SOD323XB,1509.27,12419.95,270.000,YES
D48,"SCHOTTKY_12-B0530WS7F,SMLF,IC,A",,,SOD323XB,7297.97,12419.63,180.000,YES
D49,"SCHOTTKY_12-B0530WS7F,SMLF,IC,A",,,SOD323XB,8332.07,12446.85,270.000,YES
D65,"Q_LED_SMLF-LED_BLUE,LTST-C281TA",,,LED2S_0402,3188.24,2786.85,0.000,NO
D66,"Q_LED_SMLF-LED_BLUE,LTST-C281TA",,,LED2S_0402,3062.24,2786.85,0.000,NO
D67,"Q_LED_SMLF-LED_BLUE,LTST-C281TA",,,LED2S_0402,2936.24,2786.85,0.000,NO
D68,"Q_LED_SMLF-LED_BLUE,LTST-C281TA",,,LED2S_0402,2810.24,2786.85,0.000,NO
D69,"Q_LED_SMLF-LED_BLUE,LTST-C281TA",,,LED2S_0402,2684.24,2786.85,0.000,NO
D70,"Q_LED_SMLF-LED_BLUE,LTST-C281TA",,,LED2S_0402,2558.24,2786.85,0.000,NO
D71,"Q_LED_SMLF-LED_BLUE,LTST-C281TA",,,LED2S_0402,2432.24,2786.85,0.000,NO
D72,"Q_LED_SMLF-LED_BLUE,LTST-C281TA",,,LED2S_0402,2306.24,2786.85,0.000,NO
D73,"Q_LED_SMLF-LED_BLUE,LTST-C281TA",,,LED2S_0402,3306.94,3113.34,0.000,NO
D74,"Q_LED_SMLF-LED_BLUE,LTST-C281TA",,,LED2S_0402,3054.94,3113.34,0.000,NO
D75,"Q_LED_SMLF-LED_BLUE,LTST-C281TA",,,LED2S_0402,2802.94,3113.34,0.000,NO
D76,"Q_LED_SMLF-LED_BLUE,LTST-C281TA",,,LED2S_0402,2550.94,3113.34,0.000,NO
D77,"Q_LED_SMLF-LED_BLUE,LTST-C281TA",,,LED2S_0402,2298.94,3113.34,0.000,NO
D78,"Q_LED_SMLF-LED_BLUE,LTST-C281TA",,,LED2S_0402,4196.24,2786.85,0.000,NO
D79,"Q_LED_SMLF-LED_BLUE,LTST-C281TA",,,LED2S_0402,3944.24,2786.85,0.000,NO
D80,"Q_LED_SMLF-LED_BLUE,LTST-C281TA",,,LED2S_0402,3180.94,3113.34,0.000,NO
D81,"Q_LED_SMLF-LED_BLUE,LTST-C281TA",,,LED2S_0402,2928.94,3113.34,0.000,NO
D82,"Q_LED_SMLF-LED_BLUE,LTST-C281TA",,,LED2S_0402,2676.94,3113.34,0.000,NO
D83,"Q_LED_SMLF-LED_BLUE,LTST-C281TA",,,LED2S_0402,2424.94,3113.34,0.000,NO
D84,"Q_LED_SMLF-LED_BLUE,LTST-C281TA",,,LED2S_0402,4337.84,2787.15,0.000,NO
D85,"Q_LED_SMLF-LED_BLUE,LTST-C281TA",,,LED2S_0402,4070.24,2786.85,0.000,NO
D86,"Q_LED_SMLF-LED_BLUE,LTST-C281TA",,,LED2S_0402,3818.24,2786.85,0.000,NO
D87,"Q_LED_SMLF-LED_BLUE,LTST-C281TA",,,LED2S_0402,3692.24,2786.85,0.000,NO
D88,"Q_LED_SMLF-LED_BLUE,LTST-C281TA",,,LED2S_0402,3566.24,2786.85,0.000,NO
D89,"Q_LED_SMLF-LED_BLUE,LTST-C281TA",,,LED2S_0402,3440.24,2786.85,0.000,NO
D90,"Q_LED_SMLF-LED_BLUE,LTST-C281TA",,,LED2S_0402,3314.24,2786.85,0.000,NO
D91,"Q_LED_SMLF-LED_BLUE,LTST-C281TA",,,LED2S_0402,4314.94,3113.34,0.000,NO
D92,"Q_LED_SMLF-LED_BLUE,LTST-C281TA",,,LED2S_0402,4188.94,3113.34,0.000,NO
D93,"Q_LED_SMLF-LED_BLUE,LTST-C281TA",,,LED2S_0402,4062.94,3113.34,0.000,NO
D94,"Q_LED_SMLF-LED_BLUE,LTST-C281TA",,,LED2S_0402,3936.94,3113.34,0.000,NO
D95,"Q_LED_SMLF-LED_BLUE,LTST-C281TA",,,LED2S_0402,3810.94,3113.34,0.000,NO
D96,"Q_LED_SMLF-LED_BLUE,LTST-C281TA",,,LED2S_0402,3684.94,3113.34,0.000,NO
D97,"Q_LED_SMLF-LED_BLUE,LTST-C281TA",,,LED2S_0402,4440.94,3113.34,0.000,NO
D98,"Q_LED_SMLF-LED_BLUE,LTST-C281TA",,,LED2S_0402,3558.94,3113.34,0.000,NO
D99,"Q_LED_SMLF-LED_BLUE,LTST-C281TA",,,LED2S_0402,3432.94,3113.34,0.000,NO
D141,"SCHOTTKY_12-1N5819HW,SMLF,IC,BA",,,SOD123,5184.30,2986.55,270.000,NO
D142,"Q_LED_SMLF-LED_BLUE,LTST-C281TA",,,LED2S_0402,14518.00,2811.90,0.000,NO
D143,"Q_LED_SMLF-LED_BLUE,LTST-C281TA",,,LED2S_0402,1681.44,2309.28,0.000,NO
D144,"Q_LED_SMLF-LED_YELLOW,LTST-C19A",,,LED_1921XA,8058.40,2645.80,0.000,NO
D145,"Q_DIODE_SMLF-SDMK0340L-7-F,IC,A",,,SOD323XB,17805.00,3190.23,270.000,YES
DB1,"TDR_3P_TH2-EMPTY,N_A",,,TDR_3P_C85P67_141_100M_Q,19511.78,13495.97,0.000,NO
DB2,"TDR_3P_TH2-EMPTY,N_A",,,TDR_3P_C85P67_141_100M_Q,19936.18,13498.97,0.000,NO
DB3,"TDR_3P_TH2-EMPTY,N_A",,,TDR_3P_C85P67_141_100M_Q,19931.47,16828.75,180.000,NO
DB4,"TDR_3P_TH2-EMPTY,N_A",,,TDR_3P_C85P67_141_100M_Q,19504.84,16834.97,180.000,NO
DB5,"TDR_3P_TH2-EMPTY,N_A",,,TDR_3P_C85P67_141_100M_Q,19726.97,13496.06,0.000,YES
DB6,"TDR_3P_TH2-EMPTY,N_A",,,TDR_3P_C85P67_141_100M_Q,19296.95,16832.20,180.000,YES
DB7,"TDR_3P_TH2-EMPTY,N_A",,,TDR_3P_C85P67_141_100M_Q,19026.82,13512.95,0.000,NO
DB8,"TDR_3P_TH2-EMPTY,N_A",,,TDR_3P_C85P67_141_100M_Q,19024.02,16832.56,180.000,NO
DB9,"TDR_3P_TH2-EMPTY,N_A",,,TDR_3P_C85P67_141_100M_Q,19030.86,13182.28,180.000,NO
DB10,"TDR_3P_TH2-EMPTY,N_A",,,TDR_3P_C85P67_141_100M_Q,19026.08,9883.22,0.000,NO
DB11,"TDR_3P_TH2-EMPTY,N_A",,,TDR_3P_C85P67_141_100M_Q,18812.11,13509.83,0.000,YES
DB12,"TDR_3P_TH2-EMPTY,N_A",,,TDR_3P_C85P67_141_100M_Q,18817.20,9882.79,0.000,YES
DB13,"TDR_3P_TH2-EMPTY,N_A",,,TDR_3P_C85P67_141_100M_Q,19715.55,16831.30,180.000,YES
DB14,"TDR_3P_TH2-EMPTY,N_A",,,TDR_3P_C85P67_141_100M_Q,19302.00,13495.48,0.000,YES
DB15,"TDR_3P_TH2-EMPTY,N_A",,,TDR_3P_C85P67_141_100M_Q,18811.65,16822.07,180.000,YES
DB16,"TDR_3P_TH2-EMPTY,N_A",,,TDR_3P_C85P67_141_100M_Q,18808.36,13171.64,180.000,YES
DM9,"DUMMY_SYMBOL-MECHANIC_SYMBOL,MA",,,TP30_FOR_BOM,19584.20,18425.49,0.000,NO
DM13,"DUMMY_SYMBOL-BATTERY_SYMBOL,MEA",,,TP30_FOR_BOM,19641.70,18424.29,0.000,NO
FS1,"Q_FUSE_SMLF-20A/125V,IC,DKK00XA",,,F4012,9668.80,16458.70,180.000,YES
H15,"HOLE_TH-EMPTY,HOLE1079",,,HOLE_D3-429N,13322.05,11713.18,0.000,NO
H16,"HOLE_TH-EMPTY,HOLE1079",,,HOLE_D3-429N,5252.76,11713.18,0.000,NO
H17,"HOLE_TH-EMPTY,HOLE1079",,,HOLE_D3-429N,15014.18,11713.18,0.000,NO
H18,"HOLE_TH-EMPTY,HOLE1079",,,HOLE_D3-429N,5312.40,8111.21,0.000,NO
H19,"HOLE_TH-EMPTY,HOLE1079",,,HOLE_D3-429N,15507.09,9912.20,0.000,NO
H20,"HOLE_TH-EMPTY,HOLE1079",,,HOLE_D3-429N,3500.99,8111.21,0.000,NO
H21,"HOLE_TH-EMPTY,HOLE1079",,,HOLE_D3-429N,15073.82,8111.21,0.000,NO
H22,"HOLE_TH-EMPTY,HOLE1079",,,HOLE_D3-429N,3560.63,11713.18,0.000,NO
H23,"HOLE_TH-EMPTY,HOLE1079",,,HOLE_D3-429N,13262.40,8111.21,0.000,NO
H24,"HOLE_TH-EMPTY,HOLE1079",,,HOLE_D3-429N,3067.72,9912.20,0.000,NO
H25,"HOLE_TH-EMPTY,HOLE1079",,,HOLE_D3-429N,12829.14,9912.20,0.000,NO
H26,"HOLE_TH-EMPTY,HOLE1079",,,HOLE_D3-429N,5745.67,9912.20,0.000,NO
H27,"HOLE_TH-EMPTY,DUMMY50",,,HOLE_TOOLINGD125N_T2-0,18081.92,15692.55,0.000,NO
H28,"HOLE_TH-EMPTY,DUMMY50",,,HOLE_TOOLINGD125N_T2-0,492.80,3374.02,0.000,NO
H29,"HOLE_TH-EMPTY,DUMMY50",,,HOLE_TOOLINGD125N_T2-0,18129.80,5024.72,0.000,NO
H30,"HOLE_TH-EMPTY,DUMMY50",,,HOLE_TOOLINGD125N_T2-0,418.70,15112.91,0.000,NO
H31,"HOLE_TH-EMPTY,HOLE1248",,,HOLE_C4-5D3-8B8I5-6_RO6-6_NPT_RB,2770.98,1852.36,0.000,NO
H32,"HOLE_TH-EMPTY,HOLE1248",,,HOLE_C4-5D3-8B8I5-6_RO6-6_NPT_RB,3952.08,1852.36,0.000,NO
H36,"HOLE_TH-EMPTY,TMP-Q_HOLE78",,,HOLE_D3-1N,14051.18,1120.08,0.000,NO
H38,"HOLE_TH-EMPTY,TMP-Q_HOLE78",,,HOLE_D3-1N,12476.38,2694.88,0.000,NO
H44,"HOLE_TH-EMPTY,SP_HOLE1199",,,G_HOLE_C8D3-2B8I5_RO6_NPB,15136.18,13954.13,0.000,NO
H45,"HOLE_TH-EMPTY,SP_HOLE1199",,,G_HOLE_C8D3-2B8I5_RO6_NPB,12986.42,13918.30,0.000,NO
H47,"HOLE_TH-EMPTY,SP_HOLE1199",,,G_HOLE_C8D3-2B8I5_RO6_NPB,3225.00,13918.30,0.000,NO
H49,"HOLE_TH-EMPTY,SP_HOLE1199",,,G_HOLE_C8D3-2B8I5_RO6_NPB,5374.77,13954.13,0.000,NO
H74,"HOLE_TH-EMPTY,HOLE1247",,,H_OB6-4X8OBD3-2X4-8B6-4X8N_RO6X7-6_NPM,3684.37,1852.36,90.000,NO
H75,"HOLE_TH-EMPTY,HOLE1247",,,H_OB6-4X8OBD3-2X4-8B6-4X8N_RO6X7-6_NPM,2503.26,1852.36,90.000,NO
H76,"HOLE_TH-EMPTY,HOLE1187",,,HOLE_R4-2X5D2B4_IX0-1T_NPM_RB,9446.84,1552.16,0.000,NO
H77,"HOLE_TH-EMPTY,HOLE1187",,,HOLE_R4-2X5D2B4_IX0-1T_NPM_RB,9001.96,1751.97,0.000,NO
H86,"HOLE_TH-EMPTY,HOLE596",,,HOLE_C10D5-6B10_NPB,6610.23,6318.90,0.000,NO
H87,"HOLE_TH-EMPTY,HOLE596",,,HOLE_C10D5-6B10_NPB,18062.99,17149.61,0.000,NO
H88,"HOLE_TH-EMPTY,HOLE596",,,HOLE_C10D5-6B10_NPB,12712.60,6318.90,0.000,NO
H89,"HOLE_TH-EMPTY,HOLE596",,,HOLE_C10D5-6B10_NPB,7076.77,17149.61,0.000,NO
H90,"HOLE_TH-EMPTY,HOLE372",,,HOLE_C5D3-1N,17669.29,17149.60,0.000,NO
H91,"HOLE_TH-EMPTY,HOLE596",,,HOLE_C10D5-6B10_NPB,11557.08,17149.61,0.000,NO
H92,"HOLE_TH-EMPTY,HOLE596",,,HOLE_C10D5-6B10_NPB,3956.70,17149.61,0.000,NO
H93,"HOLE_TH-EMPTY,HOLE596",,,HOLE_C10D5-6B10_NPB,14618.05,17149.61,0.000,NO
H94,"HOLE_TH-EMPTY,HOLE596",,,HOLE_C10D5-6B10_NPB,9316.92,7578.74,0.000,NO
H95,"HOLE_TH-EMPTY,HOLE596",,,HOLE_C10D5-6B10_NPB,9316.92,13877.95,0.000,NO
H96,"HOLE_TH-EMPTY,HOLE596",,,HOLE_C10D5-6B10_NPB,511.81,17149.61,0.000,NO
H97,"HOLE_TH-EMPTY,HOLE596",,,HOLE_C10D5-6B10_NPB,407.08,13688.97,0.000,NO
H98,"HOLE_TH-EMPTY,HOLE596",,,HOLE_C10D5-6B10_NPB,18167.71,13688.97,0.000,NO
H99,"HOLE_TH-EMPTY,HOLE596",,,HOLE_C10D5-6B10_NPB,9316.92,10728.34,0.000,NO
H100,"HOLE_TH-EMPTY,HOLE596",,,HOLE_C10D5-6B10_NPB,275.59,877.95,0.000,NO
H101,"HOLE_TH-EMPTY,HOLE596",,,HOLE_C10D5-6B10_NPB,3736.22,877.95,0.000,NO
H102,"HOLE_TH-EMPTY,HOLE596",,,HOLE_C10D5-6B10_NPB,10458.65,877.95,0.000,NO
H103,"HOLE_TH-EMPTY,HOLE596",,,HOLE_C10D5-6B10_NPB,8007.87,877.95,0.000,NO
H104,"HOLE_TH-EMPTY,HOLE596",,,HOLE_C10D5-6B10_NPB,18167.71,6318.90,0.000,NO
H105,"HOLE_TH-EMPTY,HOLE596",,,HOLE_C10D5-6B10_NPB,14996.06,877.95,0.000,NO
H106,"HOLE_TH-EMPTY,HOLE596",,,HOLE_C10D5-6B10_NPB,18299.21,877.95,0.000,NO
H111,"GND_HOLE_TH-EMPTY,GND_HOLE140",,,GND_C10D5-5B10,10576.58,2047.24,0.000,NO
H112,"GND_HOLE_TH-EMPTY,GND_HOLE140",,,GND_C10D5-5B10,8056.90,2047.24,0.000,NO
H113,"GND_HOLE_TH-EMPTY,TMP-QGND_HOLA",,,GND_C8D4B8,10162.40,14203.30,0.000,NO
H114,"GND_HOLE_TH-EMPTY,TMP-QGND_HOLA",,,GND_C8D4B8,8412.40,14203.30,0.000,NO
H115,"GND_HOLE_TH-EMPTY,GND_HOLE514",,,GND_C10D6-5B10_NPM_RB_NSP,9287.39,3216.53,180.000,NO
H120,"HOLE_TH-EMPTY,TMP-C_T2I_ALEX_1A",,,HOLE_D10N,17397.06,6054.55,0.000,NO
H122,"HOLE_TH-EMPTY,TMP-C_T2I_ALEX_1A",,,HOLE_D10N,10940.74,6053.80,0.000,NO
H124,"HOLE_TH-EMPTY,TMP-C_T2I_ALEX_1A",,,HOLE_D10N,7636.01,6054.13,0.000,NO
H125,"HOLE_TH-EMPTY,TMP-C_T2I_ALEX_1A",,,HOLE_D10N,383.46,14203.30,0.000,NO
H126,"HOLE_TH-EMPTY,TMP-C_T2I_ALEX_1A",,,HOLE_D10N,1179.32,6053.80,0.000,NO
H127,"HOLE_TH-EMPTY,TMP-C_T2I_ALEX_1A",,,HOLE_D10N,18192.08,14203.30,0.000,NO
H128,"HOLE_TH-EMPTY,HOLE596",,,HOLE_C10D5-6B10_NPB,407.08,6318.90,0.000,NO
H129,"HOLE_TH-EMPTY,HOLE1195",,,HOLE_C8D4-2B8_NPB,11337.79,16535.43,0.000,NO
J90_CON,"TP_TP_BOM ONLY-NA,TP12_BOM",,,TP30,19060.04,18515.86,0.000,NO
J1,SCONN288_ADR50017P130CC-SCONN2A,,,DDR288S_1-1VXB,11944.62,10161.09,0.000,NO
J2,SCONN288_ADR50017P087CC-SCONN2A,,,DDR288S_1-1VXB,12241.62,10161.09,0.000,NO
J3,SCONN288_ADR50017P130CC-SCONN2A,,,DDR288S_1-1VXB,11350.62,10161.09,0.000,NO
J4,SCONN288_ADR50017P087CC-SCONN2A,,,DDR288S_1-1VXB,11647.62,10161.09,0.000,NO
J5,SCONN288_ADR50017P130CC-SCONN2A,,,DDR288S_1-1VXB,10756.62,10161.09,0.000,NO
J6,SCONN288_ADR50017P087CC-SCONN2A,,,DDR288S_1-1VXB,11053.62,10161.09,0.000,NO
J7,SCONN288_ADR50017P130CC-SCONN2A,,,DDR288S_1-1VXB,10162.62,10161.09,0.000,NO
J8,SCONN288_ADR50017P087CC-SCONN2A,,,DDR288S_1-1VXB,10459.62,10161.09,0.000,NO
J9,SCONN288_ADR50017P130CC-SCONN2A,,,DDR288S_1-1VXB,16391.62,10161.09,0.000,NO
J10,SCONN288_ADR50017P087CC-SCONN2A,,,DDR288S_1-1VXB,16094.62,10161.09,0.000,NO
J11,SCONN288_ADR50017P130CC-SCONN2A,,,DDR288S_1-1VXB,16985.62,10161.09,0.000,NO
J12,SCONN288_ADR50017P087CC-SCONN2A,,,DDR288S_1-1VXB,16688.62,10161.09,0.000,NO
J13,SCONN288_ADR50017P130CC-SCONN2A,,,DDR288S_1-1VXB,17579.62,10161.09,0.000,NO
J14,SCONN288_ADR50017P087CC-SCONN2A,,,DDR288S_1-1VXB,17282.62,10161.09,0.000,NO
J15,SCONN288_ADR50017P130CC-SCONN2A,,,DDR288S_1-1VXB,18173.62,10161.09,0.000,NO
J16,SCONN288_ADR50017P087CC-SCONN2A,,,DDR288S_1-1VXB,17876.62,10161.09,0.000,NO
J17,SCONN288_ADR50017P130CC-SCONN2A,,,DDR288S_1-1VXB,2183.20,10161.09,0.000,NO
J18,SCONN288_ADR50017P087CC-SCONN2A,,,DDR288S_1-1VXB,2480.20,10161.09,0.000,NO
J19,SCONN288_ADR50017P130CC-SCONN2A,,,DDR288S_1-1VXB,1589.20,10161.09,0.000,NO
J20,SCONN288_ADR50017P087CC-SCONN2A,,,DDR288S_1-1VXB,1886.20,10161.09,0.000,NO
J21,SCONN288_ADR50017P130CC-SCONN2A,,,DDR288S_1-1VXB,995.20,10161.09,0.000,NO
J22,SCONN288_ADR50017P087CC-SCONN2A,,,DDR288S_1-1VXB,1292.20,10161.09,0.000,NO
J23,SCONN288_ADR50017P130CC-SCONN2A,,,DDR288S_1-1VXB,401.20,10161.09,0.000,NO
J24,SCONN288_ADR50017P087CC-SCONN2A,,,DDR288S_1-1VXB,698.20,10161.09,0.000,NO
J25,SCONN288_ADR50017P130CC-SCONN2A,,,DDR288S_1-1VXB,6630.20,10161.09,0.000,NO
J26,SCONN288_ADR50017P087CC-SCONN2A,,,DDR288S_1-1VXB,6333.20,10161.09,0.000,NO
J27,SCONN288_ADR50017P130CC-SCONN2A,,,DDR288S_1-1VXB,7224.20,10161.09,0.000,NO
J28,SCONN288_ADR50017P087CC-SCONN2A,,,DDR288S_1-1VXB,6927.20,10161.09,0.000,NO
J29,SCONN288_ADR50017P130CC-SCONN2A,,,DDR288S_1-1VXB,7818.20,10161.09,0.000,NO
J30,SCONN288_ADR50017P087CC-SCONN2A,,,DDR288S_1-1VXB,7521.20,10161.09,0.000,NO
J31,SCONN288_ADR50017P130CC-SCONN2A,,,DDR288S_1-1VXB,8412.20,10161.09,0.000,NO
J32,SCONN288_ADR50017P087CC-SCONN2A,,,DDR288S_1-1VXB,8115.20,10161.09,0.000,NO
J35,SCONN168_ME1016810202011-SCONNA,,,CON_F168S2H7D_P0-6W2-95_LUH,1866.22,219.29,270.000,NO
J37,SCONN168_ME1016810202011-SCONNA,,,CON_F168S2H7D_P0-6W2-95_LUH,16610.31,219.29,270.000,NO
J41,SCONN168_ME1016810202011-SCONNA,,,CON_F168S2H7D_P0-6W2-95_LUH,6315.04,427.17,270.000,NO
J42,SCONN60_ASP21410801-SCONN60_ASA,,,CON_60S2H2D4S_P0-5_LDV,15547.24,2244.09,0.000,NO
J43,CONN8_210HP1080BR1-CONN8_210-HA,,,HEADER1X8XE,5200.00,2785.43,270.000,NO
J45,CONN60_101062636003K02LF-CONN6A,,,HSD_M60D4H2D_P2-54W2-54_LDHXB,9387.80,17148.90,270.000,NO
J59,SCONN75K_APCI0155P004A-SCONN75A,,,CON_F67S2H2D2S_P0-5W7-55_LUVXB_H270,6825.12,1852.36,0.000,NO
J63,"PICOPROBE_BXA-DELTA-L 4.0,SMLFA",,,TRIANG_LAUNCH_3PXB,14885.81,184.89,180.000,NO
J64,"PICOPROBE_BXA-DELTA-L 4.0,SMLFA",,,TRIANG_LAUNCH_3PXB,14885.81,84.89,0.000,YES
J65,"PICOPROBE_BXA-DELTA-L 4.0,SMLFA",,,TRIANG_LAUNCH_3PXB,14885.81,-15.11,180.000,NO
J66,"PICOPROBE_BXA-DELTA-L 4.0,SMLFA",,,TRIANG_LAUNCH_3PXB,14885.81,-215.11,180.000,NO
J67,"PICOPROBE_BXA-DELTA-L 4.0,SMLFA",,,TRIANG_LAUNCH_3PXB,9868.30,185.00,180.000,NO
J68,"PICOPROBE_BXA-DELTA-L 4.0,SMLFA",,,TRIANG_LAUNCH_3PXB,9868.30,85.00,0.000,YES
J69,"PICOPROBE_BXA-DELTA-L 4.0,SMLFA",,,TRIANG_LAUNCH_3PXB,13358.21,184.89,0.000,NO
J70,"PICOPROBE_BXA-DELTA-L 4.0,SMLFA",,,TRIANG_LAUNCH_3PXB,13358.21,84.89,180.000,YES
J71,"PICOPROBE_BXA-DELTA-L 4.0,SMLFA",,,TRIANG_LAUNCH_3PXB,13358.21,-15.11,0.000,NO
J72,"PICOPROBE_BXA-DELTA-L 4.0,SMLFA",,,TRIANG_LAUNCH_3PXB,13358.21,-215.11,0.000,NO
J73,"PICOPROBE_BXA-DELTA-L 4.0,SMLFA",,,TRIANG_LAUNCH_3PXB,8340.70,185.00,0.000,NO
J74,"PICOPROBE_BXA-DELTA-L 4.0,SMLFA",,,TRIANG_LAUNCH_3PXB,8340.70,85.00,180.000,YES
J75,"PICOPROBE_BXA-DELTA-L 4.0,SMLFA",,,TRIANG_LAUNCH_3PXB,10265.02,184.89,0.000,NO
J76,"PICOPROBE_BXA-DELTA-L 4.0,SMLFA",,,TRIANG_LAUNCH_3PXB,10265.02,84.89,180.000,YES
J77,"PICOPROBE_BXA-DELTA-L 4.0,SMLFA",,,TRIANG_LAUNCH_3PXB,10265.02,-15.11,0.000,NO
J78,"PICOPROBE_BXA-DELTA-L 4.0,SMLFA",,,TRIANG_LAUNCH_3PXB,10265.02,-215.11,0.000,NO
J79,"PICOPROBE_BXA-DELTA-L 4.0,SMLFA",,,TRIANG_LAUNCH_3PXB,7171.10,-115.00,0.000,NO
J80,"PICOPROBE_BXA-DELTA-L 4.0,SMLFA",,,TRIANG_LAUNCH_3PXB,7171.10,-215.00,180.000,YES
J81,"PICOPROBE_BXA-DELTA-L 4.0,SMLFA",,,TRIANG_LAUNCH_3PXB,12962.22,184.89,180.000,NO
J82,"PICOPROBE_BXA-DELTA-L 4.0,SMLFA",,,TRIANG_LAUNCH_3PXB,12962.22,84.89,0.000,YES
J83,"PICOPROBE_BXA-DELTA-L 4.0,SMLFA",,,TRIANG_LAUNCH_3PXB,12962.22,-15.11,180.000,NO
J84,"PICOPROBE_BXA-DELTA-L 4.0,SMLFA",,,TRIANG_LAUNCH_3PXB,12962.22,-215.11,180.000,NO
J85,"PICOPROBE_BXA-DELTA-L 4.0,SMLFA",,,TRIANG_LAUNCH_3PXB,9868.30,-115.00,180.000,NO
J86,"PICOPROBE_BXA-DELTA-L 4.0,SMLFA",,,TRIANG_LAUNCH_3PXB,9868.30,-215.00,0.000,YES
J90,SCONN56_123276793-SCONN56_1-23A,,,CON_F56S2H4D_P0-6W4-6_LUHXA,9224.41,1990.55,180.000,NO
J100,SCONN20_513860200CV01-SCONN20_A,,,HEADER2X10SBHXB,704.72,2047.24,0.000,NO
J104,CONN14_210HP207GBR1-CONN14_210A,,,HEADER2X7XD,16796.46,1756.69,0.000,NO
J105,CONN112_10137002101LF-CONN112_A,,,HSD_F112D8_P2W1-2_RDH,15698.82,17342.12,0.000,NO
J106,CONN112_10137002101LF-CONN112_A,,,HSD_F112D8_P2W1-2_RDH,15029.53,17342.12,0.000,NO
J107,CONN112_10137002101LF-CONN112_A,,,HSD_F112D8_P2W1-2_RDH,13057.09,17342.12,0.000,NO
J108,CONN112_10137002101LF-CONN112_A,,,HSD_F112D8_P2W1-2_RDH,12387.80,17342.12,0.000,NO
J109,CONN112_10137002101LF-CONN112_A,,,HSD_F112D8_P2W1-2_RDH,5620.08,17342.12,0.000,NO
J110,CONN112_10137002101LF-CONN112_A,,,HSD_F112D8_P2W1-2_RDH,4950.79,17342.12,0.000,NO
J111,CONN112_10137002101LF-CONN112_A,,,HSD_F112D8_P2W1-2_RDH,2978.35,17342.12,0.000,NO
J112,CONN160_10131762101LF-CONN160_A,,,HSD_F160D8_P2W1-2_RDH,2309.06,17342.12,0.000,NO
J114,"PICOPROBE_BXA-DELTA-L 4.0,SMLFA",,,TRIANG_LAUNCH_3PXB,13358.21,-315.11,180.000,YES
J115,"PICOPROBE_BXA-DELTA-L 4.0,SMLFA",,,TRIANG_LAUNCH_3PXB,13358.21,-115.11,180.000,YES
J116,"PICOPROBE_BXA-DELTA-L 4.0,SMLFA",,,TRIANG_LAUNCH_3PXB,14885.81,-315.11,0.000,YES
J117,"PICOPROBE_BXA-DELTA-L 4.0,SMLFA",,,TRIANG_LAUNCH_3PXB,14885.81,-115.11,0.000,YES
J118,"PICOPROBE_BXA-DELTA-L 4.0,SMLFA",,,TRIANG_LAUNCH_3PXB,10265.02,-315.11,180.000,YES
J119,"PICOPROBE_BXA-DELTA-L 4.0,SMLFA",,,TRIANG_LAUNCH_3PXB,12962.22,-115.11,0.000,YES
J120,"PICOPROBE_BXA-DELTA-L 4.0,SMLFA",,,TRIANG_LAUNCH_3PXB,12962.22,-315.11,0.000,YES
J121,"PICOPROBE_BXA-DELTA-L 4.0,SMLFA",,,TRIANG_LAUNCH_3PXB,10265.02,-115.11,180.000,YES
J122,CONN1_10165288101LF-CONN1_1016A,,,CON_GUIDE-F1XG,4410.43,16982.68,180.000,NO
J123,CONN1_10165288101LF-CONN1_1016A,,,CON_GUIDE-F1XG,14164.37,16982.67,180.000,NO
JP15_23,"TP_TP_BOM ONLY-NA,TP12_BOM",,,TP30,19782.35,18486.99,0.000,NO
JP16_23,"TP_TP_BOM ONLY-NA,TP12_BOM",,,TP30,18892.50,18432.18,0.000,NO
JP4003_12,"TP_TP_BOM ONLY-NA,TP12_BOM",,,TP30,19138.34,18505.36,0.000,NO
JP4,CONN3_210HP1030BR1-CONN3_210-HA,,,HEADER1X3XG,10414.35,1633.57,0.000,NO
JP7,CONN3_210HP1030BR1-CONN3_210-HB,,,HEADER1X3XG,17714.57,16246.46,180.000,NO
JP9,CONN3_210HP1030BR1-CONN3_210-HA,,,HEADER1X3XG,10562.25,1631.31,0.000,NO
JP10,CONN3_210HP1030BR1-CONN3_210-HB,,,HEADER1X3XG,10999.70,17225.70,0.000,NO
JP15,CONN3_210HP1030BR1-CONN3_210-HB,,,HEADER1X3XG,4985.63,6070.67,90.000,NO
JP16,CONN3_210HP1030BR1-CONN3_210-HB,,,HEADER1X3XG,4735.00,2463.62,90.000,NO
JP4003,CONN3_210HP1030BR1-CONN3_210-HB,,,HEADER1X3XG,6885.00,16219.00,0.000,NO
L1,Q_INDUCTOR_SMLF-FCM2012KF-601TA,FCM2012KF-601T/0.5A,,L0805,10415.00,3858.62,90.000,YES
L2,Q_INDUCTOR_SMLF-BLM15PX121SN1DA,NA,,L0402,12880.20,2690.52,90.000,YES
L3,Q_INDUCTOR_SMLF-BLM18SG331TN1DA,BLM18SG331TN1D/1.5A,,L0603,9064.93,4793.04,270.000,YES
L4,Q_INDUCTOR_SMLF-BLM18SG331TN1DA,BLM18SG331TN1D/1.5A,,L0603,9134.01,4788.04,270.000,YES
L10,Q_INDUCTOR_SMLF-BLM18PG121SN1DA,NA,,L0603,13898.50,2301.52,0.000,YES
L13,Q_INDUCTOR_SMLF-FCM2012KF-601TA,FCM2012KF-601T/0.5A,,L0805,9413.06,3822.23,180.000,YES
L14,Q_INDUCTOR_SMLF-FCM2012KF-601TA,FCM2012KF-601T/0.5A,,L0805,10302.92,4059.13,0.000,YES
L15,Q_INDUCTOR_SMLF-BLM18PG300SN1DA,NA,,L0603,1837.67,4168.27,0.000,NO
L16,Q_INDUCTOR_SMLF-BLM18PG300SN1DB,BLM18PG300SN1D,,L0603,787.96,4421.83,0.000,NO
L17,Q_INDUCTOR_SMLF-FCM2012KF-601TA,FCM2012KF-601T/0.5A,,L0805,9375.70,9674.42,0.000,YES
L18,Q_INDUCTOR_SMLF-BLM15PX121SN1DB,BLM15PX121SN1D/2A,,L0402,4996.80,872.92,90.000,NO
L19,Q_INDUCTOR_SMLF-FCM2012KF-601TA,FCM2012KF-601T/0.5A,,L0805,4138.40,16433.04,180.000,YES
L20,Q_INDUCTOR_SMLF-FCM2012KF-601TA,FCM2012KF-601T/0.5A,,L0805,4139.10,16351.32,180.000,YES
ME2,"ME_DUMMY_SYMBOL-PICKUP_SMDC20,A",,,PICKUP_SMDC20,3061.90,5071.50,0.000,NO
ME3,"ME_DUMMY_SYMBOL-PICKUP_SMDC20,A",,,PICKUP_SMDC20,3812.00,5075.40,0.000,YES
ME4,"ME_DUMMY_SYMBOL-PICKUP_SMDC20,A",,,PICKUP_SMDC20,16059.80,1385.32,0.000,YES
ME9,"ME_DUMMY_SYMBOL-PICKUP_SMDC20,A",,,PICKUP_SMDC20,2581.10,14924.00,0.000,YES
ME10,"ME_DUMMY_SYMBOL-PICKUP_SMDC20,A",,,PICKUP_SMDC20,9338.79,11698.74,0.000,NO
ME11,"ME_DUMMY_SYMBOL-PICKUP_SMDC20,A",,,PICKUP_SMDC20,13150.40,15232.00,0.000,YES
ME12,"ME_DUMMY_SYMBOL-PICKUP_SMDC20,A",,,PICKUP_SMDC20,2579.90,14922.80,0.000,NO
ME13,"ME_DUMMY_SYMBOL-PICKUP_SMDC20,A",,,PICKUP_SMDC20,15408.20,4769.90,0.000,NO
ME14,"ME_DUMMY_SYMBOL-PICKUP_SMDC20,A",,,PICKUP_SMDC20,14836.10,5153.90,0.000,YES
ME15,"ME_DUMMY_SYMBOL-PICKUP_SMDC20,A",,,PICKUP_SMDC20,15916.00,15190.90,0.000,NO
ME17,ME_DUMMY_SYMBOL-QUANTA_LOGO_7XA,,,QUANTA_LOGO_7X26,15504.49,15319.84,0.000,NO
ME18,"ME_DUMMY_SYMBOL-WEEE,MECH,EMPTA",,,WEEE,13573.39,15317.04,0.000,NO
ME20,"ME_DUMMY_SYMBOL-PB-E1_SMALL,MEA",,,PB-E1_SMALL,15230.29,15537.14,0.000,NO
ME21,ME_DUMMY_SYMBOL-PCB_VENDOR_LOGA,,,PCB_VENDOR_LOGO_15X8,8988.60,14407.12,0.000,NO
ME22,"ME_DUMMY_SYMBOL-SNLABEL_27X6,MA",,,SNLABEL_27X6,8825.30,14888.82,0.000,NO
ME27,"ME_DUMMY_SYMBOL-CBS_3X558-8,MEA",,,CBS_3X558-8,9804.49,21284.83,270.000,NO
ME28,ME_DUMMY_SYMBOL-EFI BIOS LABELA,,,BIOS-BMCLABEL_10-5X10-5,17142.80,15585.70,0.000,NO
ME29,"ME_DUMMY_SYMBOL-SNLABEL_15X5,MA",,,SNLABEL_15X5,1240.29,1904.94,0.000,NO
OSC1,"Q_OSC4P_SMLF-50MHZ,OSC,BF65000A",,,OSC4_XP,8459.15,1028.01,90.000,NO
OSC2,"Q_OSC4P_SMLF-25MHZ,OSC,BF62500A",,,OSC4_FJ2500009,7677.20,4433.62,270.000,NO
PC189_P0_1,"Q_CAP_0402-3300PF,50V,10%,X7R,A",3300PF,10%,C0402,16381.81,6584.75,180.000,NO
PC190_P0_2,"Q_CAP_0402-3300PF,50V,10%,X7R,A",3300PF,10%,C0402,16381.81,6924.75,180.000,NO
PC191_P0_1,"Q_CAP_C0402-1UF,16V,10%,X6S,CHA",1UF,10%,C0402,16540.32,6555.09,270.000,NO
PC192_P0_2,"Q_CAP_C0402-1UF,16V,10%,X6S,CHA",1UF,10%,C0402,16540.32,6895.09,270.000,NO
PC195_P0_1,"Q_CAP_C0805-22UF,16V,20%,X6S,CA",22UF,20%,C0805_H57,16379.10,6597.05,0.000,YES
PC196_P0_2,"Q_CAP_C0805-22UF,16V,20%,X6S,CA",22UF,20%,C0805_H57,16379.10,6937.05,0.000,YES
PC197_P0_1,"Q_CAP_C0805-22UF,16V,20%,X6S,CA",22UF,20%,C0805_H57,16379.10,6681.11,0.000,YES
PC198_P0_2,"Q_CAP_C0805-22UF,16V,20%,X6S,CA",22UF,20%,C0805_H57,16379.10,7021.11,0.000,YES
PC199_P0_1,"Q_CAP_C0402-100NF,50V,10%,X7R,A",100NF,10%,C0402,16039.60,7225.82,0.000,NO
PC202_P0_1,"Q_CAP_C0805-22UF,4V,20%,X6S,CHA",22UF,20%,C0805_H61,16059.55,6855.92,180.000,YES
PC203_P0_2,"Q_CAP_C0805-22UF,4V,20%,X6S,CHA",22UF,20%,C0805_H61,16059.55,6928.62,180.000,YES
PC204_P0_1,"Q_CAP_C0805-22UF,4V,20%,X6S,CHA",22UF,20%,C0805_H61,16059.55,6588.62,180.000,YES
PC205_P0_2,"Q_CAP_C0805-22UF,4V,20%,X6S,CHA",22UF,20%,C0805_H61,16059.55,7195.92,180.000,YES
PC228_P0_8,"Q_CAP_C0402-2.2UF,10V,10%,X6S,A",2.2UF,10%,C0402,15045.88,13493.16,270.000,NO
PC229_P0_7,"Q_CAP_C0402-2.2UF,10V,10%,X6S,A",2.2UF,10%,C0402,12798.12,13495.52,270.000,NO
PC230_P0_8,"Q_CAP_0402-3300PF,50V,10%,X7R,A",3300PF,10%,C0402,15371.10,13504.68,270.000,NO
PC231_P0_7,"Q_CAP_0402-3300PF,50V,10%,X7R,A",3300PF,10%,C0402,13123.46,13523.47,270.000,NO
PC232_P0_8,"Q_CAP_C0402-1UF,16V,10%,X6S,CHA",1UF,10%,C0402,15327.27,13504.68,270.000,NO
PC233_P0_7,"Q_CAP_C0402-1UF,16V,10%,X6S,CHA",1UF,10%,C0402,13081.40,13504.14,270.000,NO
PC236_P0_8,"Q_CAP_C0805-22UF,16V,20%,X6S,CA",22UF,20%,C0805_H57,15234.68,13653.76,270.000,YES
PC237_P0_7,"Q_CAP_C0805-22UF,16V,20%,X6S,CA",22UF,20%,C0805_H57,13065.88,13501.44,90.000,YES
PC238_P0_8,"Q_CAP_C0805-22UF,16V,20%,X6S,CA",22UF,20%,C0805_H57,15314.56,13501.44,90.000,YES
PC239_P0_7,"Q_CAP_C0805-22UF,16V,20%,X6S,CA",22UF,20%,C0805_H57,12996.85,13653.87,270.000,YES
PC240_P0_8,"Q_CAP_C0805-22UF,16V,20%,X6S,CA",22UF,20%,C0805_H57,15230.78,13501.44,90.000,YES
PC241_P0_7,"Q_CAP_C0805-22UF,16V,20%,X6S,CA",22UF,20%,C0805_H57,12981.82,13501.44,90.000,YES
PC242_P0_8,"Q_CAP_C0402-1UF,16V,10%,X6S,CHA",1UF,10%,C0402,15377.46,13049.18,90.000,NO
PC243_P0_7,"Q_CAP_C0402-1UF,16V,10%,X6S,CHA",1UF,10%,C0402,13037.61,13145.52,270.000,YES
PC244_P0_8,"Q_CAP_C0805-22UF,4V,20%,X6S,CHA",22UF,20%,C0805_H61,15205.28,13055.20,270.000,YES
PC245_P0_7,"Q_CAP_C0805-22UF,4V,20%,X6S,CHA",22UF,20%,C0805_H61,12967.22,13134.70,270.000,YES
PC246_P0_8,"Q_CAP_C0805-22UF,4V,20%,X6S,CHA",22UF,20%,C0805_H61,15137.18,13054.70,270.000,YES
PC247_P0_7,"Q_CAP_C0805-22UF,4V,20%,X6S,CHA",22UF,20%,C0805_H61,12894.59,13134.98,270.000,YES
PC250_P0_6,"Q_CAP_C0402-2.2UF,10V,10%,X6S,A",2.2UF,10%,C0402,13118.20,13265.18,270.000,NO
PC251_P0_5,"Q_CAP_C0402-2.2UF,10V,10%,X6S,A",2.2UF,10%,C0402,14724.60,13265.18,270.000,NO
PC252_P0_6,"Q_CAP_0402-3300PF,50V,10%,X7R,A",3300PF,10%,C0402,13430.44,13366.75,270.000,NO
PC253_P0_5,"Q_CAP_0402-3300PF,50V,10%,X7R,A",3300PF,10%,C0402,15029.79,13388.37,0.000,NO
PC254_P0_6,"Q_CAP_C0402-1UF,16V,10%,X6S,CHA",1UF,10%,C0402,13399.46,13276.17,270.000,NO
PC255_P0_5,"Q_CAP_C0402-1UF,16V,10%,X6S,CHA",1UF,10%,C0402,15005.86,13276.17,270.000,NO
PC258_P0_6,"Q_CAP_C0805-22UF,16V,20%,X6S,CA",22UF,20%,C0805_H57,13318.13,13425.89,270.000,YES
PC259_P0_5,"Q_CAP_C0805-22UF,16V,20%,X6S,CA",22UF,20%,C0805_H57,14909.50,13273.46,90.000,YES
PC260_P0_6,"Q_CAP_C0805-22UF,16V,20%,X6S,CA",22UF,20%,C0805_H57,13387.16,13273.46,90.000,YES
PC261_P0_5,"Q_CAP_C0805-22UF,16V,20%,X6S,CA",22UF,20%,C0805_H57,14992.47,13274.06,90.000,YES
PC262_P0_6,"Q_CAP_C0805-22UF,16V,20%,X6S,CA",22UF,20%,C0805_H57,13303.10,13273.46,90.000,YES
PC263_P0_5,"Q_CAP_C0805-22UF,16V,20%,X6S,CA",22UF,20%,C0805_H57,14913.40,13433.78,270.000,YES
PC266_P0_6,"Q_CAP_C0805-22UF,4V,20%,X6S,CHA",22UF,20%,C0805_H61,13400.59,12925.12,270.000,YES
PC267_P0_5,"Q_CAP_C0805-22UF,4V,20%,X6S,CHA",22UF,20%,C0805_H61,14724.49,12925.12,270.000,YES
PC268_P0_6,"Q_CAP_C0805-22UF,4V,20%,X6S,CHA",22UF,20%,C0805_H61,13125.29,12925.12,270.000,YES
PC269_P0_5,"Q_CAP_C0805-22UF,4V,20%,X6S,CHA",22UF,20%,C0805_H61,14999.12,12939.05,270.000,YES
PC272_P0_4,"Q_CAP_C0402-2.2UF,10V,10%,X6S,A",2.2UF,10%,C0402,14403.32,13130.92,270.000,NO
PC273_P0_3,"Q_CAP_C0402-2.2UF,10V,10%,X6S,A",2.2UF,10%,C0402,14082.04,13130.92,270.000,NO
PC274_P0_4,"Q_CAP_0402-3300PF,50V,10%,X7R,A",3300PF,10%,C0402,14703.81,13195.92,0.000,NO
PC275_P0_3,"Q_CAP_0402-3300PF,50V,10%,X7R,A",3300PF,10%,C0402,14382.21,13305.33,0.000,NO
PC276_P0_4,"Q_CAP_C0402-1UF,16V,10%,X6S,CHA",1UF,10%,C0402,14684.58,13141.91,270.000,NO
PC277_P0_3,"Q_CAP_C0402-1UF,16V,10%,X6S,CHA",1UF,10%,C0402,14363.30,13141.91,270.000,NO
PC280_P0_4,"Q_CAP_C0805-22UF,16V,20%,X6S,CA",22UF,20%,C0805_H57,14672.28,13139.20,90.000,YES
PC281_P0_3,"Q_CAP_C0805-22UF,16V,20%,X6S,CA",22UF,20%,C0805_H57,14266.94,13139.20,90.000,YES
PC282_P0_4,"Q_CAP_C0805-22UF,16V,20%,X6S,CA",22UF,20%,C0805_H57,14595.83,13289.23,270.000,YES
PC283_P0_3,"Q_CAP_C0805-22UF,16V,20%,X6S,CA",22UF,20%,C0805_H57,14351.00,13139.20,90.000,YES
PC284_P0_4,"Q_CAP_C0805-22UF,16V,20%,X6S,CA",22UF,20%,C0805_H57,14588.22,13139.20,90.000,YES
PC285_P0_3,"Q_CAP_C0805-22UF,16V,20%,X6S,CA",22UF,20%,C0805_H57,14281.97,13289.96,270.000,YES
PC288_P0_4,"Q_CAP_C0805-22UF,4V,20%,X6S,CHA",22UF,20%,C0805_H61,14602.42,12791.79,270.000,YES
PC289_P0_3,"Q_CAP_C0805-22UF,4V,20%,X6S,CHA",22UF,20%,C0805_H61,14092.95,12791.79,270.000,YES
PC290_P0_4,"Q_CAP_C0805-22UF,4V,20%,X6S,CHA",22UF,20%,C0805_H61,14518.42,12791.79,270.000,YES
PC291_P0_3,"Q_CAP_C0805-22UF,4V,20%,X6S,CHA",22UF,20%,C0805_H61,14387.34,12791.79,270.000,YES
PC294_P0_2,"Q_CAP_C0402-2.2UF,10V,10%,X6S,A",2.2UF,10%,C0402,13760.76,13130.92,270.000,NO
PC295_P0_1,"Q_CAP_C0402-2.2UF,10V,10%,X6S,A",2.2UF,10%,C0402,13438.58,13130.92,270.000,NO
PC296_P0_2,"Q_CAP_0402-3300PF,50V,10%,X7R,A",3300PF,10%,C0402,14052.96,13300.42,0.000,NO
PC297_P0_1,"Q_CAP_0402-3300PF,50V,10%,X7R,A",3300PF,10%,C0402,13737.37,13301.42,0.000,NO
PC298_P0_2,"Q_CAP_C0402-1UF,16V,10%,X6S,CHA",1UF,10%,C0402,14042.02,13141.91,270.000,NO
PC299_P0_1,"Q_CAP_C0402-1UF,16V,10%,X6S,CHA",1UF,10%,C0402,13720.74,13141.91,270.000,NO
PC302_P0_2,"Q_CAP_C0805-22UF,16V,20%,X6S,CA",22UF,20%,C0805_H57,13960.69,13289.96,270.000,YES
PC303_P0_1,"Q_CAP_C0805-22UF,16V,20%,X6S,CA",22UF,20%,C0805_H57,13621.74,13135.43,90.000,YES
PC304_P0_2,"Q_CAP_C0805-22UF,16V,20%,X6S,CA",22UF,20%,C0805_H57,14029.72,13135.43,90.000,YES
PC305_P0_1,"Q_CAP_C0805-22UF,16V,20%,X6S,CA",22UF,20%,C0805_H57,13706.10,13135.43,90.000,YES
PC306_P0_2,"Q_CAP_C0805-22UF,16V,20%,X6S,CA",22UF,20%,C0805_H57,13945.66,13135.43,90.000,YES
PC307_P0_1,"Q_CAP_C0805-22UF,16V,20%,X6S,CA",22UF,20%,C0805_H57,13639.41,13289.96,270.000,YES
PC308_P0_1,"Q_CAP_C0402-100NF,50V,10%,X7R,A",100NF,10%,C0402,14448.52,12799.61,270.000,YES
PC310_P0_1,"Q_CAP_C0402-1UF,16V,10%,X6S,CHA",1UF,10%,C0402,14669.84,12799.14,270.000,YES
PC311_P0_2,"Q_CAP_C0805-22UF,4V,20%,X6S,CHA",22UF,20%,C0805_H61,13737.39,12790.29,270.000,YES
PC312_P0_1,"Q_CAP_C0805-22UF,4V,20%,X6S,CHA",22UF,20%,C0805_H61,13608.58,12790.29,270.000,YES
PC313_P0_2,"Q_CAP_C0805-22UF,4V,20%,X6S,CHA",22UF,20%,C0805_H61,14012.35,12791.79,270.000,YES
PC314_P0_1,"Q_CAP_C0805-22UF,4V,20%,X6S,CHA",22UF,20%,C0805_H61,13524.58,12790.29,270.000,YES
PC397_P1_1,"Q_CAP_0402-3300PF,50V,10%,X7R,A",3300PF,10%,C0402,6954.25,13922.15,270.000,NO
PC398_P1_2,"Q_CAP_0402-3300PF,50V,10%,X7R,A",3300PF,10%,C0402,2203.87,13922.99,270.000,NO
PC399_P1_1,"Q_CAP_C0402-1UF,16V,10%,X6S,CHA",1UF,10%,C0402,6913.21,13922.15,270.000,NO
PC400_P1_2,"Q_CAP_C0402-1UF,16V,10%,X6S,CHA",1UF,10%,C0402,2160.90,13922.99,270.000,NO
PC403_P1_1,"Q_CAP_C0805-22UF,16V,20%,X6S,CA",22UF,20%,C0805_H57,6816.77,13921.23,90.000,YES
PC404_P1_2,"Q_CAP_C0805-22UF,16V,20%,X6S,CA",22UF,20%,C0805_H57,2062.01,13919.98,90.000,YES
PC405_P1_1,"Q_CAP_C0805-22UF,16V,20%,X6S,CA",22UF,20%,C0805_H57,6900.83,13926.23,90.000,YES
PC406_P1_2,"Q_CAP_C0805-22UF,16V,20%,X6S,CA",22UF,20%,C0805_H57,2146.07,13919.98,90.000,YES
PC408_P1_2,"Q_CAP_C0402-1UF,16V,10%,X6S,CHA",1UF,10%,C0402,2145.80,13571.94,270.000,YES
PC410_P1_1,"Q_CAP_C0805-22UF,4V,20%,X6S,CHA",22UF,20%,C0805_H61,6632.88,13580.39,270.000,YES
PC411_P1_2,"Q_CAP_C0805-22UF,4V,20%,X6S,CHA",22UF,20%,C0805_H61,2199.80,13568.91,270.000,YES
PC412_P1_1,"Q_CAP_C0805-22UF,4V,20%,X6S,CHA",22UF,20%,C0805_H61,6908.26,13580.39,270.000,YES
PC413_P1_2,"Q_CAP_C0805-22UF,4V,20%,X6S,CHA",22UF,20%,C0805_H61,1882.15,13580.14,270.000,YES
PC442_P1_1,"Q_CAP_0402-3300PF,50V,10%,X7R,A",3300PF,10%,C0402,1999.41,6330.73,90.000,NO
PC443_P1_2,"Q_CAP_0402-3300PF,50V,10%,X7R,A",3300PF,10%,C0402,1999.41,5990.73,90.000,NO
PC444_P1_1,"Q_CAP_C0402-1UF,16V,10%,X6S,CHA",1UF,10%,C0402,2157.92,6301.07,0.000,NO
PC445_P1_2,"Q_CAP_C0402-1UF,16V,10%,X6S,CHA",1UF,10%,C0402,2157.92,5961.07,0.000,NO
PC448_P1_1,"Q_CAP_C0805-22UF,16V,20%,X6S,CA",22UF,20%,C0805_H57,2160.63,6288.77,180.000,YES
PC449_P1_2,"Q_CAP_C0805-22UF,16V,20%,X6S,CA",22UF,20%,C0805_H57,2160.63,5948.77,180.000,YES
PC450_P1_1,"Q_CAP_C0805-22UF,16V,20%,X6S,CA",22UF,20%,C0805_H57,2160.63,6204.71,180.000,YES
PC451_P1_2,"Q_CAP_C0805-22UF,16V,20%,X6S,CA",22UF,20%,C0805_H57,2160.63,5864.71,180.000,YES
PC452_P1_1,"Q_CAP_C0402-100NF,50V,10%,X7R,A",100NF,10%,C0402,2480.08,5659.76,180.000,NO
PC455_P1_1,"Q_CAP_C0805-22UF,4V,20%,X6S,CHA",22UF,20%,C0805_H61,2480.18,6026.90,0.000,YES
PC456_P1_2,"Q_CAP_C0805-22UF,4V,20%,X6S,CHA",22UF,20%,C0805_H61,2480.18,5686.90,0.000,YES
PC457_P1_1,"Q_CAP_C0805-22UF,4V,20%,X6S,CHA",22UF,20%,C0805_H61,2480.18,6294.20,0.000,YES
PC458_P1_2,"Q_CAP_C0805-22UF,4V,20%,X6S,CHA",22UF,20%,C0805_H61,2480.18,5954.20,0.000,YES
PC481_P1_8,"Q_CAP_C0402-2.2UF,10V,10%,X6S,A",2.2UF,10%,C0402,5284.47,13493.16,270.000,NO
PC482_P1_7,"Q_CAP_C0402-2.2UF,10V,10%,X6S,A",2.2UF,10%,C0402,3035.51,13493.16,270.000,NO
PC483_P1_8,"Q_CAP_0402-3300PF,50V,10%,X7R,A",3300PF,10%,C0402,5609.69,13504.68,270.000,NO
PC484_P1_7,"Q_CAP_0402-3300PF,50V,10%,X7R,A",3300PF,10%,C0402,3362.05,13523.47,270.000,NO
PC485_P1_8,"Q_CAP_C0402-1UF,16V,10%,X6S,CHA",1UF,10%,C0402,5565.86,13504.68,270.000,NO
PC486_P1_7,"Q_CAP_C0402-1UF,16V,10%,X6S,CHA",1UF,10%,C0402,3317.73,13504.53,270.000,NO
PC489_P1_8,"Q_CAP_C0805-22UF,16V,20%,X6S,CA",22UF,20%,C0805_H57,5469.37,13501.44,90.000,YES
PC490_P1_7,"Q_CAP_C0805-22UF,16V,20%,X6S,CA",22UF,20%,C0805_H57,3235.44,13653.87,270.000,YES
PC491_P1_8,"Q_CAP_C0805-22UF,16V,20%,X6S,CA",22UF,20%,C0805_H57,5473.27,13661.76,270.000,YES
PC492_P1_7,"Q_CAP_C0805-22UF,16V,20%,X6S,CA",22UF,20%,C0805_H57,3304.47,13501.44,90.000,YES
PC493_P1_8,"Q_CAP_C0805-22UF,16V,20%,X6S,CA",22UF,20%,C0805_H57,5553.43,13501.44,90.000,YES
PC494_P1_7,"Q_CAP_C0805-22UF,16V,20%,X6S,CA",22UF,20%,C0805_H57,3220.41,13501.44,90.000,YES
PC495_P1_8,"Q_CAP_C0402-1UF,16V,10%,X6S,CHA",1UF,10%,C0402,5300.52,13141.06,270.000,YES
PC496_P1_7,"Q_CAP_C0402-1UF,16V,10%,X6S,CHA",1UF,10%,C0402,3286.20,13065.52,270.000,YES
PC497_P1_8,"Q_CAP_C0805-22UF,4V,20%,X6S,CHA",22UF,20%,C0805_H61,5370.77,13134.70,270.000,YES
PC498_P1_7,"Q_CAP_C0805-22UF,4V,20%,X6S,CHA",22UF,20%,C0805_H61,3143.18,13054.98,270.000,YES
PC499_P1_8,"Q_CAP_C0805-22UF,4V,20%,X6S,CHA",22UF,20%,C0805_H61,5439.07,13134.50,270.000,YES
PC500_P1_7,"Q_CAP_C0805-22UF,4V,20%,X6S,CHA",22UF,20%,C0805_H61,3215.81,13054.70,270.000,YES
PC503_P1_6,"Q_CAP_C0402-2.2UF,10V,10%,X6S,A",2.2UF,10%,C0402,3356.79,13265.18,270.000,NO
PC504_P1_5,"Q_CAP_C0402-2.2UF,10V,10%,X6S,A",2.2UF,10%,C0402,4963.19,13265.18,270.000,NO
PC505_P1_6,"Q_CAP_0402-3300PF,50V,10%,X7R,A",3300PF,10%,C0402,3669.03,13366.75,270.000,NO
PC506_P1_5,"Q_CAP_0402-3300PF,50V,10%,X7R,A",3300PF,10%,C0402,5268.38,13388.37,0.000,NO
PC507_P1_6,"Q_CAP_C0402-1UF,16V,10%,X6S,CHA",1UF,10%,C0402,3638.05,13276.17,270.000,NO
PC508_P1_5,"Q_CAP_C0402-1UF,16V,10%,X6S,CHA",1UF,10%,C0402,5244.45,13276.17,270.000,NO
PC511_P1_6,"Q_CAP_C0805-22UF,16V,20%,X6S,CA",22UF,20%,C0805_H57,3625.75,13273.46,90.000,YES
PC512_P1_5,"Q_CAP_C0805-22UF,16V,20%,X6S,CA",22UF,20%,C0805_H57,5148.09,13273.46,90.000,YES
PC513_P1_6,"Q_CAP_C0805-22UF,16V,20%,X6S,CA",22UF,20%,C0805_H57,3556.72,13425.89,270.000,YES
PC514_P1_5,"Q_CAP_C0805-22UF,16V,20%,X6S,CA",22UF,20%,C0805_H57,5151.99,13433.78,270.000,YES
PC515_P1_6,"Q_CAP_C0805-22UF,16V,20%,X6S,CA",22UF,20%,C0805_H57,3541.69,13273.46,90.000,YES
PC516_P1_5,"Q_CAP_C0805-22UF,16V,20%,X6S,CA",22UF,20%,C0805_H57,5232.15,13273.46,90.000,YES
PC519_P1_6,"Q_CAP_C0805-22UF,4V,20%,X6S,CHA",22UF,20%,C0805_H61,3359.88,12925.12,270.000,YES
PC520_P1_5,"Q_CAP_C0805-22UF,4V,20%,X6S,CHA",22UF,20%,C0805_H61,4962.28,12925.12,270.000,YES
PC521_P1_6,"Q_CAP_C0805-22UF,4V,20%,X6S,CHA",22UF,20%,C0805_H61,3635.18,12925.12,270.000,YES
PC522_P1_5,"Q_CAP_C0805-22UF,4V,20%,X6S,CHA",22UF,20%,C0805_H61,5238.97,12925.12,270.000,YES
PC525_P1_4,"Q_CAP_C0402-2.2UF,10V,10%,X6S,A",2.2UF,10%,C0402,4641.91,13130.92,270.000,NO
PC526_P1_3,"Q_CAP_C0402-2.2UF,10V,10%,X6S,A",2.2UF,10%,C0402,4320.63,13130.92,270.000,NO
PC527_P1_4,"Q_CAP_0402-3300PF,50V,10%,X7R,A",3300PF,10%,C0402,4942.40,13195.92,0.000,NO
PC528_P1_3,"Q_CAP_0402-3300PF,50V,10%,X7R,A",3300PF,10%,C0402,4620.80,13305.33,0.000,NO
PC529_P1_4,"Q_CAP_C0402-1UF,16V,10%,X6S,CHA",1UF,10%,C0402,4923.17,13141.91,270.000,NO
PC530_P1_3,"Q_CAP_C0402-1UF,16V,10%,X6S,CHA",1UF,10%,C0402,4601.89,13141.91,270.000,NO
PC533_P1_4,"Q_CAP_C0805-22UF,16V,20%,X6S,CA",22UF,20%,C0805_H57,4834.42,13289.23,270.000,YES
PC534_P1_3,"Q_CAP_C0805-22UF,16V,20%,X6S,CA",22UF,20%,C0805_H57,4589.59,13139.20,90.000,YES
PC535_P1_4,"Q_CAP_C0805-22UF,16V,20%,X6S,CA",22UF,20%,C0805_H57,4910.87,13139.20,90.000,YES
PC536_P1_3,"Q_CAP_C0805-22UF,16V,20%,X6S,CA",22UF,20%,C0805_H57,4505.53,13139.20,90.000,YES
PC537_P1_4,"Q_CAP_C0805-22UF,16V,20%,X6S,CA",22UF,20%,C0805_H57,4826.81,13139.20,90.000,YES
PC538_P1_3,"Q_CAP_C0805-22UF,16V,20%,X6S,CA",22UF,20%,C0805_H57,4520.56,13291.63,270.000,YES
PC541_P1_4,"Q_CAP_C0805-22UF,4V,20%,X6S,CHA",22UF,20%,C0805_H61,4758.21,12787.09,270.000,YES
PC542_P1_3,"Q_CAP_C0805-22UF,4V,20%,X6S,CHA",22UF,20%,C0805_H61,4627.13,12787.09,270.000,YES
PC543_P1_4,"Q_CAP_C0805-22UF,4V,20%,X6S,CHA",22UF,20%,C0805_H61,4842.21,12787.09,270.000,YES
PC544_P1_3,"Q_CAP_C0805-22UF,4V,20%,X6S,CHA",22UF,20%,C0805_H61,4332.74,12787.09,270.000,YES
PC558_P1_2,"Q_CAP_C0402-2.2UF,10V,10%,X6S,A",2.2UF,10%,C0402,3999.35,13130.92,270.000,NO
PC559_P1_1,"Q_CAP_C0402-2.2UF,10V,10%,X6S,A",2.2UF,10%,C0402,3677.17,13130.92,270.000,NO
PC560_P1_2,"Q_CAP_0402-3300PF,50V,10%,X7R,A",3300PF,10%,C0402,4291.55,13300.42,0.000,NO
PC561_P1_1,"Q_CAP_0402-3300PF,50V,10%,X7R,A",3300PF,10%,C0402,3975.96,13301.42,0.000,NO
PC562_P1_2,"Q_CAP_C0402-1UF,16V,10%,X6S,CHA",1UF,10%,C0402,4280.61,13141.91,270.000,NO
PC563_P1_1,"Q_CAP_C0402-1UF,16V,10%,X6S,CHA",1UF,10%,C0402,3959.33,13141.91,270.000,NO
PC566_P1_2,"Q_CAP_C0805-22UF,16V,20%,X6S,CA",22UF,20%,C0805_H57,4184.25,13135.43,90.000,YES
PC567_P1_1,"Q_CAP_C0805-22UF,16V,20%,X6S,CA",22UF,20%,C0805_H57,3944.69,13135.43,90.000,YES
PC568_P1_2,"Q_CAP_C0805-22UF,16V,20%,X6S,CA",22UF,20%,C0805_H57,4199.28,13291.63,270.000,YES
PC569_P1_1,"Q_CAP_C0805-22UF,16V,20%,X6S,CA",22UF,20%,C0805_H57,3878.00,13291.63,270.000,YES
PC570_P1_2,"Q_CAP_C0805-22UF,16V,20%,X6S,CA",22UF,20%,C0805_H57,4268.31,13135.43,90.000,YES
PC571_P1_1,"Q_CAP_C0805-22UF,16V,20%,X6S,CA",22UF,20%,C0805_H57,3860.33,13135.43,90.000,YES
PC572_P1_1,"Q_CAP_C0402-100NF,50V,10%,X7R,A",100NF,10%,C0402,4688.31,12794.91,270.000,YES
PC574_P1_1,"Q_CAP_C0402-1UF,16V,10%,X6S,CHA",1UF,10%,C0402,4909.63,12794.44,270.000,YES
PC575_P1_2,"Q_CAP_C0805-22UF,4V,20%,X6S,CHA",22UF,20%,C0805_H61,4252.74,12787.09,270.000,YES
PC576_P1_1,"Q_CAP_C0805-22UF,4V,20%,X6S,CHA",22UF,20%,C0805_H61,3764.37,12785.59,270.000,YES
PC577_P1_2,"Q_CAP_C0805-22UF,4V,20%,X6S,CHA",22UF,20%,C0805_H61,3975.18,12785.59,270.000,YES
PC578_P1_1,"Q_CAP_C0805-22UF,4V,20%,X6S,CHA",22UF,20%,C0805_H61,3848.37,12785.59,270.000,YES
PC602_P0_1,"Q_CAP_0402-3300PF,50V,10%,X7R,A",3300PF,10%,C0402,16565.91,14258.11,270.000,NO
PC603_P0_2,"Q_CAP_0402-3300PF,50V,10%,X7R,A",3300PF,10%,C0402,11891.56,14285.19,270.000,NO
PC604_P0_1,"Q_CAP_C0402-1UF,16V,10%,X6S,CHA",1UF,10%,C0402,16524.87,14258.11,270.000,NO
PC605_P0_2,"Q_CAP_C0402-1UF,16V,10%,X6S,CHA",1UF,10%,C0402,11932.60,14285.19,270.000,NO
PC608_P0_1,"Q_CAP_C0805-22UF,16V,20%,X6S,CA",22UF,20%,C0805_H57,16512.49,14256.19,90.000,YES
PC609_P0_2,"Q_CAP_C0805-22UF,16V,20%,X6S,CA",22UF,20%,C0805_H57,11795.12,14283.27,90.000,YES
PC610_P0_1,"Q_CAP_C0805-22UF,16V,20%,X6S,CA",22UF,20%,C0805_H57,16428.43,14256.19,90.000,YES
PC611_P0_2,"Q_CAP_C0805-22UF,16V,20%,X6S,CA",22UF,20%,C0805_H57,11879.18,14283.27,90.000,YES
PC612_P0_1,"Q_CAP_C0402-100NF,50V,10%,X7R,A",100NF,10%,C0402,16580.26,13902.26,270.000,YES
PC613_P0_2,"Q_CAP_C0402-1UF,16V,10%,X6S,CHA",1UF,10%,C0402,11878.91,13935.24,270.000,YES
PC615_P0_1,"Q_CAP_C0805-22UF,4V,20%,X6S,CHA",22UF,20%,C0805_H61,16244.54,13907.85,270.000,YES
PC616_P0_2,"Q_CAP_C0805-22UF,4V,20%,X6S,CHA",22UF,20%,C0805_H61,11619.31,13943.44,270.000,YES
PC617_P0_1,"Q_CAP_C0805-22UF,4V,20%,X6S,CHA",22UF,20%,C0805_H61,16519.92,13907.85,270.000,YES
PC618_P0_2,"Q_CAP_C0805-22UF,4V,20%,X6S,CHA",22UF,20%,C0805_H61,11932.80,13932.21,270.000,YES
PC621_P1_1,"Q_CAP_C0402-100NF,50V,10%,X7R,A",100NF,10%,C0402,6968.60,13574.80,270.000,YES
PC720_P0_1,"Q_CAP_C0805-22UF,16V,20%,X6S,CA",22UF,20%,C0805_H57,16553.28,14435.36,0.000,NO
PC721_P0_2,"Q_CAP_C0805-22UF,16V,20%,X6S,CA",22UF,20%,C0805_H57,11950.92,14462.12,0.000,NO
PC722_P0_3,"Q_CAP_C0805-22UF,16V,20%,X6S,CA",22UF,20%,C0805_H57,16968.17,14435.05,0.000,NO
PC723_P0_4,"Q_CAP_C0805-22UF,16V,20%,X6S,CA",22UF,20%,C0805_H57,11538.54,14462.44,0.000,NO
PC724_P1_1,"Q_CAP_C0805-22UF,16V,20%,X6S,CA",22UF,20%,C0805_H57,6941.62,14099.40,0.000,NO
PC725_P1_2,"Q_CAP_C0805-22UF,16V,20%,X6S,CA",22UF,20%,C0805_H57,2215.86,14099.15,0.000,NO
PC726_P1_3,"Q_CAP_C0805-22UF,16V,20%,X6S,CA",22UF,20%,C0805_H57,7357.00,14100.25,0.000,NO
PC727_P1_4,"Q_CAP_C0805-22UF,16V,20%,X6S,CA",22UF,20%,C0805_H57,1805.43,14099.15,0.000,NO
PC1173_P0_3,"Q_CAP_0402-3300PF,50V,10%,X7R,A",3300PF,10%,C0402,16951.72,14259.20,270.000,NO
PC1174_P0_4,"Q_CAP_0402-3300PF,50V,10%,X7R,A",3300PF,10%,C0402,11551.17,14285.19,270.000,NO
PC1175_P0_3,"Q_CAP_C0402-1UF,16V,10%,X6S,CHA",1UF,10%,C0402,16908.75,14259.20,270.000,NO
PC1176_P0_4,"Q_CAP_C0402-1UF,16V,10%,X6S,CHA",1UF,10%,C0402,11510.13,14285.19,270.000,NO
PC1179_P0_3,"Q_CAP_C0805-22UF,16V,20%,X6S,CA",22UF,20%,C0805_H57,16893.92,14256.19,90.000,YES
PC1180_P0_4,"Q_CAP_C0805-22UF,16V,20%,X6S,CA",22UF,20%,C0805_H57,11413.69,14283.27,90.000,YES
PC1181_P0_3,"Q_CAP_C0805-22UF,16V,20%,X6S,CA",22UF,20%,C0805_H57,16809.86,14256.19,90.000,YES
PC1182_P0_4,"Q_CAP_C0805-22UF,16V,20%,X6S,CA",22UF,20%,C0805_H57,11497.75,14283.27,90.000,YES
PC1183_P0_3,"Q_CAP_C0402-1UF,16V,10%,X6S,CHA",1UF,10%,C0402,16895.65,13899.65,270.000,YES
PC1183_P0_4,"Q_CAP_C0402-100NF,50V,10%,X7R,A",100NF,10%,C0402,11565.52,13937.85,270.000,YES
PC1185_P0_3,"Q_CAP_C0805-22UF,4V,20%,X6S,CHA",22UF,20%,C0805_H61,16949.54,13896.62,270.000,YES
PC1186_P0_4,"Q_CAP_C0805-22UF,4V,20%,X6S,CHA",22UF,20%,C0805_H61,11505.18,13943.44,270.000,YES
PC1187_P0_3,"Q_CAP_C0805-22UF,4V,20%,X6S,CHA",22UF,20%,C0805_H61,16634.05,13907.85,270.000,YES
PC1188_P0_4,"Q_CAP_C0805-22UF,4V,20%,X6S,CHA",22UF,20%,C0805_H61,11229.80,13943.44,270.000,YES
PC1193_P1_3,"Q_CAP_0402-3300PF,50V,10%,X7R,A",3300PF,10%,C0402,7340.06,13923.24,270.000,NO
PC1194_P1_4,"Q_CAP_0402-3300PF,50V,10%,X7R,A",3300PF,10%,C0402,1818.06,13921.90,270.000,NO
PC1195_P1_3,"Q_CAP_C0402-1UF,16V,10%,X6S,CHA",1UF,10%,C0402,7297.09,13923.24,270.000,NO
PC1196_P1_4,"Q_CAP_C0402-1UF,16V,10%,X6S,CHA",1UF,10%,C0402,1777.02,13921.90,270.000,NO
PC1199_P1_3,"Q_CAP_C0805-22UF,16V,20%,X6S,CA",22UF,20%,C0805_H57,7198.20,13920.23,90.000,YES
PC1200_P1_4,"Q_CAP_C0805-22UF,16V,20%,X6S,CA",22UF,20%,C0805_H57,1764.64,13919.98,90.000,YES
PC1201_P1_3,"Q_CAP_C0805-22UF,16V,20%,X6S,CA",22UF,20%,C0805_H57,7282.26,13920.23,90.000,YES
PC1202_P1_4,"Q_CAP_C0805-22UF,16V,20%,X6S,CA",22UF,20%,C0805_H57,1680.58,13919.98,90.000,YES
PC1203_P1_4,"Q_CAP_C0402-100NF,50V,10%,X7R,A",100NF,10%,C0402,1827.27,13572.01,270.000,YES
PC1204_P1_3,"Q_CAP_C0402-1UF,16V,10%,X6S,CHA",1UF,10%,C0402,7281.99,13572.19,270.000,YES
PC1206_P1_3,"Q_CAP_C0805-22UF,4V,20%,X6S,CHA",22UF,20%,C0805_H61,7335.88,13569.16,270.000,YES
PC1207_P1_4,"Q_CAP_C0805-22UF,4V,20%,X6S,CHA",22UF,20%,C0805_H61,1772.39,13580.14,270.000,YES
PC1208_P1_3,"Q_CAP_C0805-22UF,4V,20%,X6S,CHA",22UF,20%,C0805_H61,7022.39,13580.39,270.000,YES
PC1209_P1_4,"Q_CAP_C0805-22UF,4V,20%,X6S,CHA",22UF,20%,C0805_H61,1496.69,13580.14,270.000,YES
PC1211_P0_1,"Q_CAP_C0402-2.2UF,10V,10%,X6S,A",2.2UF,10%,C0402,16243.53,14247.91,270.000,NO
PC1212_P0_2,"Q_CAP_C0402-2.2UF,10V,10%,X6S,A",2.2UF,10%,C0402,11610.22,14274.99,270.000,NO
PC1213_P0_3,"Q_CAP_C0402-2.2UF,10V,10%,X6S,A",2.2UF,10%,C0402,16624.96,14247.91,270.000,NO
PC1214_P0_4,"Q_CAP_C0402-2.2UF,10V,10%,X6S,A",2.2UF,10%,C0402,11228.79,14274.99,270.000,NO
PC1242_P1_1,"Q_CAP_C0402-2.2UF,10V,10%,X6S,A",2.2UF,10%,C0402,6631.87,13911.95,270.000,NO
PC1243_P1_2,"Q_CAP_C0402-2.2UF,10V,10%,X6S,A",2.2UF,10%,C0402,1877.11,13911.70,270.000,NO
PC1244_P1_3,"Q_CAP_C0402-2.2UF,10V,10%,X6S,A",2.2UF,10%,C0402,7013.30,13911.95,270.000,NO
PC1245_P1_4,"Q_CAP_C0402-2.2UF,10V,10%,X6S,A",2.2UF,10%,C0402,1495.68,13911.70,270.000,NO
PC1,"Q_CAP_C0805-22UF,4V,20%,X6S,CHA",22UF,20%,C0805_H61,16059.55,6248.62,180.000,YES
PC2,"Q_CAP_C0805-22UF,4V,20%,X6S,CHA",22UF,20%,C0805_H61,2480.18,6366.90,0.000,YES
PC3,"Q_CAPP_THLF-270UF,16V,20%,OSCOA",270UF,20%,EC2-5_6-8_9-2,18264.05,2697.63,90.000,NO
PC8,"Q_CAP_0603-1UF,16V,10%,X7R,TMPA",1UF,10%,C0603,17505.00,2998.62,90.000,NO
PC16,"Q_CAPP_THLF-560UF,2.5V,20%,OSCA",560UF,20%,EC2_5-5_9XB,14615.60,12427.85,90.000,NO
PC27,"Q_CAP_0402-3300PF,50V,10%,X7R,A",3300PF,10%,C0402,17089.20,7010.62,180.000,NO
PC28,"Q_CAP_0402-3300PF,50V,10%,X7R,A",3300PF,10%,C0402,973.20,6962.62,180.000,NO
PC71,"Q_CAP_C0805-22UF,16V,20%,X6S,CA",22UF,20%,C0805_H57,17848.10,2804.92,90.000,YES
PC83,"Q_CAPP_THLF-560UF,2.5V,20%,OSCA",560UF,20%,EC2_5-5_9XB,4854.19,12427.85,90.000,NO
PC100,"Q_CAP_0402-470PF,50V,10%,X7R,TA",470PF,10%,C0402,14277.42,14131.25,0.000,NO
PC101,"Q_CAP_0402-470PF,50V,10%,X7R,TA",470PF,10%,C0402,4516.01,14131.25,0.000,NO
PC113,"Q_CAP_C0402-1UF,25V,10%,X6S,CHA",1UF,10%,C0402,10358.33,2682.64,180.000,NO
PC117,"Q_CAPP_SMLF-330UF,2V,35%,SPCAPA",330U,35%,TAJ_DXC,10681.61,2537.71,180.000,NO
PC175,"Q_CAP_C0402-2.2UF,10V,10%,X6S,A",2.2UF,10%,C0402,16492.20,6166.62,90.000,NO
PC176,"Q_CAP_0402-3300PF,50V,10%,X7R,A",3300PF,10%,C0402,16657.06,5875.56,270.000,NO
PC177,"Q_CAP_C0402-1UF,16V,10%,X6S,CHA",1UF,10%,C0402,16615.06,5875.56,270.000,NO
PC178,"Q_CAP_C0402-100NF,50V,10%,X7R,A",100NF,10%,C0402,16643.31,5949.59,180.000,NO
PC179,"Q_CAP_C0805-22UF,16V,20%,X6S,CA",22UF,20%,C0805_H57,16479.35,5903.56,0.000,YES
PC180,"Q_CAP_C0805-22UF,16V,20%,X6S,CA",22UF,20%,C0805_H57,16713.06,5875.56,270.000,NO
PC181,"Q_CAP_C0402-100NF,50V,10%,X7R,A",100NF,10%,C0402,16128.20,5867.62,0.000,NO
PC184,"Q_CAP_C0805-22UF,4V,20%,X6S,CHA",22UF,20%,C0805_H61,16114.55,6167.01,180.000,YES
PC186,"Q_CAP_C0805-22UF,4V,20%,X6S,CHA",22UF,20%,C0805_H61,16114.55,5891.85,180.000,YES
PC187,"Q_CAP_C0402-2.2UF,10V,10%,X6S,A",2.2UF,10%,C0402,16475.82,6866.01,0.000,NO
PC188,"Q_CAP_C0402-2.2UF,10V,10%,X6S,A",2.2UF,10%,C0402,16475.82,7206.01,0.000,NO
PC189,"Q_CAPP_SMLF-330UF,2.5V,+10/-35A",330UF,+10/-35%,TAJ_SX,3497.53,12990.96,270.000,YES
PC190,"Q_CAP_C0402-1UF,25V,10%,X6S,CHA",1UF,10%,C0402,3382.49,2255.09,90.000,NO
PC193,"Q_CAP_C0402-100NF,50V,10%,X7R,A",100NF,10%,C0402,16554.00,6657.03,180.000,NO
PC194,"Q_CAP_C0402-100NF,50V,10%,X7R,A",100NF,10%,C0402,16554.00,6997.03,180.000,NO
PC207,"Q_CAPP_THLF-270UF,16V,20%,OSCOA",270UF,20%,EC2-5_6-8_9-2,16828.82,6789.52,0.000,NO
PC208,"Q_CAPP_THLF-270UF,16V,20%,OSCOA",270UF,20%,EC2-5_6-8_9-2,16828.82,6280.17,0.000,NO
PC214,"Q_CAP_0402-0.1UF,25V,10%,EMPTYA",NA,10%,C0402,16562.29,5360.71,180.000,NO
PC215,"Q_CAP_0402-3300PF,50V,10%,X7R,A",3300PF,10%,C0402,16850.69,5522.41,180.000,NO
PC216,"Q_CAP_0402-3300PF,50V,10%,X7R,A",3300PF,10%,C0402,16633.03,5503.82,0.000,NO
PC221,"Q_CAP_0402-0.1UF,25V,10%,X7R,CA",0.1UF,10%,C0402,16562.29,5320.71,180.000,NO
PC222,"Q_CAP_0402-470PF,50V,10%,X7R,TA",470PF,10%,C0402,16562.29,5400.71,180.000,NO
PC223,"Q_CAP_C0402-100NF,50V,10%,EMPTA",NA,10%,C0402,16562.29,5240.71,180.000,NO
PC224,"Q_CAP_C0402-10UF,6.3V,20%,X6S,B",10UF,20%,C0402,16673.76,5195.88,270.000,NO
PC225,"Q_CAP_C0402-1UF,16V,10%,X6S,CHA",1UF,10%,C0402,16562.29,5280.71,180.000,NO
PC226,"Q_CAP_C0402-2.2UF,10V,10%,X6S,A",2.2UF,10%,C0402,15045.88,13598.16,90.000,NO
PC227,"Q_CAP_C0402-2.2UF,10V,10%,X6S,A",2.2UF,10%,C0402,12798.34,13600.89,90.000,NO
PC234,"Q_CAP_C0402-100NF,50V,10%,X7R,A",100NF,10%,C0402,15256.93,13681.91,270.000,NO
PC235,"Q_CAP_C0402-100NF,50V,10%,X7R,A",100NF,10%,C0402,13009.17,13684.27,270.000,NO
PC237,"Q_CAP_0402-680PF,50V,10%,X7R,TA",680PF,10%,C0402,17024.20,6881.30,0.000,NO
PC238,"Q_CAP_0402-680PF,50V,10%,X7R,TA",680PF,10%,C0402,880.19,6854.88,0.000,NO
PC248,"Q_CAP_C0402-2.2UF,10V,10%,X6S,A",2.2UF,10%,C0402,13118.20,13370.18,90.000,NO
PC249,"Q_CAP_C0402-2.2UF,10V,10%,X6S,A",2.2UF,10%,C0402,14724.60,13370.18,90.000,NO
PC256,"Q_CAP_C0402-100NF,50V,10%,X7R,A",100NF,10%,C0402,13329.25,13453.93,270.000,NO
PC257,"Q_CAP_C0402-100NF,50V,10%,X7R,A",100NF,10%,C0402,14935.65,13453.93,270.000,NO
PC270,"Q_CAP_C0402-2.2UF,10V,10%,X6S,A",2.2UF,10%,C0402,14403.32,13235.92,90.000,NO
PC271,"Q_CAP_C0402-2.2UF,10V,10%,X6S,A",2.2UF,10%,C0402,14082.04,13235.92,90.000,NO
PC278,"Q_CAP_C0402-100NF,50V,10%,X7R,A",100NF,10%,C0402,14614.37,13314.10,270.000,NO
PC279,"Q_CAP_C0402-100NF,50V,10%,X7R,A",100NF,10%,C0402,14291.02,13314.10,270.000,NO
PC292,"Q_CAP_C0402-2.2UF,10V,10%,X6S,A",2.2UF,10%,C0402,13760.76,13235.92,90.000,NO
PC293,"Q_CAP_C0402-2.2UF,10V,10%,X6S,A",2.2UF,10%,C0402,13439.48,13235.92,90.000,NO
PC300,"Q_CAP_C0402-100NF,50V,10%,X7R,A",100NF,10%,C0402,13973.65,13314.18,270.000,NO
PC301,"Q_CAP_C0402-100NF,50V,10%,X7R,A",100NF,10%,C0402,13661.70,13314.18,270.000,NO
PC315,"Q_CAPP_THLF-270UF,16V,20%,OSCOA",270UF,20%,EC2-5_6-8_9-2,14194.67,13539.46,90.000,NO
PC316,"Q_CAPP_THLF-560UF,2.5V,20%,OSCA",560UF,20%,EC2_5-5_9XB,14371.60,12427.85,90.000,NO
PC318,"Q_CAPP_THLF-270UF,16V,20%,OSCOA",270UF,20%,EC2-5_6-8_9-2,13593.65,13539.46,90.000,NO
PC319,"Q_CAPP_THLF-560UF,2.5V,20%,OSCA",560UF,20%,EC2_5-5_9XB,14127.60,12427.85,90.000,NO
PC321,"Q_CAPP_THLF-270UF,16V,20%,OSCOA",270UF,20%,EC2-5_6-8_9-2,14492.33,13539.46,90.000,NO
PC322,"Q_CAPP_THLF-560UF,2.5V,20%,OSCA",560UF,20%,EC2_5-5_9XB,13884.38,12427.85,90.000,NO
PC323,"Q_CAPP_SMLF-330UF,2.5V,+10/-35A",330UF,+10/-35%,TAJ_SX,14861.63,12989.04,270.000,YES
PC324,"Q_CAPP_THLF-270UF,16V,20%,OSCOA",270UF,20%,EC2-5_6-8_9-2,13891.31,13539.46,90.000,NO
PC325,"Q_CAPP_THLF-560UF,2.5V,20%,OSCA",560UF,20%,EC2_5-5_9XB,13640.38,12427.85,90.000,NO
PC326,"Q_CAPP_SMLF-330UF,2.5V,+10/-35A",330UF,+10/-35%,TAJ_SX,13875.21,12868.78,270.000,YES
PC329,"Q_CAP_0402-0.1UF,25V,10%,EMPTYA",NA,10%,C0402,14277.42,14171.25,0.000,NO
PC330,"Q_CAP_0402-0.1UF,25V,10%,X7R,CA",0.1UF,10%,C0402,14277.42,14206.25,0.000,NO
PC331,"Q_CAP_0402-3300PF,50V,10%,X7R,A",3300PF,10%,C0402,13931.18,13903.06,0.000,NO
PC334,"Q_CAP_0402-0.1UF,25V,10%,EMPTYA",NA,10%,C0402,14277.42,14276.32,0.000,NO
PC335,"Q_CAP_C0402-10UF,6.3V,20%,X6S,B",10UF,20%,C0402,14273.49,14381.41,90.000,NO
PC336,"Q_CAP_0402-470PF,50V,10%,X7R,TA",470PF,10%,C0402,14277.42,14091.25,0.000,NO
PC337,"Q_CAP_C0402-1UF,16V,10%,X6S,CHA",1UF,10%,C0402,14277.42,14241.25,0.000,NO
PC373,"Q_CAP_C0402-2.2UF,10V,10%,X6S,A",2.2UF,10%,C0402,2063.91,6359.81,180.000,NO
PC374,"Q_CAP_0402-3300PF,50V,10%,X7R,A",3300PF,10%,C0402,1934.61,6681.43,90.000,NO
PC375,"Q_CAP_C0402-1UF,16V,10%,X6S,CHA",1UF,10%,C0402,2157.92,6641.07,0.000,NO
PC376,"Q_CAP_C0402-100NF,50V,10%,X7R,A",100NF,10%,C0402,1985.73,6568.79,0.000,NO
PC377,"Q_CAP_C0805-22UF,16V,20%,X6S,CA",22UF,20%,C0805_H57,2160.63,6544.71,180.000,YES
PC378,"Q_CAP_C0805-22UF,16V,20%,X6S,CA",22UF,20%,C0805_H57,2160.63,6628.77,180.000,YES
PC379,"Q_CAP_C0402-100NF,50V,10%,X7R,A",100NF,10%,C0402,2906.20,6378.09,0.000,NO
PC381,"Q_CAP_C0805-22UF,4V,20%,X6S,CHA",22UF,20%,C0805_H61,2480.18,6677.50,180.000,NO
PC382,"Q_CAP_C0805-22UF,4V,20%,X6S,CHA",22UF,20%,C0805_H61,2467.18,6637.20,0.000,YES
PC384,"Q_CAPP_THLF-560UF,2.5V,20%,OSCA",560UF,20%,EC2_5-5_9XB,2702.52,6762.60,90.000,NO
PC385,"Q_CAPP_THLF-560UF,2.5V,20%,OSCA",560UF,20%,EC2_5-5_9XB,2752.89,6560.43,0.000,NO
PC386,"Q_CAP_0402-0.1UF,25V,10%,X7R,CA",0.1UF,10%,C0402,1267.38,6526.03,0.000,NO
PC389,"Q_CAP_0402-3300PF,50V,10%,X7R,A",3300PF,10%,C0402,905.18,6386.05,270.000,NO
PC390,"Q_CAP_0402-0.1UF,25V,10%,X7R,CA",0.1UF,10%,C0402,1267.38,6566.03,0.000,NO
PC391,"Q_CAP_C0402-100NF,50V,10%,EMPTA",NA,10%,C0402,1241.74,6615.15,0.000,NO
PC392,"Q_CAP_C0402-10UF,6.3V,20%,X6S,B",10UF,20%,C0402,1180.21,6653.57,90.000,NO
PC393,"Q_CAP_0402-470PF,50V,10%,X7R,TA",470PF,10%,C0402,1257.38,6471.03,0.000,NO
PC394,"Q_CAP_C0402-1UF,16V,10%,X6S,CHA",1UF,10%,C0402,1241.74,6655.15,0.000,NO
PC395,"Q_CAP_C0402-2.2UF,10V,10%,X6S,A",2.2UF,10%,C0402,6631.87,14016.95,90.000,NO
PC396,"Q_CAP_C0402-2.2UF,10V,10%,X6S,A",2.2UF,10%,C0402,1877.11,14016.70,90.000,NO
PC401,"Q_CAP_C0402-100NF,50V,10%,X7R,A",100NF,10%,C0402,6842.92,14100.70,270.000,NO
PC402,"Q_CAP_C0402-100NF,50V,10%,X7R,A",100NF,10%,C0402,2077.16,14102.45,270.000,NO
PC414,"Q_CAPP_THLF-560UF,2.5V,20%,OSCA",560UF,20%,EC2_5-5_9XB,1594.74,13286.27,0.000,NO
PC415,"Q_CAPP_THLF-560UF,2.5V,20%,OSCA",560UF,20%,EC2_5-5_9XB,1838.47,13286.52,0.000,NO
PC416,"Q_CAPP_THLF-560UF,2.5V,20%,OSCA",560UF,20%,EC2_5-5_9XB,2082.47,13286.52,0.000,NO
PC417,"Q_CAPP_THLF-270UF,16V,20%,OSCOA",270UF,20%,EC2-5_6-8_9-2,1953.16,14300.34,90.000,NO
PC418,"Q_CAPP_SMLF-330UF,2.5V,+10/-35B",330UF,+10/-35%,TAJ_SX,6771.07,13645.13,270.000,YES
PC422,"Q_CAP_0402-3300PF,50V,10%,X7R,A",3300PF,10%,C0402,4525.89,13939.59,0.000,NO
PC428,"Q_CAP_C0402-2.2UF,10V,10%,X6S,A",2.2UF,10%,C0402,2053.20,6715.62,270.000,NO
PC429,"Q_CAP_0402-3300PF,50V,10%,X7R,A",3300PF,10%,C0402,1954.67,7010.26,90.000,NO
PC430,"Q_CAP_C0402-1UF,16V,10%,X6S,CHA",1UF,10%,C0402,1912.67,7010.26,90.000,NO
PC431,"Q_CAP_C0402-100NF,50V,10%,X7R,A",100NF,10%,C0402,1926.42,6936.23,0.000,NO
PC432,"Q_CAP_C0805-22UF,16V,20%,X6S,CA",22UF,20%,C0805_H57,1856.67,7010.26,90.000,NO
PC433,"Q_CAP_C0805-22UF,16V,20%,X6S,CA",22UF,20%,C0805_H57,2090.38,6982.26,180.000,YES
PC434,"Q_CAP_C0402-100NF,50V,10%,X7R,A",100NF,10%,C0402,2440.18,7033.97,180.000,NO
PC435,"Q_CAP_C0805-22UF,4V,20%,X6S,CHA",22UF,20%,C0805_H61,2419.78,6993.57,0.000,YES
PC437,"Q_CAP_C0805-22UF,4V,20%,X6S,CHA",22UF,20%,C0805_H61,2440.18,6718.81,0.000,YES
PC440,"Q_CAP_C0402-2.2UF,10V,10%,X6S,A",2.2UF,10%,C0402,2063.91,6019.81,180.000,NO
PC441,"Q_CAP_C0402-2.2UF,10V,10%,X6S,A",2.2UF,10%,C0402,2063.91,5679.81,180.000,NO
PC446,"Q_CAP_C0402-100NF,50V,10%,X7R,A",100NF,10%,C0402,1985.73,6228.79,0.000,NO
PC447,"Q_CAP_C0402-100NF,50V,10%,X7R,A",100NF,10%,C0402,1985.73,5888.79,0.000,NO
PC460,"Q_CAPP_THLF-270UF,16V,20%,OSCOA",270UF,20%,EC2-5_6-8_9-2,1743.93,6783.54,0.000,NO
PC461,"Q_CAPP_THLF-270UF,16V,20%,OSCOA",270UF,20%,EC2-5_6-8_9-2,1746.85,6472.10,0.000,NO
PC467,"Q_CAP_0402-0.1UF,25V,10%,EMPTYA",NA,10%,C0402,1064.50,5093.74,180.000,NO
PC468,"Q_CAP_0402-3300PF,50V,10%,X7R,A",3300PF,10%,C0402,1329.50,5253.74,180.000,NO
PC469,"Q_CAP_0402-3300PF,50V,10%,X7R,A",3300PF,10%,C0402,1143.14,5237.85,0.000,NO
PC474,"Q_CAP_0402-0.1UF,25V,10%,X7R,CA",0.1UF,10%,C0402,1064.50,5053.74,180.000,NO
PC475,"Q_CAP_0402-470PF,50V,10%,X7R,TA",470PF,10%,C0402,1064.50,5133.74,180.000,NO
PC476,"Q_CAP_C0402-100NF,50V,10%,EMPTA",NA,10%,C0402,1064.50,4973.74,180.000,NO
PC477,"Q_CAP_C0402-10UF,6.3V,20%,X6S,B",10UF,20%,C0402,1175.97,4928.91,270.000,NO
PC478,"Q_CAP_C0402-1UF,16V,10%,X6S,CHA",1UF,10%,C0402,1064.50,5013.74,180.000,NO
PC479,"Q_CAP_C0402-2.2UF,10V,10%,X6S,A",2.2UF,10%,C0402,5284.47,13598.16,90.000,NO
PC480,"Q_CAP_C0402-2.2UF,10V,10%,X6S,A",2.2UF,10%,C0402,3035.73,13598.53,90.000,NO
PC487,"Q_CAP_C0402-100NF,50V,10%,X7R,A",100NF,10%,C0402,5495.52,13681.91,270.000,NO
PC488,"Q_CAP_C0402-100NF,50V,10%,X7R,A",100NF,10%,C0402,3246.56,13681.91,270.000,NO
PC501,"Q_CAP_C0402-2.2UF,10V,10%,X6S,A",2.2UF,10%,C0402,3356.73,13375.53,90.000,NO
PC502,"Q_CAP_C0402-2.2UF,10V,10%,X6S,A",2.2UF,10%,C0402,4963.19,13370.18,90.000,NO
PC509,"Q_CAP_C0402-100NF,50V,10%,X7R,A",100NF,10%,C0402,3567.84,13453.93,270.000,NO
PC510,"Q_CAP_C0402-100NF,50V,10%,X7R,A",100NF,10%,C0402,5174.24,13453.93,270.000,NO
PC523,"Q_CAP_C0402-2.2UF,10V,10%,X6S,A",2.2UF,10%,C0402,4641.91,13235.92,90.000,NO
PC524,"Q_CAP_C0402-2.2UF,10V,10%,X6S,A",2.2UF,10%,C0402,4320.63,13235.92,90.000,NO
PC531,"Q_CAP_C0402-100NF,50V,10%,X7R,A",100NF,10%,C0402,4852.96,13314.10,270.000,NO
PC532,"Q_CAP_C0402-100NF,50V,10%,X7R,A",100NF,10%,C0402,4529.61,13314.10,270.000,NO
PC547,"Q_CAP_0402-0.1UF,25V,10%,EMPTYA",NA,10%,C0402,4516.01,14171.25,0.000,NO
PC548,"Q_CAP_0402-0.1UF,25V,10%,X7R,CA",0.1UF,10%,C0402,4516.01,14206.25,0.000,NO
PC549,"Q_CAP_0402-3300PF,50V,10%,X7R,A",3300PF,10%,C0402,4169.77,13903.06,0.000,NO
PC552,"Q_CAP_C0402-100NF,50V,10%,EMPTA",NA,10%,C0402,4516.01,14276.32,0.000,NO
PC553,"Q_CAP_C0402-10UF,6.3V,20%,X6S,B",10UF,20%,C0402,4497.78,14376.31,90.000,NO
PC554,"Q_CAP_0402-470PF,50V,10%,X7R,TA",470PF,10%,C0402,4516.01,14091.25,0.000,NO
PC555,"Q_CAP_C0402-1UF,16V,10%,X6S,CHA",1UF,10%,C0402,4516.01,14241.25,0.000,NO
PC556,"Q_CAP_C0402-2.2UF,10V,10%,X6S,A",2.2UF,10%,C0402,3999.35,13235.92,90.000,NO
PC557,"Q_CAP_C0402-2.2UF,10V,10%,X6S,A",2.2UF,10%,C0402,3678.07,13235.92,90.000,NO
PC564,"Q_CAP_C0402-100NF,50V,10%,X7R,A",100NF,10%,C0402,4212.24,13314.18,270.000,NO
PC565,"Q_CAP_C0402-100NF,50V,10%,X7R,A",100NF,10%,C0402,3900.29,13314.18,270.000,NO
PC566,"Q_CAPP_THLF-270UF,16V,20%,OSCOA",270UF,20%,EC2-5_6-8_9-2,18264.05,2990.56,90.000,NO
PC567,"Q_CAP_C0805-22UF,16V,20%,X6S,CA",22UF,20%,C0805_H57,17918.26,2804.96,270.000,NO
PC568,"Q_CAP_C0402-0.22UF,25V,10%,X7RA",0.22UF,10%,C0402,17814.28,2918.76,0.000,NO
PC569,"Q_CAP_0402-10PF,50V,1%,NPO,TMPA",10PF,1%,C0402,17692.30,3064.17,90.000,NO
PC570,"Q_CAP_C0805-22UF,16V,20%,X6S,CA",22UF,20%,C0805_H57,17848.26,2804.96,270.000,NO
PC571,"Q_CAP_C0805-22UF,16V,20%,X6S,CA",22UF,20%,C0805_H57,17918.50,2805.02,90.000,YES
PC576,"Q_CAP_C0805-22UF,16V,20%,X6S,CA",22UF,20%,C0805_H57,17973.26,3015.28,90.000,NO
PC577,"Q_CAP_0402-0.1UF,25V,10%,X7R,CA",0.1UF,10%,C0402,17792.26,2796.04,270.000,NO
PC579,"Q_CAPP_THLF-270UF,16V,20%,OSCOA",270UF,20%,EC2-5_6-8_9-2,3832.24,13544.46,90.000,NO
PC580,"Q_CAPP_THLF-560UF,2.5V,20%,OSCA",560UF,20%,EC2_5-5_9XB,3878.97,12427.85,90.000,NO
PC581,"Q_CAP_C0603-4.7UF,16V,10%,X6S,A",4.7UF,10%,C0603_H40,17508.47,2830.63,270.000,NO
PC582,"Q_CAPP_THLF-270UF,16V,20%,OSCOA",270UF,20%,EC2-5_6-8_9-2,4433.26,13544.46,90.000,NO
PC583,"Q_CAPP_THLF-560UF,2.5V,20%,OSCA",560UF,20%,EC2_5-5_9XB,4610.19,12427.85,90.000,NO
PC585,"Q_CAPP_THLF-270UF,16V,20%,OSCOA",270UF,20%,EC2-5_6-8_9-2,4727.00,13539.62,90.000,NO
PC586,"Q_CAPP_THLF-560UF,2.5V,20%,OSCA",560UF,20%,EC2_5-5_9XB,4366.19,12427.85,90.000,NO
PC587,"Q_CAPP_SMLF-330UF,2.5V,+10/-35A",330UF,+10/-35%,TAJ_SX,5100.22,12989.04,270.000,YES
PC588,"Q_CAPP_THLF-270UF,16V,20%,OSCOA",270UF,20%,EC2-5_6-8_9-2,4129.90,13544.46,90.000,NO
PC589,"Q_CAPP_THLF-560UF,2.5V,20%,OSCA",560UF,20%,EC2_5-5_9XB,4122.97,12427.85,90.000,NO
PC590,"Q_CAPP_SMLF-330UF,2.5V,+10/-35A",330UF,+10/-35%,TAJ_SX,4113.80,12873.78,270.000,YES
PC591,"Q_CAP_C0603-2.2UF,16V,10%,X6S,A",2.2UF,10%,C0603,17450.00,2938.62,90.000,NO
PC594,"Q_CAP_0402-3300PF,50V,10%,X7R,A",3300PF,10%,C0402,14287.30,13939.59,0.000,NO
PC600,"Q_CAP_C0402-2.2UF,10V,10%,X6S,A",2.2UF,10%,C0402,16243.53,14352.91,90.000,NO
PC601,"Q_CAP_C0402-2.2UF,10V,10%,X6S,A",2.2UF,10%,C0402,11610.22,14379.99,90.000,NO
PC606,"Q_CAP_C0402-100NF,50V,10%,X7R,A",100NF,10%,C0402,16454.58,14436.66,270.000,NO
PC607,"Q_CAP_C0402-100NF,50V,10%,X7R,A",100NF,10%,C0402,11821.27,14463.74,270.000,NO
PC619,"Q_CAPP_THLF-560UF,2.5V,20%,OSCA",560UF,20%,EC2_5-5_9XB,11799.00,13649.62,0.000,NO
PC620,"Q_CAPP_THLF-560UF,2.5V,20%,OSCA",560UF,20%,EC2_5-5_9XB,11555.00,13649.62,0.000,NO
PC621,"Q_CAPP_THLF-560UF,2.5V,20%,OSCA",560UF,20%,EC2_5-5_9XB,11311.00,13649.62,0.000,NO
PC622,"Q_CAPP_THLF-270UF,16V,20%,OSCOA",270UF,20%,EC2-5_6-8_9-2,11686.27,14663.63,90.000,NO
PC623,"Q_CAPP_SMLF-330UF,2.5V,+10/-35B",330UF,+10/-35%,TAJ_SX,11367.99,14017.18,270.000,YES
PC624,"Q_CAP_0402-0.1UF,25V,10%,X7R,CA",0.1UF,10%,C0402,16859.31,4827.90,180.000,NO
PC627,"Q_CAP_0402-3300PF,50V,10%,X7R,A",3300PF,10%,C0402,17120.80,4994.12,180.000,NO
PC628,"Q_CAP_0402-0.1UF,25V,10%,X7R,CA",0.1UF,10%,C0402,16859.31,4787.90,180.000,NO
PC629,"Q_CAP_C0402-100NF,50V,10%,EMPTA",NA,10%,C0402,16874.95,4738.78,180.000,NO
PC630,"Q_CAP_C0402-10UF,6.3V,20%,X6S,B",10UF,20%,C0402,16936.48,4677.76,270.000,NO
PC631,"Q_CAP_0402-470PF,50V,10%,X7R,TA",470PF,10%,C0402,16859.31,4882.90,180.000,NO
PC632,"Q_CAP_C0402-1UF,16V,10%,X6S,CHA",1UF,10%,C0402,16874.95,4698.78,180.000,NO
PC633,"Q_CAP_C0402-2.2UF,10V,10%,X6S,A",2.2UF,10%,C0402,16475.82,6526.01,0.000,NO
PC634,"Q_CAP_0402-3300PF,50V,10%,X7R,A",3300PF,10%,C0402,16381.81,6244.75,180.000,NO
PC635,"Q_CAP_C0402-1UF,16V,10%,X6S,CHA",1UF,10%,C0402,16611.32,6220.09,270.000,NO
PC636,"Q_CAP_C0402-100NF,50V,10%,X7R,A",100NF,10%,C0402,16554.00,6317.03,180.000,NO
PC637,"Q_CAP_C0805-22UF,16V,20%,X6S,CA",22UF,20%,C0805_H57,16379.10,6257.05,0.000,YES
PC638,"Q_CAP_C0805-22UF,16V,20%,X6S,CA",22UF,20%,C0805_H57,16379.10,6341.11,0.000,YES
PC639,"Q_CAP_C0402-100NF,50V,10%,X7R,A",100NF,10%,C0402,16057.80,6545.42,0.000,NO
PC641,"Q_CAP_C0805-22UF,4V,20%,X6S,CHA",22UF,20%,C0805_H61,16059.55,6208.32,0.000,NO
PC642,"Q_CAP_C0805-22UF,4V,20%,X6S,CHA",22UF,20%,C0805_H61,16059.55,6515.92,180.000,YES
PC644,"Q_CAP_C0402-1UF,25V,10%,X6S,CHA",1UF,10%,C0402,5060.96,14168.17,270.000,NO
PC813,"Q_CAP_C0402-1UF,16V,10%,X6S,CHA",1UF,10%,C0402,16856.86,4806.53,270.000,YES
PC814,"Q_CAP_C0402-1UF,16V,10%,X6S,CHA",1UF,10%,C0402,1257.60,6545.40,90.000,YES
PC831,"Q_CAP_C0805-22UF,16V,20%,X6S,CA",22UF,20%,C0805_H57,14737.64,13970.27,0.000,NO
PC1171,"Q_CAP_C0402-2.2UF,10V,10%,X6S,A",2.2UF,10%,C0402,16624.96,14352.91,90.000,NO
PC1172,"Q_CAP_C0402-2.2UF,10V,10%,X6S,A",2.2UF,10%,C0402,11228.79,14379.99,90.000,NO
PC1173,"Q_CAP_C0402-1UF,16V,10%,X6S,CHA",1UF,10%,C0402,14235.19,14381.51,90.000,NO
PC1177,"Q_CAP_C0402-100NF,50V,10%,X7R,A",100NF,10%,C0402,16836.01,14436.66,270.000,NO
PC1178,"Q_CAP_C0402-100NF,50V,10%,X7R,A",100NF,10%,C0402,11439.84,14463.74,270.000,NO
PC1183,"Q_CAPP_THLF-560UF,2.5V,20%,OSCA",560UF,20%,EC2_5-5_9XB,16586.32,13622.73,0.000,NO
PC1185,"Q_CAPP_THLF-560UF,2.5V,20%,OSCA",560UF,20%,EC2_5-5_9XB,16342.59,13622.48,0.000,NO
PC1186,"Q_CAPP_THLF-560UF,2.5V,20%,OSCA",560UF,20%,EC2_5-5_9XB,16830.32,13622.73,0.000,NO
PC1187,"Q_CAPP_SMLF-330UF,2.5V,+10/-35B",330UF,+10/-35%,TAJ_SX,16771.70,13972.59,270.000,YES
PC1189,"Q_CAPP_THLF-270UF,16V,20%,OSCOA",270UF,20%,EC2-5_6-8_9-2,16701.01,14636.55,90.000,NO
PC1191,"Q_CAP_C0402-2.2UF,10V,10%,X6S,A",2.2UF,10%,C0402,7013.30,14016.95,90.000,NO
PC1192,"Q_CAP_C0402-2.2UF,10V,10%,X6S,A",2.2UF,10%,C0402,1495.68,14016.70,90.000,NO
PC1193,"Q_CAP_C0402-1UF,16V,10%,X6S,CHA",1UF,10%,C0402,1135.97,4928.91,270.000,NO
PC1194,"Q_CAP_C0402-1UF,16V,10%,X6S,CHA",1UF,10%,C0402,4462.58,14376.31,90.000,NO
PC1196,"Q_CAP_C0402-1UF,16V,10%,X6S,CHA",1UF,10%,C0402,16976.48,4677.76,270.000,NO
PC1197,"Q_CAP_C0402-100NF,50V,10%,X7R,A",100NF,10%,C0402,7224.35,14100.70,270.000,NO
PC1198,"Q_CAP_C0402-100NF,50V,10%,X7R,A",100NF,10%,C0402,1706.73,14109.45,270.000,NO
PC1201,"Q_CAPP_THLF-560UF,2.5V,20%,OSCA",560UF,20%,EC2_5-5_9XB,7218.66,13286.77,0.000,NO
PC1203,"Q_CAPP_THLF-560UF,2.5V,20%,OSCA",560UF,20%,EC2_5-5_9XB,6730.93,13286.52,0.000,NO
PC1204,"Q_CAPP_THLF-560UF,2.5V,20%,OSCA",560UF,20%,EC2_5-5_9XB,6974.66,13286.77,0.000,NO
PC1205,"Q_CAPP_SMLF-330UF,2.5V,+10/-35B",330UF,+10/-35%,TAJ_SX,7160.04,13645.13,270.000,YES
PC1206,"Q_CAP_C0805-22UF,4V,20%,X6S,CHA",22UF,20%,C0805_H61,17589.77,6999.40,0.000,NO
PC1207,"Q_CAP_C0805-22UF,4V,20%,X6S,CHA",22UF,20%,C0805_H61,1448.87,7176.60,0.000,NO
PC1210,"Q_CAPP_THLF-270UF,16V,20%,OSCOA",270UF,20%,EC2-5_6-8_9-2,7087.95,14295.79,90.000,NO
PC1215,"Q_CAPP_SMLF-100UF,16V,20%,OSCOA",100UF,20%,EC56_197_229SXA,10058.78,3000.87,90.000,NO
PC1216,"Q_CAP_C0805-22UF,16V,20%,X6S,CA",22UF,20%,C0805_H57,10005.82,2773.24,270.000,NO
PC1217,"Q_CAP_C0805-22UF,16V,20%,X6S,CA",22UF,20%,C0805_H57,10084.45,2771.90,270.000,NO
PC1218,"Q_CAP_C0805-22UF,16V,20%,X6S,CA",22UF,20%,C0805_H57,10161.75,2771.90,270.000,NO
PC1219,"Q_CAP_C0402-1UF,16V,10%,X6S,CHA",1UF,10%,C0402,10434.24,2844.98,90.000,NO
PC1221,"Q_CAP_0402-0.1UF,25V,10%,X7R,CA",0.1UF,10%,C0402,10310.25,2977.10,90.000,NO
PC1222,"Q_CAP_C0402-0.22UF,25V,10%,X7RA",0.22UF,10%,C0402,10425.27,2911.05,0.000,NO
PC1223,"Q_CAP_0402-680PF,50V,10%,X7R,TA",680PF,10%,C0402,10258.33,3053.13,0.000,NO
PC1224,"Q_CAP_0402-0.1UF,25V,10%,X7R,CA",0.1UF,10%,C0402,10724.21,2655.74,180.000,NO
PC1225,"Q_CAP_C0805-47UF,4V,20%,X6S,CHA",47UF,20%,C0805_H57,10722.99,2808.74,0.000,YES
PC1226,"Q_CAP_C0805-47UF,4V,20%,X6S,CHA",47UF,20%,C0805_H57,10726.18,2696.00,0.000,YES
PC1227,"Q_CAPP_THLF-560UF,2.5V,20%,OSCA",560UF,20%,EC2_5-5_9XB,11008.00,2593.62,0.000,NO
PC1229,"Q_CAPP_SMLF-330UF,2V,35%,SPCAPA",330U,35%,TAJ_DXC,10597.61,2536.71,0.000,YES
PC1230,"Q_CAPP_THLF-560UF,2.5V,20%,OSCA",560UF,20%,EC2_5-5_9XB,11007.00,2836.62,0.000,NO
PC1232,"Q_CAP_C0805-10UF,16V,10%,X6S,CB",10UF,10%,C0805_H57,15350.48,2998.86,90.000,NO
PC1233,"Q_CAP_C0805-10UF,16V,10%,X6S,CB",10UF,10%,C0805_H57,15276.18,2998.86,90.000,NO
PC1234,"Q_CAP_C0402-100NF,50V,10%,X7R,A",100NF,10%,C0402,15218.28,3007.75,90.000,NO
PC1235,"Q_CAP_C0402-0.22UF,25V,10%,X7RA",0.22UF,10%,C0402,15046.02,2967.57,90.000,NO
PC1236,"Q_CAP_C0402-100NF,50V,10%,X7R,A",100NF,10%,C0402,14829.08,2814.56,0.000,NO
PC1237,"Q_CAP_C0805-22UF,4V,20%,X6S,CHA",22UF,20%,C0805_H61,14823.58,3163.56,180.000,YES
PC1238,"Q_CAP_C0805-22UF,4V,20%,X6S,CHA",22UF,20%,C0805_H61,14821.58,3163.56,0.000,NO
PC1239,"Q_CAP_C0805-22UF,4V,20%,X6S,CHA",22UF,20%,C0805_H61,14821.58,3019.56,180.000,YES
PC1240,"Q_CAP_C0805-22UF,4V,20%,X6S,CHA",22UF,20%,C0805_H61,14821.58,2937.56,180.000,YES
PC1241,"Q_CAP_C0805-22UF,4V,20%,X6S,CHA",22UF,20%,C0805_H61,14822.58,2855.56,180.000,YES
PC1247,"Q_CAP_C0805-22UF,16V,20%,X6S,CA",22UF,20%,C0805_H57,14737.64,13890.27,0.000,NO
PC1248,"Q_CAP_C0805-22UF,16V,20%,X6S,CA",22UF,20%,C0805_H57,14737.23,13810.27,0.000,NO
PC1249,"Q_CAP_C0402-1UF,16V,10%,X6S,CHA",1UF,10%,C0402,14679.97,14240.33,180.000,NO
PC1251,"Q_CAP_0402-0.1UF,25V,10%,X7R,CA",0.1UF,10%,C0402,14542.12,14111.44,0.000,NO
PC1252,"Q_CAP_C0402-0.22UF,25V,10%,X7RA",0.22UF,10%,C0402,14618.03,14235.07,90.000,NO
PC1253,"Q_CAP_0402-100PF,50V,5%,NPO,CHA",100PF,5%,C0402,14535.09,14059.70,90.000,NO
PC1254,"Q_CAP_0402-0.1UF,25V,10%,X7R,CA",0.1UF,10%,C0402,14549.38,14439.53,270.000,NO
PC1255,"Q_CAP_C0805-22UF,4V,20%,X6S,CHA",22UF,20%,C0805_H61,14800.94,14439.19,90.000,YES
PC1256,"Q_CAP_C0805-22UF,4V,20%,X6S,CHA",22UF,20%,C0805_H61,14716.94,14439.19,90.000,YES
PC1257,"Q_CAP_C0805-22UF,4V,20%,X6S,CHA",22UF,20%,C0805_H61,14632.94,14439.19,90.000,YES
PC1258,"Q_CAPP_THLF-560UF,6.3V,20%,OSCA",560UF,20%,EC2-5_6-8_9-5,15029.56,14493.73,0.000,NO
PC1259,"Q_CAP_C0805-22UF,16V,20%,X6S,CA",22UF,20%,C0805_H57,4976.23,13970.27,0.000,NO
PC1260,"Q_CAP_C0805-22UF,16V,20%,X6S,CA",22UF,20%,C0805_H57,4976.23,13890.27,0.000,NO
PC1261,"Q_CAP_C0805-22UF,16V,20%,X6S,CA",22UF,20%,C0805_H57,4975.82,13810.27,0.000,NO
PC1262,"Q_CAP_C0402-1UF,16V,10%,X6S,CHA",1UF,10%,C0402,4918.56,14240.33,180.000,NO
PC1264,"Q_CAP_0402-0.1UF,25V,10%,X7R,CA",0.1UF,10%,C0402,4780.71,14111.44,0.000,NO
PC1265,"Q_CAP_C0402-0.22UF,25V,10%,X7RA",0.22UF,10%,C0402,4857.12,14234.77,90.000,NO
PC1266,"Q_CAP_0402-100PF,50V,5%,NPO,CHA",100PF,5%,C0402,4773.68,14059.70,90.000,NO
PC1267,"Q_CAP_0402-0.1UF,25V,10%,X7R,CA",0.1UF,10%,C0402,4784.60,14440.79,270.000,NO
PC1268,"Q_CAP_C0805-22UF,4V,20%,X6S,CHA",22UF,20%,C0805_H61,4867.73,14437.92,90.000,YES
PC1269,"Q_CAP_C0805-22UF,4V,20%,X6S,CHA",22UF,20%,C0805_H61,5035.73,14437.92,90.000,YES
PC1270,"Q_CAP_C0805-22UF,4V,20%,X6S,CHA",22UF,20%,C0805_H61,4951.73,14437.92,90.000,YES
PC1271,"Q_CAP_0402-470PF,50V,10%,X7R,TA",470PF,10%,C0402,16685.33,5396.80,180.000,YES
PC1272,"Q_CAP_C0805-22UF,16V,20%,X6S,CA",22UF,20%,C0805_H57,16896.97,7147.05,90.000,NO
PC1273,"Q_CAP_C0805-22UF,16V,20%,X6S,CA",22UF,20%,C0805_H57,16817.97,7147.05,90.000,NO
PC1274,"Q_CAP_C0402-1UF,16V,10%,X6S,CHA",1UF,10%,C0402,16954.43,7148.45,90.000,NO
PC1275,"Q_CAP_C0402-0.22UF,25V,10%,X7RA",0.22UF,10%,C0402,17142.98,7131.15,90.000,NO
PC1276,"Q_CAP_C0402-100NF,50V,10%,X7R,A",100NF,10%,C0402,17592.56,6927.42,0.000,NO
PC1277,"Q_CAP_C0805-22UF,4V,20%,X6S,CHA",22UF,20%,C0805_H61,17588.19,7245.23,0.000,NO
PC1278,"Q_CAP_C0805-22UF,4V,20%,X6S,CHA",22UF,20%,C0805_H61,17587.95,7164.72,0.000,NO
PC1279,"Q_CAP_C0805-22UF,4V,20%,X6S,CHA",22UF,20%,C0805_H61,17587.71,7081.21,0.000,NO
PC1280,"Q_CAP_C0805-22UF,16V,20%,X6S,CA",22UF,20%,C0805_H57,683.65,7107.19,90.000,NO
PC1281,"Q_CAP_C0805-22UF,16V,20%,X6S,CA",22UF,20%,C0805_H57,762.65,7107.19,90.000,NO
PC1282,"Q_CAP_C0402-1UF,16V,10%,X6S,CHA",1UF,10%,C0402,823.11,7113.49,90.000,NO
PC1283,"Q_CAP_C0402-0.22UF,25V,10%,X7RA",0.22UF,10%,C0402,1009.14,7107.47,90.000,NO
PC1284,"Q_CAP_C0402-100NF,50V,10%,X7R,A",100NF,10%,C0402,1450.45,6882.07,0.000,NO
PC1285,"Q_CAP_C0805-22UF,4V,20%,X6S,CHA",22UF,20%,C0805_H61,1450.45,6948.07,0.000,NO
PC1286,"Q_CAP_C0805-22UF,4V,20%,X6S,CHA",22UF,20%,C0805_H61,1448.63,7108.40,0.000,NO
PC1287,"Q_CAP_C0805-22UF,4V,20%,X6S,CHA",22UF,20%,C0805_H61,1448.39,7028.35,0.000,NO
PC1289,"Q_CAP_C0402-1UF,16V,10%,X6S,CHA",1UF,10%,C0402,1140.21,6653.57,90.000,NO
PC1292,"Q_CAP_0402-470PF,50V,10%,X7R,TA",470PF,10%,C0402,1187.54,5129.83,180.000,YES
PC1320,"Q_CAP_C0603-2.2UF,16V,20%,EMPTA",NA,20%,C0603_H40,2543.87,976.33,180.000,NO
PC1321,"Q_CAP_0402-0.068UF,16V,10%,EMPA",NA,10%,C0402,2632.40,2407.82,90.000,NO
PC1322,"Q_CAP_0402-100PF,50V,5%,EMPTY,A",NA,5%,C0402,2772.40,2407.82,90.000,NO
PC1338,"Q_CAP_0402-0.1UF,25V,10%,X7R,CA",0.1UF,10%,C0402,4029.73,13318.53,270.000,NO
PC1339,"Q_CAP_0402-0.1UF,25V,10%,X7R,CA",0.1UF,10%,C0402,3708.74,13318.83,270.000,NO
PC1340,"Q_CAP_0402-0.1UF,25V,10%,X7R,CA",0.1UF,10%,C0402,14437.85,13319.00,270.000,NO
PC1341,"Q_CAP_0402-0.1UF,25V,10%,X7R,CA",0.1UF,10%,C0402,14111.24,13318.82,270.000,NO
PC1342,"Q_CAP_0402-0.1UF,25V,10%,X7R,CA",0.1UF,10%,C0402,13150.58,13453.07,270.000,NO
PC1343,"Q_CAP_0402-0.1UF,25V,10%,X7R,CA",0.1UF,10%,C0402,14755.99,13453.39,270.000,NO
PC1344,"Q_CAP_0402-0.1UF,25V,10%,X7R,CA",0.1UF,10%,C0402,15077.51,13681.49,270.000,NO
PC1345,"Q_CAP_0402-0.1UF,25V,10%,X7R,CA",0.1UF,10%,C0402,12832.80,13682.73,270.000,NO
PC1346,"Q_CAP_0402-0.1UF,25V,10%,X7R,CA",0.1UF,10%,C0402,16558.72,7176.81,180.000,NO
PC1347,"Q_CAP_0402-0.1UF,25V,10%,X7R,CA",0.1UF,10%,C0402,16558.72,6836.81,180.000,NO
PC1348,"Q_CAP_0402-0.1UF,25V,10%,X7R,CA",0.1UF,10%,C0402,16634.22,6072.91,180.000,NO
PC1349,"Q_CAP_0402-0.1UF,25V,10%,X7R,CA",0.1UF,10%,C0402,16275.91,14435.80,270.000,NO
PC1350,"Q_CAP_0402-0.1UF,25V,10%,X7R,CA",0.1UF,10%,C0402,11642.60,14462.88,270.000,NO
PC1351,"Q_CAP_0402-0.1UF,25V,10%,X7R,CA",0.1UF,10%,C0402,16657.34,14435.80,270.000,NO
PC1352,"Q_CAP_0402-0.1UF,25V,10%,X7R,CA",0.1UF,10%,C0402,11261.17,14462.88,270.000,NO
PC1354,"Q_CAP_0402-0.1UF,25V,10%,X7R,CA",0.1UF,10%,C0402,16558.72,6496.81,180.000,NO
PC1355,"Q_CAP_0402-0.1UF,25V,10%,X7R,CA",0.1UF,10%,C0402,13791.14,13318.53,270.000,NO
PC1356,"Q_CAP_0402-0.1UF,25V,10%,X7R,CA",0.1UF,10%,C0402,13470.15,13318.83,270.000,NO
PC1358,"Q_CAP_0402-0.1UF,25V,10%,X7R,CA",0.1UF,10%,C0402,4676.44,13319.00,270.000,NO
PC1359,"Q_CAP_0402-0.1UF,25V,10%,X7R,CA",0.1UF,10%,C0402,4349.83,13318.82,270.000,NO
PC1360,"Q_CAP_0402-0.1UF,25V,10%,X7R,CA",0.1UF,10%,C0402,3389.17,13453.07,270.000,NO
PC1361,"Q_CAP_0402-0.1UF,25V,10%,X7R,CA",0.1UF,10%,C0402,4994.58,13453.39,270.000,NO
PC1362,"Q_CAP_0402-0.1UF,25V,10%,X7R,CA",0.1UF,10%,C0402,5316.10,13681.49,270.000,NO
PC1363,"Q_CAP_0402-0.1UF,25V,10%,X7R,CA",0.1UF,10%,C0402,3070.19,13680.37,270.000,NO
PC1364,"Q_CAP_0402-0.1UF,25V,10%,X7R,CA",0.1UF,10%,C0402,1981.01,6049.01,0.000,NO
PC1365,"Q_CAP_0402-0.1UF,25V,10%,X7R,CA",0.1UF,10%,C0402,1981.01,5709.01,0.000,NO
PC1366,"Q_CAP_0402-0.1UF,25V,10%,X7R,CA",0.1UF,10%,C0402,1935.51,6812.91,0.000,NO
PC1367,"Q_CAP_0402-0.1UF,25V,10%,X7R,CA",0.1UF,10%,C0402,6664.25,14099.84,270.000,NO
PC1368,"Q_CAP_0402-0.1UF,25V,10%,X7R,CA",0.1UF,10%,C0402,1909.49,14099.59,270.000,NO
PC1369,"Q_CAP_0402-0.1UF,25V,10%,X7R,CA",0.1UF,10%,C0402,7045.68,14099.84,270.000,NO
PC1370,"Q_CAP_0402-0.1UF,25V,10%,X7R,CA",0.1UF,10%,C0402,1528.06,14099.59,270.000,NO
PC1371,"Q_CAP_0402-0.1UF,25V,10%,X7R,CA",0.1UF,10%,C0402,1981.01,6389.01,0.000,NO
PC1372,"Q_CAP_C0402-1UF,16V,10%,X6S,CHA",1UF,10%,C0402,16633.76,5195.88,270.000,NO
PC1420,"Q_CAP_0402-0.01UF,25V,10%,X7R,A",0.01UF,10%,C0402,17080.30,6897.52,90.000,NO
PC1421,"Q_CAP_0402-0.01UF,25V,10%,X7R,A",0.01UF,10%,C0402,14529.73,14081.39,180.000,YES
PC1525,"Q_CAP_C0402-1UF,25V,10%,X6S,CHA",1UF,10%,C0402,7729.52,15856.93,90.000,NO
PC1573,"Q_CAPP_SMLF-330UF,2V,35%,SPCAPA",330U,35%,TAJ_DXC,16113.58,7065.27,180.000,YES
PC1574,"Q_CAPP_THLF-560UF,2.5V,20%,OSCA",560UF,20%,EC2_5-5_9XB,15770.00,6976.62,0.000,NO
PC1575,"Q_CAPP_SMLF-330UF,2V,35%,SPCAPA",330U,35%,TAJ_DXC,16113.58,6725.27,180.000,YES
PC1576,"Q_CAPP_THLF-560UF,2.5V,20%,OSCA",560UF,20%,EC2_5-5_9XB,15770.00,6731.62,0.000,NO
PC1579,"Q_CAPP_THLF-560UF,2.5V,20%,OSCA",560UF,20%,EC2_5-5_9XB,15770.00,7221.62,0.000,NO
PC1588,"Q_CAPP_SMLF-330UF,2V,35%,SPCAPA",330U,35%,TAJ_DXC,2426.15,5820.55,0.000,YES
PC1593,"Q_CAPP_THLF-560UF,2.5V,20%,OSCA",560UF,20%,EC2_5-5_9XB,2752.89,5835.76,0.000,NO
PC1594,"Q_CAPP_SMLF-330UF,2V,35%,SPCAPA",330U,35%,TAJ_DXC,2426.15,6160.55,0.000,YES
PC1595,"Q_CAPP_THLF-560UF,2.5V,20%,OSCA",560UF,20%,EC2_5-5_9XB,2752.89,6318.89,0.000,NO
PC1596,"Q_CAPP_THLF-560UF,2.5V,20%,OSCA",560UF,20%,EC2_5-5_9XB,2752.89,6077.35,0.000,NO
PC1599,"Q_CAP_C0805-22UF,10V,20%,X6S,CA",22UF,20%,C0805_H61,17708.98,2296.28,270.000,YES
PC1600,"Q_CAP_C0805-22UF,10V,20%,X6S,CA",22UF,20%,C0805_H61,17628.78,2296.28,270.000,YES
PC1642,"Q_CAP_C0402-1UF,25V,10%,X6S,CHA",1UF,10%,C0402,15099.01,2880.30,0.000,NO
PC1644,"Q_CAPP_THLF-560UF,2.5V,20%,OSCA",560UF,20%,EC2_5-5_9XB,15770.00,6242.62,0.000,NO
PC1645,"Q_CAPP_THLF-560UF,2.5V,20%,OSCA",560UF,20%,EC2_5-5_9XB,15770.00,6487.62,0.000,NO
PC1648,"Q_CAP_C0402-100NF,50V,10%,X7R,A",100NF,10%,C0402,18260.75,15063.41,90.000,NO
PC1649,"Q_CAP_C0402-100NF,50V,10%,X7R,A",100NF,10%,C0402,18431.66,2403.46,90.000,NO
PC1650,"Q_CAP_C0402-100NF,50V,10%,X7R,A",100NF,10%,C0402,9828.49,2763.94,0.000,NO
PC1651,"Q_CAP_C0402-100NF,50V,10%,X7R,A",100NF,10%,C0402,15393.39,3104.87,180.000,NO
PC1652,"Q_CAP_C0402-100NF,50V,10%,X7R,A",100NF,10%,C0402,13582.77,13975.95,270.000,NO
PC1653,"Q_CAP_C0402-100NF,50V,10%,X7R,A",100NF,10%,C0402,11435.33,14793.13,0.000,NO
PC1654,"Q_CAP_C0402-100NF,50V,10%,X7R,A",100NF,10%,C0402,16446.07,14766.95,0.000,NO
PC1655,"Q_CAP_C0402-100NF,50V,10%,X7R,A",100NF,10%,C0402,17050.27,6551.41,0.000,NO
PC1656,"Q_CAP_C0402-100NF,50V,10%,X7R,A",100NF,10%,C0402,3857.97,13971.85,270.000,NO
PC1657,"Q_CAP_C0402-100NF,50V,10%,X7R,A",100NF,10%,C0402,1671.11,14433.90,0.000,NO
PC1658,"Q_CAP_C0402-100NF,50V,10%,X7R,A",100NF,10%,C0402,6834.00,14422.45,0.000,NO
PC1659,"Q_CAP_C0402-100NF,50V,10%,X7R,A",100NF,10%,C0402,1901.10,5709.72,270.000,NO
PC1669,"Q_CAP_C0805-22UF,16V,20%,X6S,CA",22UF,20%,C0805_H57,11970.82,14367.32,0.000,NO
PC1670,"Q_CAP_C0805-22UF,16V,20%,X6S,CA",22UF,20%,C0805_H57,11950.52,14530.22,0.000,NO
PC1671,"Q_CAP_C0805-22UF,16V,20%,X6S,CA",22UF,20%,C0805_H57,11537.54,14455.44,180.000,YES
PC1672,"Q_CAP_C0805-22UF,16V,20%,X6S,CA",22UF,20%,C0805_H57,11966.92,14378.72,180.000,YES
PC1673,"Q_CAP_C0805-22UF,16V,20%,X6S,CA",22UF,20%,C0805_H57,16970.97,14519.35,0.000,NO
PC1674,"Q_CAP_C0805-22UF,16V,20%,X6S,CA",22UF,20%,C0805_H57,16985.57,14353.32,0.000,NO
PC1675,"Q_CAP_C0805-22UF,16V,20%,X6S,CA",22UF,20%,C0805_H57,16553.28,14427.36,180.000,YES
PC1676,"Q_CAP_C0805-22UF,16V,20%,X6S,CA",22UF,20%,C0805_H57,16978.27,14437.35,180.000,YES
PC1677,"Q_CAP_C0805-22UF,16V,20%,X6S,CA",22UF,20%,C0805_H57,2218.47,14209.75,0.000,NO
PC1678,"Q_CAP_C0805-22UF,16V,20%,X6S,CA",22UF,20%,C0805_H57,2218.47,14277.83,0.000,NO
PC1679,"Q_CAP_C0805-22UF,16V,20%,X6S,CA",22UF,20%,C0805_H57,1805.43,14091.15,180.000,YES
PC1680,"Q_CAP_C0805-22UF,16V,20%,X6S,CA",22UF,20%,C0805_H57,2216.13,14099.35,180.000,YES
PC1681,"Q_CAP_C0805-22UF,16V,20%,X6S,CA",22UF,20%,C0805_H57,7373.60,14012.05,0.000,NO
PC1682,"Q_CAP_C0805-22UF,16V,20%,X6S,CA",22UF,20%,C0805_H57,7357.10,14183.65,0.000,NO
PC1683,"Q_CAP_C0805-22UF,16V,20%,X6S,CA",22UF,20%,C0805_H57,6941.62,14098.40,180.000,YES
PC1684,"Q_CAP_C0805-22UF,16V,20%,X6S,CA",22UF,20%,C0805_H57,7363.80,14099.05,180.000,YES
PC1750,"Q_CAP_C0402-33NF,25V,10%,EMPTYA",NA,10%,C0402,9586.06,15592.76,180.000,YES
PC1751,"Q_CAP_0402-1NF,50V,10%,EMPTY,CA",NA,10%,C0402,9655.70,15607.60,90.000,YES
PC1771,"Q_CAPP_THLF-560UF,6.3V,20%,OSCA",560UF,20%,EC2-5_6-8_9-5,5264.78,14497.95,0.000,NO
PC1789,"Q_CAP_0402-0.1UF,25V,10%,EMPTYA",NA,10%,C0402,11361.42,15553.01,180.000,NO
PC1845,"Q_CAPP_SMLF-220UF,6.3V,20%,ALUA",220UF,20%,EC56_197_229SXA,17221.49,15256.98,180.000,NO
PC1846,"Q_CAP_C0402-1UF,16V,10%,X6S,CHA",1UF,10%,C0402,17900.11,15129.98,270.000,NO
PC1847,"Q_CAP_C0402-0.22UF,25V,10%,X7RA",0.22UF,10%,C0402,17903.88,15065.38,180.000,NO
PC1848,"Q_CAP_C0402-1UF,25V,10%,X6S,CHA",1UF,10%,C0402,17970.27,15273.66,0.000,NO
PC1849,"Q_CAP_C0805-22UF,16V,20%,X6S,CA",22UF,20%,C0805_H57,18236.84,15186.71,90.000,NO
PC1850,"Q_CAP_C0805-22UF,16V,20%,X6S,CA",22UF,20%,C0805_H57,18305.84,15186.71,90.000,NO
PC1852,"Q_CAP_0402-0.1UF,25V,10%,X7R,CA",0.1UF,10%,C0402,17221.49,14962.70,180.000,NO
PC1853,"Q_CAP_0402-0.1UF,25V,10%,X7R,CA",0.1UF,10%,C0402,18021.50,15009.80,270.000,NO
PC1855,"Q_CAP_C0805-22UF,10V,20%,X6S,CA",22UF,20%,C0805_H61,17221.49,15099.20,180.000,NO
PC1856,"Q_CAP_C0805-22UF,10V,20%,X6S,CA",22UF,20%,C0805_H61,17221.49,15018.70,180.000,NO
PC1866,"Q_CAPP_THLF-560UF,6.3V,20%,OSCA",560UF,20%,EC2-5_6-8_9-5,17697.90,2046.32,0.000,NO
PC1867,"Q_CAPP_THLF-560UF,6.3V,20%,OSCA",560UF,20%,EC2-5_6-8_9-5,17993.50,2046.32,0.000,NO
PC1868,"Q_CAP_C0805-22UF,10V,20%,X6S,CA",22UF,20%,C0805_H61,17793.78,2296.28,270.000,YES
PC1869,"Q_CAP_0402-0.1UF,25V,10%,X7R,CA",0.1UF,10%,C0402,17553.78,2295.28,270.000,YES
PC1877,"Q_CAP_0402-47PF,50V,5%,NPO,TMPA",47PF,5%,C0402,18081.41,14943.18,0.000,NO
PC1898,"Q_CAP_C0805-22UF,16V,20%,X6S,CA",22UF,20%,C0805_H57,18167.84,15186.71,90.000,NO
PC1900,"Q_CAPP_SMLF-330UF,2.5V,+10/-35B",330UF,+10/-35%,TAJ_SX,16177.27,6029.43,180.000,YES
PC1910,"Q_CAPP_SMLF-330UF,2V,35%,SPCAPA",330U,35%,TAJ_DXC,16113.58,6385.27,180.000,YES
PC1920,"Q_CAPP_SMLF-330UF,2.5V,+10/-35A",330UF,+10/-35%,TAJ_SX,14236.92,12868.90,270.000,YES
PC1930,"Q_CAPP_SMLF-330UF,2.5V,+10/-35B",330UF,+10/-35%,TAJ_SX,2365.46,6856.39,0.000,YES
PC1940,"Q_CAPP_SMLF-330UF,2V,35%,SPCAPA",330U,35%,TAJ_DXC,2426.15,6500.55,0.000,YES
PC1990,"Q_CAPP_SMLF-330UF,2.5V,+10/-35A",330UF,+10/-35%,TAJ_SX,4475.51,12873.90,270.000,YES
PC2000,"Q_CAP_0402-0.022UF,16V,10%,X7RA",0.022UF,10%,C0402,10348.35,2977.10,90.000,NO
PC2001,"Q_CAP_0402-0.022UF,16V,10%,X7RA",0.022UF,10%,C0402,14524.22,14174.93,90.000,NO
PC2002,"Q_CAP_0402-0.022UF,16V,10%,X7RA",0.022UF,10%,C0402,4762.81,14174.93,90.000,NO
PC2079,"Q_CAP_C0402-1UF,25V,10%,X6S,CHA",1UF,10%,C0402,17678.91,988.20,270.000,NO
PC2080,"Q_CAP_C0805-22UF,16V,20%,X6S,CA",22UF,20%,C0805_H57,17326.30,803.64,0.000,YES
PC2081,"Q_CAP_C0805-10UF,16V,10%,X6S,CB",10UF,10%,C0805_H57,16798.50,4316.72,90.000,NO
PC2082,"Q_CAP_C0805-10UF,16V,10%,X6S,CB",10UF,10%,C0805_H57,17326.00,804.74,180.000,NO
PC2085,"Q_CAP_C0402-1UF,25V,10%,X6S,CHA",1UF,10%,C0402,17702.78,928.91,180.000,NO
PC2086,"Q_CAP_C0402-1UF,25V,10%,X6S,CHA",1UF,10%,C0402,17104.08,4219.45,90.000,NO
PC2087,"Q_CAP_C0402-1UF,25V,10%,X6S,CHA",1UF,10%,C0402,17620.68,767.97,0.000,NO
PC2088,"Q_CAP_C0402-0.01UF,50V,10%,EMPA",NA,10%,C0402,17836.78,969.27,180.000,NO
PC2089,"Q_CAP_C0402-6800PF,50V,10%,X7RA",6800PF,10%,C0402,17104.26,4091.63,270.000,NO
PC2091,"Q_CAP_0402-0.1UF,25V,10%,X7R,CA",0.1UF,10%,C0402,16738.72,4296.45,90.000,NO
PC2092,"Q_CAP_0402-0.1UF,25V,10%,X7R,CA",0.1UF,10%,C0402,17337.97,574.54,180.000,NO
PC2093,"Q_CAP_C0402-1UF,25V,10%,X6S,CHA",1UF,10%,C0402,16943.14,4301.55,270.000,NO
PC2098,"Q_CAP_C0402-1UF,25V,10%,X6S,CHA",1UF,10%,C0402,3036.57,917.67,180.000,NO
PC2103,"Q_CAP_C0402-1UF,25V,10%,X6S,CHA",1UF,10%,C0402,7061.12,15796.83,180.000,NO
PC2137,"Q_CAP_0402-0.1UF,25V,10%,X7R,CA",0.1UF,10%,C0402,2840.33,2296.06,180.000,NO
PC2139,"Q_CAP_C0402-1UF,25V,10%,X6S,CHA",1UF,10%,C0402,3013.15,972.99,270.000,NO
PC2140,"Q_CAP_C0402-1UF,25V,10%,X6S,CHA",1UF,10%,C0402,3462.49,2255.09,90.000,NO
PC2141,"Q_CAP_C0805-22UF,16V,20%,X6S,CA",22UF,20%,C0805_H57,2591.69,789.30,0.000,YES
PC2142,"Q_CAP_C0805-10UF,16V,10%,X6S,CB",10UF,10%,C0805_H57,2898.00,2108.12,180.000,NO
PC2143,"Q_CAP_C0805-10UF,16V,10%,X6S,CB",10UF,10%,C0805_H57,2591.69,789.30,180.000,NO
PC2144,"Q_CAP_C0402-0.01UF,50V,10%,EMPA",NA,10%,C0402,17150.44,4085.45,90.000,NO
PC2146,"Q_CAP_C0402-1UF,25V,10%,X6S,CHA",1UF,10%,C0402,2969.47,756.73,0.000,NO
PC2147,"Q_CAP_C0402-1UF,25V,10%,X6S,CHA",1UF,10%,C0402,3221.55,2337.19,270.000,NO
PC2149,"Q_CAP_C0402-0.01UF,50V,10%,EMPA",NA,10%,C0402,3422.85,2121.09,90.000,NO
PC2150,"Q_CAP_C0402-3900PF,50V,10%,X7RA",3900PF,10%,C0402,3185.57,918.03,0.000,NO
PC2151,"Q_CAP_C0402-6800PF,50V,10%,X7RA",6800PF,10%,C0402,3382.67,2121.27,270.000,NO
PC2152,"Q_CAP_0402-0.1UF,25V,10%,X7R,CA",0.1UF,10%,C0402,2604.36,561.60,180.000,NO
PC2153,"Q_CAP_0402-0.22UF,16V,10%,EMPTA",NA,10%,C0402,17469.18,1266.67,90.000,NO
PC2154,"Q_CAP_C0402-1UF,25V,10%,EMPTY,A",NA,10%,C0402,17644.78,1186.27,90.000,NO
PC2155,"Q_CAP_C0402-0.047UF,25V,10%,EMA",NA,10%,C0402,17364.18,1266.67,90.000,NO
PC2156,"Q_CAP_C0402-100NF,50V,10%,EMPTA",NA,10%,C0402,17294.18,1266.67,90.000,NO
PC2157,"Q_CAP_C0402-39PF,50V,5%,EMPTY,A",NA,5%,C0402,16596.10,3987.02,270.000,NO
PC2158,"Q_CAP_C0603-2.2UF,16V,20%,EMPTA",NA,20%,C0603_H40,17295.08,987.57,180.000,NO
PC2159,"Q_CAP_C0402-1UF,25V,10%,EMPTY,A",NA,10%,C0402,16461.10,4142.02,180.000,NO
PC2160,"Q_CAP_0402-0.1UF,25V,10%,EMPTYA",NA,10%,C0402,17503.88,1003.07,0.000,NO
PC2161,"Q_CAP_0402-0.068UF,16V,10%,EMPA",NA,10%,C0402,16471.10,4302.02,90.000,NO
PC2162,"Q_CAP_0402-100PF,50V,5%,EMPTY,A",NA,5%,C0402,16611.10,4302.02,90.000,NO
PC2163,"Q_CAP_C0805-10UF,16V,10%,EMPTYB",NA,10%,C0805_H57,16675.70,4178.32,90.000,NO
PC2164,"Q_CAP_0402-0.22UF,16V,10%,EMPTA",NA,10%,C0402,2717.97,1255.43,90.000,NO
PC2165,"Q_CAP_C0402-1UF,25V,10%,EMPTY,A",NA,10%,C0402,2893.57,1175.03,90.000,NO
PC2166,"Q_CAP_C0402-0.047UF,25V,10%,EMA",NA,10%,C0402,2612.97,1255.43,90.000,NO
PC2167,"Q_CAP_C0402-100PF,50V,5%,EMPTYA",NA,5%,C0402,2542.97,1255.43,90.000,NO
PC2168,"Q_CAP_C0402-39PF,50V,5%,EMPTY,A",NA,5%,C0402,2723.20,2108.22,180.000,NO
PC2169,"Q_CAP_C0402-1UF,25V,10%,EMPTY,A",NA,10%,C0402,2635.80,2226.02,270.000,NO
PC2170,"Q_CAPP_SMLF-330UF,2.5V,+10/-35B",330UF,+10/-35%,TAJ_SX,11756.96,14017.18,270.000,YES
PC2171,"Q_CAPP_SMLF-330UF,2.5V,+10/-35B",330UF,+10/-35%,TAJ_SX,2019.27,13644.88,270.000,YES
PC2172,"Q_CAPP_SMLF-330UF,2.5V,+10/-35B",330UF,+10/-35%,TAJ_SX,1635.27,13644.88,270.000,YES
PC2173,"Q_CAP_C0805-10UF,16V,10%,EMPTYB",NA,10%,C0805_H57,2826.40,2211.02,270.000,NO
PC2174,"Q_CAP_0402-0.1UF,25V,10%,EMPTYA",NA,10%,C0402,2752.67,991.83,0.000,NO
PC2180,"Q_CAPP_THLF-560UF,2.5V,20%,OSCA",560UF,20%,EC2_5-5_9XB,15770.00,5997.62,0.000,NO
PC2181,"Q_CAP_C0402-1UF,25V,10%,X6S,CHA",1UF,10%,C0402,8152.52,15865.93,90.000,NO
PC2182,"Q_CAP_0402-220PF,50V,10%,X7R,TA",220PF,10%,C0402,8086.52,15937.93,0.000,NO
PC2183,"Q_CAP_0402-220PF,50V,10%,EMPTYA",NA,10%,C0402,8506.52,15937.93,0.000,NO
PC2184,"Q_CAP_0402-0.068UF,16V,10%,X7RA",0.068UF,10%,C0402,7671.52,15908.93,180.000,NO
PC2185,"Q_CAP_0402-0.068UF,16V,10%,X7RA",0.068UF,10%,C0402,8086.52,15977.93,180.000,NO
PC2186,"Q_CAP_C0402-1UF,25V,10%,X6S,CHA",1UF,10%,C0402,7244.52,15855.18,270.000,YES
PC2187,"Q_CAP_C0402-1UF,25V,10%,X6S,CHA",1UF,10%,C0402,7061.12,15876.83,180.000,NO
PC2188,"Q_CAP_C0402-1UF,25V,10%,X6S,CHA",1UF,10%,C0402,7293.53,16145.03,180.000,NO
PC2189,"Q_CAP_C0402-0.01UF,50V,10%,X7RA",0.01UF,10%,C0402,7255.52,16040.93,90.000,NO
PC2190,"Q_CAP_C0402-0.01UF,50V,10%,X7RA",0.01UF,10%,C0402,7212.52,15694.93,180.000,NO
PC2191,"Q_CAP_0402-0.068UF,16V,10%,X7RA",0.068UF,10%,C0402,7061.12,15876.83,0.000,YES
PC2192,"Q_CAP_C0402-0.001UF,50V,10%,X7A",0.001UF,10%,C0402,7061.12,15956.83,180.000,NO
PC2193,"Q_CAP_C0402-0.047UF,25V,10%,X7A",0.047UF,10%,C0402,7061.12,15676.83,180.000,NO
PC2196,"Q_CAP_0402-0.22UF,16V,10%,EMPTA",NA,10%,C0402,10172.27,1951.14,0.000,NO
PC2197,"Q_CAP_C0402-39PF,50V,5%,EMPTY,A",NA,5%,C0402,7496.60,2693.22,180.000,NO
PC2198,"Q_CAP_C0402-1UF,25V,10%,EMPTY,A",NA,10%,C0402,10232.20,1835.99,90.000,NO
PC2199,"Q_CAPP_THLF-560UF,2.5V,20%,OSCA",560UF,20%,EC2_5-5_9XB,2702.52,7004.14,90.000,NO
PC2200,"Q_CAP_C0402-1UF,25V,10%,EMPTY,A",NA,10%,C0402,7651.60,2828.22,90.000,NO
PC2201,"Q_CAP_0402-0.068UF,16V,10%,EMPA",NA,10%,C0402,7811.60,2818.22,0.000,NO
PC2202,"Q_CAP_C0402-100NF,50V,10%,EMPTA",NA,10%,C0402,10151.95,2104.23,0.000,NO
PC2203,"Q_CAP_0402-100PF,50V,5%,EMPTY,A",NA,5%,C0402,7811.60,2678.22,0.000,NO
PC2204,"Q_CAP_C0805-10UF,16V,10%,EMPTYB",NA,10%,C0805_H57,7648.50,2567.92,270.000,NO
PC2205,"Q_CAP_C0603-2.2UF,16V,20%,EMPTA",NA,20%,C0603_H40,9872.85,2103.33,90.000,NO
PC2206,"Q_CAP_0402-0.1UF,25V,10%,EMPTYA",NA,10%,C0402,9888.35,1894.53,270.000,NO
PC2207,"Q_CAP_C0402-1UF,25V,10%,X6S,CHA",1UF,10%,C0402,10113.76,1712.78,180.000,NO
PC2208,"Q_CAP_C0402-1UF,25V,10%,X6S,CHA",1UF,10%,C0402,8635.71,2953.85,270.000,NO
PC2209,"Q_CAP_C0402-1UF,25V,10%,X6S,CHA",1UF,10%,C0402,10056.99,1688.43,90.000,NO
PC2210,"Q_CAP_C0402-1UF,25V,10%,X6S,CHA",1UF,10%,C0402,8660.43,2893.11,180.000,NO
PC2211,"Q_CAP_C0402-1UF,25V,10%,X6S,CHA",1UF,10%,C0402,9896.05,1770.53,270.000,NO
PC2212,"Q_CAP_C0402-1UF,25V,10%,X6S,CHA",1UF,10%,C0402,8578.33,2732.17,0.000,NO
PC2213,"Q_CAP_C0402-0.01UF,50V,10%,EMPA",NA,10%,C0402,8794.43,2933.47,180.000,NO
PC2214,"Q_CAP_C0402-0.01UF,50V,10%,EMPA",NA,10%,C0402,10097.35,1554.43,90.000,NO
PC2215,"Q_CAP_C0402-3900PF,50V,10%,X7RA",3900PF,10%,C0402,10057.35,1554.43,270.000,NO
PC2216,"Q_CAP_C0402-6800PF,50V,10%,X7RA",6800PF,10%,C0402,8794.15,2894.39,0.000,NO
PC2217,"Q_CAP_0402-0.1UF,25V,10%,X7R,CA",0.1UF,10%,C0402,9831.24,1853.47,0.000,NO
PC2218,"Q_CAP_0402-0.1UF,25V,10%,X7R,CA",0.1UF,10%,C0402,8595.92,2404.41,180.000,NO
PC2219,"Q_CAP_C0805-10UF,16V,10%,X6S,CB",10UF,10%,C0805_H57,9693.90,2085.89,90.000,NO
PC2220,"Q_CAP_C0805-10UF,16V,10%,X6S,CB",10UF,10%,C0805_H57,8590.76,2340.68,180.000,NO
PC2221,"Q_CAP_C0402-1UF,25V,10%,X6S,CHA",1UF,10%,C0402,17034.67,7230.05,180.000,NO
PC2222,"Q_CAP_C0402-1UF,25V,10%,X6S,CHA",1UF,10%,C0402,900.35,7188.79,180.000,NO
PC2223,"Q_CAP_C0402-1UF,25V,10%,X6S,CHA",1UF,10%,C0402,8992.52,15865.93,90.000,NO
PC2224,"Q_CAP_0402-220PF,50V,10%,EMPTYA",NA,10%,C0402,8926.52,15937.93,0.000,NO
PC2225,"Q_CAP_0402-220PF,50V,10%,EMPTYA",NA,10%,C0402,9346.52,15853.93,0.000,NO
PC2226,"Q_CAP_0402-0.068UF,16V,10%,X7RA",0.068UF,10%,C0402,8506.52,15977.93,180.000,NO
PC2227,"Q_CAP_0402-0.068UF,16V,10%,X7RA",0.068UF,10%,C0402,8926.52,15977.93,180.000,NO
PC2229,"Q_CAP_0402-0.22UF,16V,10%,EMPTA",NA,10%,C0402,7049.53,1296.68,90.000,NO
PC2230,"Q_CAP_C0402-1UF,25V,10%,X6S,CHA",1UF,10%,C0402,7373.40,1172.35,270.000,NO
PC2231,"Q_CAP_C0402-1UF,25V,10%,EMPTY,A",NA,10%,C0402,7239.33,1369.88,90.000,NO
PC2232,"Q_CAP_C0402-0.047UF,25V,10%,EMA",NA,10%,C0402,6944.53,1296.68,90.000,NO
PC2233,"Q_CAP_C0402-1UF,25V,10%,X6S,CHA",1UF,10%,C0402,7397.33,1112.52,180.000,NO
PC2234,"Q_CAP_C0402-1UF,25V,10%,X6S,CHA",1UF,10%,C0402,7315.23,951.58,0.000,NO
PC2235,"Q_CAP_C0402-100NF,50V,10%,EMPTA",NA,10%,C0402,6874.53,1296.68,90.000,NO
PC2236,"Q_CAP_C0402-0.01UF,50V,10%,EMPA",NA,10%,C0402,7531.33,1152.88,180.000,NO
PC2237,"Q_CAP_C0402-3900PF,50V,10%,X7RA",3900PF,10%,C0402,7531.33,1112.88,0.000,NO
PC2238,"Q_CAP_0402-0.1UF,25V,10%,X7R,CA",0.1UF,10%,C0402,6922.20,769.62,180.000,NO
PC2239,"Q_CAP_C0603-2.2UF,16V,20%,EMPTA",NA,20%,C0603_H40,6875.43,1017.58,180.000,NO
PC2240,"Q_CAP_C0805-10UF,16V,10%,X6S,CB",10UF,10%,C0805_H57,6889.20,970.62,0.000,YES
PC2241,"Q_CAP_0402-0.1UF,25V,10%,EMPTYA",NA,10%,C0402,7084.23,1033.08,0.000,NO
PC2242,"Q_CAP_C0805-22UF,16V,20%,X6S,CA",22UF,20%,C0805_H57,6892.20,833.62,180.000,NO
PC2260,"Q_CAP_C0805-22UF,16V,20%,X6S,CA",22UF,20%,C0805_H57,18043.26,3015.28,90.000,NO
PC2261,"Q_CAP_C0805-22UF,16V,20%,X6S,CA",22UF,20%,C0805_H57,18059.86,2766.59,270.000,NO
PC2262,"Q_CAP_C0805-22UF,16V,20%,X6S,CA",22UF,20%,C0805_H57,18113.86,3014.65,90.000,NO
PC2263,"Q_CAP_C0805-22UF,16V,20%,X6S,CA",22UF,20%,C0805_H57,18130.86,2766.59,270.000,NO
PC2277,"Q_CAP_0402-0.01UF,25V,10%,X7R,A",0.01UF,10%,C0402,935.47,6871.45,90.000,NO
PC2279,"Q_CAP_0402-0.01UF,25V,10%,X7R,A",0.01UF,10%,C0402,10312.70,3050.62,270.000,NO
PC2280,"Q_CAP_C0805-10UF,16V,10%,X6S,CB",10UF,10%,C0805_H57,9685.80,2082.99,270.000,YES
PC2281,"Q_CAP_C0402-0.047UF,25V,10%,EMA",NA,10%,C0402,10151.95,2034.23,0.000,NO
PC2282,"Q_CAP_0402-0.01UF,25V,10%,X7R,A",0.01UF,10%,C0402,4769.00,14081.72,180.000,YES
PC2286,"Q_CAP_0402-1000PF,50V,5%,EMPTYA",NA,5%,C0402,10240.99,3014.13,270.000,YES
PC2336,"Q_CAPP_SMLF-330UF,2.5V,+10/-35A",330UF,+10/-35%,TAJ_SX,13262.94,13000.56,270.000,YES
PC2340,"Q_CAP_C0402-560PF,50V,10%,EMPTA",NA,10%,C0402,7009.60,1297.02,90.000,YES
PC2341,"Q_CAP_C0402-560PF,50V,10%,EMPTA",NA,10%,C0402,10211.60,1946.09,180.000,YES
PC2342,"Q_CAP_C0805-22UF,16V,20%,X6S,CA",22UF,20%,C0805_H57,17989.26,2765.96,270.000,NO
PC2343,"Q_CAP_C0805-22UF,16V,20%,X6S,CA",22UF,20%,C0805_H57,17903.26,3015.28,90.000,NO
PC2344,"Q_CAP_C0805-22UF,16V,20%,X6S,CA",22UF,20%,C0805_H57,17903.20,3015.32,270.000,YES
PC2345,"Q_CAPP_THLF-270UF,16V,20%,OSCOA",270UF,20%,EC2-5_6-8_9-2,14342.00,13793.62,90.000,NO
PC2346,"Q_CAPP_THLF-270UF,16V,20%,OSCOA",270UF,20%,EC2-5_6-8_9-2,4586.00,13796.62,90.000,NO
PC2347,"Q_CAP_0402-1NF,50V,10%,EMPTY,CA",NA,10%,C0402,7671.39,15737.93,180.000,NO
PC2348,"Q_CAP_0402-1NF,50V,10%,EMPTY,CA",NA,10%,C0402,8086.52,15737.93,180.000,NO
PC2349,"Q_CAP_0402-1NF,50V,10%,EMPTY,CA",NA,10%,C0402,8926.52,15737.93,180.000,NO
PC2350,"Q_CAP_0402-1NF,50V,10%,EMPTY,CA",NA,10%,C0402,8506.52,15737.93,180.000,NO
PC2361,"Q_CAP_0402-0.1UF,25V,10%,EMPTYA",NA,10%,C0402,14277.70,14311.50,0.000,NO
PC2362,"Q_CAP_0402-0.1UF,25V,10%,EMPTYA",NA,10%,C0402,16561.80,5205.40,180.000,NO
PC2365,"Q_CAP_0402-0.1UF,25V,10%,EMPTYA",NA,10%,C0402,16875.20,4659.40,180.000,NO
PC2366,"Q_CAP_0402-0.1UF,25V,10%,EMPTYA",NA,10%,C0402,4515.90,14311.34,0.000,NO
PC2367,"Q_CAP_0402-0.1UF,25V,10%,EMPTYA",NA,10%,C0402,1064.20,4935.78,180.000,NO
PC2368,"Q_CAP_0402-0.1UF,25V,10%,EMPTYA",NA,10%,C0402,1241.50,6694.00,0.000,NO
PC2643,"Q_CAP_C0402-1UF,25V,10%,X6S,CHA",1UF,10%,C0402,14822.37,14168.17,270.000,NO
PC2645,"Q_CAPP_SMLF-330UF,2.5V,+10/-35B",330UF,+10/-35%,TAJ_SX,16382.73,13972.59,270.000,YES
PC2946,"Q_CAP_C0402-2.2UF,10V,10%,X6S,A",2.2UF,10%,C0402,16370.82,7206.01,180.000,NO
PC2947,"Q_CAP_C0402-2.2UF,10V,10%,X6S,A",2.2UF,10%,C0402,16370.82,6866.01,180.000,NO
PC2948,"Q_CAP_C0402-2.2UF,10V,10%,X6S,A",2.2UF,10%,C0402,16370.82,6526.01,180.000,NO
PC2949,"Q_CAP_C0402-2.2UF,10V,10%,X6S,A",2.2UF,10%,C0402,2168.91,5679.81,0.000,NO
PC2950,"Q_CAP_C0402-2.2UF,10V,10%,X6S,A",2.2UF,10%,C0402,2168.91,6019.81,0.000,NO
PC2951,"Q_CAP_C0402-2.2UF,10V,10%,X6S,A",2.2UF,10%,C0402,2168.91,6359.81,0.000,NO
PC3272,"Q_CAP_C0402-1UF,25V,10%,X6S,CHA",1UF,10%,C0402,8572.52,15865.93,90.000,NO
PC4056,"Q_CAP_C0402-3900PF,50V,10%,X7RA",3900PF,10%,C0402,17836.78,929.27,0.000,NO
PC5328,"Q_CAP_C0402-1UF,25V,10%,X6S,CHA",1UF,10%,C0402,17165.27,4243.40,180.000,NO
PD15,"ZENER_AC-5.0SMDJ14A,SMLF,IC,BCA",,,D2723_SMCXC,10103.62,16501.68,90.000,YES
PD16,"ZENER_AC-5.0SMDJ14A,SMLF,IC,BCA",,,D2723_SMCXC,10364.50,16502.52,90.000,YES
PD17,"SS15P3SM386A-SS15P3S-M3/86A,SMA",,,TO277A_4-3X6-1,9291.96,15426.66,90.000,NO
PD101,"DIODE_TVS-SMF14A,SMLF,IC,BCSMFA",,,SOD123F,17768.78,1196.77,270.000,NO
PD102,"SCHOTTKY_AC-B340A-13-F,SMLF,ICA",,,D2010XF,17922.38,610.37,180.000,NO
PD103,"SCHOTTKY_AC-B340A-13-F,SMLF,ICA",,,D2010XF,16638.73,3855.98,0.000,NO
PD107,"DIODE_TVS-SMF14A,SMLF,IC,BCSMFA",,,SOD123F,3067.57,1185.53,270.000,NO
PD108,"SCHOTTKY_AC-B340A-13-F,SMLF,ICA",,,D2010XF,3205.67,597.53,180.000,NO
PD109,"SCHOTTKY_AC-B340A-13-F,SMLF,ICA",,,D2010XF,2936.77,2436.37,0.000,NO
PD112,"SCHOTTKY_AC-B340A-13-F,SMLF,ICA",,,D2010XF,9690.75,1585.03,90.000,NO
PD113,"SCHOTTKY_AC-B340A-13-F,SMLF,ICA",,,D2010XF,8981.33,2562.40,180.000,NO
PD114,"DIODE_TVS-SMF14A,SMLF,IC,BCSMFA",,,SOD123F,10224.84,1525.14,90.000,NO
PD115,"DIODE_TVS-SMF14A,SMLF,IC,BCSMFA",,,SOD123F,7522.26,1264.19,180.000,NO
PD116,"SCHOTTKY_AC-B340A-13-F,SMLF,ICA",,,D2010XF,7551.43,792.38,180.000,NO
PJ42,SCONN21_9193031121LF-SCONN21_9A,,,CON_F21S2H2D2S_P1W4-22_LDH,11534.65,15372.44,270.000,NO
PJ45,"Q_SHORT_SM-EMPTY,SHORT6",,,SHORT_R0603,16900.28,5636.50,270.000,NO
PJ46,"Q_SHORT_SM-EMPTY,SHORT6",,,SHORT_R0603,16605.52,5580.97,180.000,NO
PJ47,"Q_SHORT_SM-EMPTY,SHORT6",,,SHORT_R0603,13809.40,13859.10,180.000,NO
PJ48,"Q_SHORT_SM-EMPTY,SHORT6",,,SHORT_R0603,818.99,6341.10,90.000,NO
PJ49,"Q_SHORT_SM-EMPTY,SHORT6",,,SHORT_R0603,4554.34,14015.19,90.000,NO
PJ50,"Q_SHORT_SM-EMPTY,SHORT6",,,SHORT_R0603,1384.69,5369.53,270.000,NO
PJ51,"Q_SHORT_SM-EMPTY,SHORT6",,,SHORT_R0603,1115.63,5315.00,180.000,NO
PJ52,"Q_SHORT_SM-EMPTY,SHORT6",,,SHORT_R0603,4047.99,13859.10,180.000,NO
PJ53,"Q_SHORT_SM-EMPTY,SHORT6",,,SHORT_R0603,14315.75,14015.19,90.000,NO
PJ54,"Q_SHORT_SM-EMPTY,SHORT6",,,SHORT_R0603,17149.16,5073.91,0.000,NO
PJ62,"Q_SHORT_SM-EMPTY,SHORT6",,,SHORT_R0603,12822.39,2893.68,180.000,YES
PJ63,"Q_SHORT_SM-EMPTY,SHORT6",,,SHORT_R0603,12822.39,2947.68,180.000,YES
PJ64,"Q_SHORT_SM-EMPTY,SHORT6",,,SHORT_R0603,14503.87,14156.94,270.000,YES
PJ65,"Q_SHORT_SM-EMPTY,SHORT6",,,SHORT_R0603,14557.87,14156.94,270.000,YES
PJ66,"Q_SHORT_SM-EMPTY,SHORT6",,,SHORT_R0603,4742.46,14157.34,270.000,YES
PJ67,"Q_SHORT_SM-EMPTY,SHORT6",,,SHORT_R0603,4796.46,14157.34,270.000,YES
PJP1,CONN3_210HP1030BR1-CONN3_210-HB,,,HEADER1X3XG,5492.36,14412.07,90.000,NO
PL2,"Q_INDUCTOR_SMLF-130NH/106A,INDA",130NH/106A,,L_HCME107512-131_10X7-5,16765.62,13909.96,270.000,NO
PL3,"Q_INDUCTOR_SMLF-300NH/33A,IND,A",300NH/33A,,L_AF13A-120K_9-6X6-4,16145.44,6026.34,180.000,NO
PL4,"Q_INDUCTOR_SMLF-120NH/69A,IND,A",120NH/69A,,L_VLBU6565100T-R12L-1_6-5X6-5,16084.83,6725.27,180.000,NO
PL5,"Q_INDUCTOR_SMLF-120NH/69A,IND,A",120NH/69A,,L_VLBU6565100T-R12L-1_6-5X6-5,16084.83,7065.27,180.000,NO
PL6,"Q_INDUCTOR_SMLF-100NH/16A,IND,A",100NH/16A,,L_HCBS4545_4-5X4-5,16900.48,6487.43,180.000,NO
PL7,"Q_INDUCTOR4P_14-150NH,SMLF,INDA",,,L_TLM117513Q-151QL_11X7-5XA,15191.26,13131.95,0.000,NO
PL8,"Q_INDUCTOR4P_14-150NH,SMLF,INDA",,,L_TLM117513Q-151QL_11X7-5XA,12937.83,13134.60,0.000,NO
PL9,"Q_INDUCTOR4P_14-150NH,SMLF,INDA",,,L_TLM117513Q-151QL_11X7-5XA,13257.91,12904.26,0.000,NO
PL10,"Q_INDUCTOR4P_14-150NH,SMLF,INDA",,,L_TLM117513Q-151QL_11X7-5XA,14867.61,12905.25,0.000,NO
PL11,"Q_INDUCTOR4P_14-150NH,SMLF,INDA",,,L_TLM117513Q-151QL_11X7-5XA,14545.74,12773.44,0.000,NO
PL12,"Q_INDUCTOR_SMLF-130NH/106A,INDA",130NH/106A,,L_HCME107512-131_10X7-5,7153.96,13574.00,270.000,NO
PL13,"Q_INDUCTOR4P_14-150NH,SMLF,INDA",,,L_TLM117513Q-151QL_11X7-5XA,13900.50,12773.44,0.000,NO
PL14,"Q_INDUCTOR_SMLF-100NH/16A,IND,A",100NH/16A,,L_HCBS4545_4-5X4-5,6854.84,14301.18,0.000,NO
PL15,"Q_INDUCTOR_SMLF-50NH/148A,IND,A",50NH/148A,,L_HCBS1080-500QL_10X8-3,13387.16,13950.08,270.000,NO
PL16,Q_INDUCTOR_SMLF-BLM18SN220TN1DA,BLM18SN220TN1D/8000MA,,L0603,15420.18,3010.26,270.000,NO
PL17,"Q_INDUCTOR_SMLF-120NH/69A,IND,A",120NH/69A,,L_VLBU6565100T-R12L-1_6-5X6-5,2454.90,6500.55,0.000,NO
PL18,"Q_INDUCTOR_SMLF-130NH/106A,INDA",130NH/106A,,L_HCME107512-131_10X7-5,6772.96,13574.00,270.000,NO
PL19,"Q_INDUCTOR_SMLF-130NH/106A,INDA",130NH/106A,,L_HCME107512-131_10X7-5,2017.77,13573.75,270.000,NO
PL20,"Q_INDUCTOR_SMLF-300NH/33A,IND,A",300NH/33A,,L_AF13A-120K_9-6X6-4,2420.29,6859.48,0.000,NO
PL21,"Q_INDUCTOR_SMLF-120NH/69A,IND,A",120NH/69A,,L_VLBU6565100T-R12L-1_6-5X6-5,2454.90,6160.55,0.000,NO
PL22,"Q_INDUCTOR_SMLF-120NH/69A,IND,A",120NH/69A,,L_VLBU6565100T-R12L-1_6-5X6-5,2454.90,5820.55,0.000,NO
PL23,"Q_INDUCTOR_SMLF-100NH/16A,IND,A",100NH/16A,,L_HCBS4545_4-5X4-5,1803.36,5859.74,90.000,NO
PL24,"Q_INDUCTOR4P_14-150NH,SMLF,INDA",,,L_TLM117513Q-151QL_11X7-5XA,5429.85,13131.95,0.000,NO
PL25,"Q_INDUCTOR4P_14-150NH,SMLF,INDA",,,L_TLM117513Q-151QL_11X7-5XA,3176.42,13134.60,0.000,NO
PL26,"Q_INDUCTOR4P_14-150NH,SMLF,INDA",,,L_TLM117513Q-151QL_11X7-5XA,3496.50,12904.26,0.000,NO
PL27,"Q_INDUCTOR4P_14-150NH,SMLF,INDA",,,L_TLM117513Q-151QL_11X7-5XA,5106.20,12905.25,0.000,NO
PL28,"Q_INDUCTOR4P_14-150NH,SMLF,INDA",,,L_TLM117513Q-151QL_11X7-5XA,4784.33,12773.44,0.000,NO
PL29,"Q_INDUCTOR4P_14-150NH,SMLF,INDA",,,L_TLM117513Q-151QL_11X7-5XA,4462.56,12773.44,0.000,NO
PL30,"Q_INDUCTOR4P_14-150NH,SMLF,INDA",,,L_TLM117513Q-151QL_11X7-5XA,4139.09,12773.44,0.000,NO
PL31,"Q_INDUCTOR4P_14-150NH,SMLF,INDA",,,L_TLM117513Q-151QL_11X7-5XA,3817.31,12773.44,0.000,NO
PL32,"Q_INDUCTOR_SMLF-50NH/148A,IND,A",50NH/148A,,L_HCBS1080-500QL_10X8-3,3660.75,13949.38,270.000,NO
PL33,"Q_INDUCTOR_SMLF-130NH/106A,INDA",130NH/106A,,L_HCME107512-131_10X7-5,16384.62,13909.96,270.000,NO
PL34,"Q_INDUCTOR_SMLF-130NH/106A,INDA",130NH/106A,,L_HCME107512-131_10X7-5,11750.88,13937.04,270.000,NO
PL35,"Q_INDUCTOR_SMLF-120NH/69A,IND,A",120NH/69A,,L_VLBU6565100T-R12L-1_6-5X6-5,16084.83,6385.27,180.000,NO
PL43,"Q_INDUCTOR_SMLF-100NH/16A,IND,A",100NH/16A,,L_HCBS4545_4-5X4-5,1716.55,14301.23,0.000,NO
PL44,"Q_INDUCTOR_SMLF-100NH/16A,IND,A",100NH/16A,,L_HCBS4545_4-5X4-5,11451.76,14664.22,0.000,NO
PL45,"Q_INDUCTOR_SMLF-100NH/16A,IND,A",100NH/16A,,L_HCBS4545_4-5X4-5,18310.62,2447.49,90.000,NO
PL64,Q_INDUCTOR_SMLF-BLM18SN220TN1DA,BLM18SN220TN1D/8000MA,,L0603,18308.52,15068.91,90.000,NO
PL65,"Q_INDUCTOR_SMLF-4.7UH,IND,CV-4A",4.7UH,,L_PCMB104EXB,17628.81,15162.11,180.000,NO
PL66,"Q_INDUCTOR_SMLF-1.5UH/53A,IND,A",1.5UH/53A,,L_EM-15AM17VG1-QS_14-3X12-9,17668.78,2441.74,270.000,NO
PL101,"Q_INDUCTOR_SMLF-100NH/16A,IND,A",100NH/16A,,L_HCBS4545_4-5X4-5,16466.50,14637.14,0.000,NO
PL105,"Q_INDUCTOR_SMLF-120NH/69A,IND,A",120NH/69A,,L_VLBU6565100T-R12L-1_6-5X6-5,12636.05,13315.69,90.000,NO
PL106,"Q_INDUCTOR_SMLF-120NH/69A,IND,A",120NH/69A,,L_VLBU6565100T-R12L-1_6-5X6-5,5726.90,13322.58,90.000,NO
PL110,"Q_INDUCTOR_SMLF-100NH/16A,IND,A",100NH/16A,,L_HCBS4545_4-5X4-5,9835.25,2885.46,0.000,NO
PL112,"Q_INDUCTOR4P_14-150NH,SMLF,INDA",,,L_TLM117513Q-151QL_11X7-5XA,14223.97,12773.44,0.000,NO
PL113,"Q_INDUCTOR_SMLF-130NH/106A,INDA",130NH/106A,,L_HCME107512-131_10X7-5,1636.77,13573.75,270.000,NO
PL114,"Q_INDUCTOR4P_14-150NH,SMLF,INDA",,,L_TLM117513Q-151QL_11X7-5XA,13578.72,12773.44,0.000,NO
PL118,"Q_INDUCTOR_SMLF-0.68UH,IND,CV+A",0.68UH,,L_PCMC063T,14714.04,14432.36,90.000,NO
PL119,"Q_INDUCTOR_SMLF-0.68UH,IND,CV+A",0.68UH,,L_PCMC063T,4949.26,14436.58,90.000,NO
PL120,"Q_INDUCTOR_SMLF-4.7UH,IND,CV-4B",4.7UH,,L_PCMC063T,17346.65,7083.55,0.000,NO
PL121,"Q_INDUCTOR_SMLF-4.7UH,IND,CV-4B",4.7UH,,L_PCMC063T,1211.23,7070.39,0.000,NO
PL150,"Q_INDUCTOR_SMLF-300NH/33A,IND,A",300NH/33A,,L_AF13A-120K_9-6X6-4,10678.18,2814.00,0.000,NO
PL170,"Q_INDUCTOR_SMLF-2.2UH,IND,CV-2A",2.2UH,,L_PCMC063T,14854.37,2982.20,180.000,NO
PL210,"Q_INDUCTOR_SMLF-130NH/106A,INDA",130NH/106A,,L_HCME107512-131_10X7-5,11369.88,13937.04,270.000,NO
PPQ1,"MOSFET_NCH_1D3S-PSMNR58-30YLH,B",,,SOT1023,9539.04,15700.00,90.000,NO
PPQ2,"MOSFET_NCH_1D3S-PSMNR58-30YLH,B",,,SOT1023,9772.70,15700.00,90.000,NO
PPQ5,"MOSFET_NCH_1D3S-PSMNR58-30YLH,B",,,SOT1023,10006.36,15700.00,90.000,NO
PPQ6,"MOSFET_NCH_1D3S-PSMNR58-30YLH,B",,,SOT1023,10240.02,15700.00,90.000,NO
PPQ7,"MOSFET_NCH_1D3S-PSMNR58-30YLH,B",,,SOT1023,10473.68,15700.00,90.000,NO
PPQ8,"MOSFET_NCH_1D3S-PSMNR58-30YLH,B",,,SOT1023,10707.34,15700.00,90.000,NO
PPQ9,"MOSFET_NCH_1D3S-PSMNR58-30YLH,B",,,SOT1023,10941.00,15700.00,90.000,NO
PR1,"Q_RES_0402LF-3.3,1%,1/16W,CHIPA",3.3,1%,R0402,17037.68,7004.06,270.000,NO
PR2,"Q_RES_0402LF-3.3,1%,1/16W,CHIPA",3.3,1%,R0402,920.96,6961.80,270.000,NO
PR3,"Q_RES_4P_12-0.003,1%,3W,SMLF,EA",,,R2512_4P_H41,10939.36,16039.44,270.000,NO
PR4,"Q_SP_RES4P-0.0003,1%,4W,SMLF,EA",,,R2725_4P,9635.86,16039.84,270.000,NO
PR50,"Q_RES_0402LF-12.4K,0.1%,1/16W,A",12.4K,0.1%,R0402,17024.20,6953.30,0.000,NO
PR51,"Q_RES_0402LF-12.4K,0.1%,1/16W,A",12.4K,0.1%,R0402,870.08,6942.09,0.000,NO
PR73,"Q_RES_0402LF-10K,1%,1/16W,CHIPA",10K,1%,R0402,18137.00,14987.87,90.000,NO
PR89,"Q_RES_0402LF-16.9K,1%,1/16W,CHA",16.9K,1%,R0402,17977.22,15010.43,270.000,NO
PR91,"Q_RES_0402LF-11.8K,0.1%,1/16W,A",11.8K,0.1%,R0402,18081.41,15023.88,179.946,NO
PR92,"Q_RES_0402LF-88.7K,1%,1/16W,CHA",88.7K,1%,R0402,18081.41,14983.18,0.000,NO
PR97,"Q_RES_0402LF-2.2,1%,1/16W,CHIPA",2.2,1%,R0402,16532.20,6166.62,270.000,YES
PR101,"Q_RES_0402LF-2.2,1%,1/16W,CHIPA",2.2,1%,R0402,16417.19,6819.63,180.000,YES
PR102,"Q_RES_0402LF-2.2,1%,1/16W,CHIPA",2.2,1%,R0402,16417.19,7159.63,180.000,YES
PR105,"Q_RES_0402LF-28K,1%,1/16W,EMPTA",28K,1%,R0402,16562.29,5446.22,180.000,YES
PR106,"Q_RES_0402LF-681,1%,1/16W,CHIPA",681,1%,R0402,16562.29,5400.71,0.000,YES
PR107,"Q_RES_0402LF-0,5%,1/16W,EMPTY,A",0,5%,R0402,16562.29,5360.71,180.000,YES
PR108,"Q_RES_0402LF-0,5%,1/16W,CHIP,CA",0,5%,R0402,16562.29,5320.71,180.000,YES
PR120,"Q_RES_0402LF-0,5%,1/16W,CHIP,CA",0,5%,R0402,16900.80,5537.57,270.000,NO
PR121,"Q_RES_0402LF-0,5%,1/16W,CHIP,CA",0,5%,R0402,16576.32,5519.14,270.000,NO
PR123,"Q_RES_0402LF-1K,1%,1/16W,EMPTYA",1K,1%,R0402,16685.03,5283.35,180.000,YES
PR130,"Q_RES_0402LF-1,1%,1/16W,CHIP,CA",1,1%,R0402,16562.93,5221.76,0.000,YES
PR132,"Q_RES_0402LF-8.87K,1%,1/16W,EMA",8.87K,1%,R0402,15143.78,13699.19,0.000,NO
PR133,"Q_RES_0402LF-8.87K,1%,1/16W,EMA",8.87K,1%,R0402,12899.07,13700.43,0.000,NO
PR134,"Q_RES_0402LF-2.2,1%,1/16W,CHIPA",2.2,1%,R0402,15095.64,13540.47,270.000,YES
PR135,"Q_RES_0402LF-2.2,1%,1/16W,CHIPA",2.2,1%,R0402,12823.13,13540.47,270.000,YES
PR136,"Q_RES_0402LF-0,5%,1/16W,CHIP,CA",0,5%,R0402,15050.70,13600.91,270.000,YES
PR137,"Q_RES_0402LF-0,5%,1/16W,CHIP,CA",0,5%,R0402,12801.92,13613.16,270.000,YES
PR138,"Q_RES_0402LF-8.87K,1%,1/16W,EMA",8.87K,1%,R0402,13208.10,13475.21,0.000,NO
PR139,"Q_RES_0402LF-8.87K,1%,1/16W,EMA",8.87K,1%,R0402,14814.50,13475.21,0.000,NO
PR140,"Q_RES_0402LF-2.2,1%,1/16W,CHIPA",2.2,1%,R0402,13144.41,13312.49,270.000,YES
PR141,"Q_RES_0402LF-2.2,1%,1/16W,CHIPA",2.2,1%,R0402,14771.54,13310.98,270.000,YES
PR142,"Q_RES_0402LF-0,5%,1/16W,CHIP,CA",0,5%,R0402,13123.20,13385.18,270.000,YES
PR143,"Q_RES_0402LF-0,5%,1/16W,CHIP,CA",0,5%,R0402,14724.60,13370.18,270.000,YES
PR144,"Q_RES_0402LF-8.87K,1%,1/16W,EMA",8.87K,1%,R0402,14493.22,13340.95,0.000,NO
PR145,"Q_RES_0402LF-8.87K,1%,1/16W,EMA",8.87K,1%,R0402,14171.94,13340.95,0.000,NO
PR146,"Q_RES_0402LF-2.2,1%,1/16W,CHIPA",2.2,1%,R0402,14449.31,13176.91,270.000,YES
PR147,"Q_RES_0402LF-2.2,1%,1/16W,CHIPA",2.2,1%,R0402,14128.42,13177.29,270.000,YES
PR148,"Q_RES_0402LF-0,5%,1/16W,CHIP,CA",0,5%,R0402,14427.18,13303.12,0.000,YES
PR149,"Q_RES_0402LF-0,5%,1/16W,CHIP,CA",0,5%,R0402,14107.41,13301.59,0.000,YES
PR150,"Q_RES_0402LF-8.87K,1%,1/16W,EMA",8.87K,1%,R0402,13866.84,13340.95,0.000,NO
PR151,"Q_RES_0402LF-8.87K,1%,1/16W,EMA",8.87K,1%,R0402,13529.38,13340.95,0.000,NO
PR152,"Q_RES_0402LF-2.2,1%,1/16W,CHIPA",2.2,1%,R0402,13812.97,13182.88,270.000,YES
PR153,"Q_RES_0402LF-2.2,1%,1/16W,CHIPA",2.2,1%,R0402,13485.69,13179.23,270.000,YES
PR154,"Q_RES_0402LF-0,5%,1/16W,CHIP,CA",0,5%,R0402,13785.78,13301.33,0.000,YES
PR155,"Q_RES_0402LF-0,5%,1/16W,CHIP,CA",0,5%,R0402,13445.32,13239.31,270.000,YES
PR156,"Q_RES_0402LF-0,5%,1/16W,CHIP,CA",0,5%,R0402,14239.81,14242.49,0.000,YES
PR157,"Q_RES_0402LF-0,5%,1/16W,EMPTY,A",0,5%,R0402,14264.35,14189.69,270.000,YES
PR158,"Q_RES_0402LF-0,5%,1/16W,CHIP,CA",0,5%,R0402,14126.25,14152.75,0.000,YES
PR159,"Q_RES_0402LF-28K,1%,1/16W,EMPTA",28K,1%,R0402,14274.15,14082.29,0.000,YES
PR166,"Q_RES_0402LF-1K,1%,1/16W,EMPTYA",1K,1%,R0402,14155.95,14206.59,0.000,YES
PR170,"Q_RES_0402LF-0,5%,1/16W,CHIP,CA",0,5%,R0402,13856.76,13903.35,0.000,NO
PR171,"Q_RES_0402LF-0,5%,1/16W,CHIP,CA",0,5%,R0402,14126.15,14077.89,0.000,YES
PR176,"Q_RES_0402LF-1,1%,1/16W,CHIP,CA",1,1%,R0402,14239.81,14279.48,180.000,YES
PR187,"Q_RES_0402LF-10K,0.1%,1/16W,CHA",10K,0.1%,R0402,10258.33,2972.64,0.000,NO
PR200,"Q_RES_0402LF-2.2,1%,1/16W,CHIPA",2.2,1%,R0402,2122.54,6406.19,0.000,YES
PR202,"Q_RES_0402LF-28K,1%,1/16W,EMPTA",28K,1%,R0402,1257.38,6401.03,180.000,NO
PR203,"Q_RES_0402LF-24.3K,1%,1/16W,CHA",24.3K,1%,R0402,1257.38,6361.53,180.000,NO
PR214,"Q_RES_0402LF-1K,1%,1/16W,EMPTYA",1K,1%,R0402,1164.47,6517.34,0.000,YES
PR215,"Q_RES_0402LF-1K,1%,1/16W,CHIP,A",1K,1%,R0402,871.40,6565.64,0.000,NO
PR216,"Q_RES_0402LF-0,5%,1/16W,CHIP,CA",0,5%,R0402,863.02,6386.05,90.000,NO
PR217,"Q_RES_0402LF-1K,1%,1/16W,CHIP,A",1K,1%,R0402,1260.92,6401.43,270.000,YES
PR218,"Q_RES_0402LF-1K,1%,1/16W,EMPTYA",1K,1%,R0402,1164.47,6575.50,0.000,YES
PR220,"Q_RES_0402LF-1,1%,1/16W,CHIP,CA",1,1%,R0402,1236.08,6677.00,180.000,YES
PR224,"Q_RES_0402LF-8.87K,1%,1/16W,EMA",8.87K,1%,R0402,1967.01,14121.73,0.000,NO
PR225,"Q_RES_0402LF-8.87K,1%,1/16W,EMA",8.87K,1%,R0402,6721.77,14121.98,0.000,NO
PR226,"Q_RES_0402LF-2.2,1%,1/16W,CHIPA",2.2,1%,R0402,6674.08,13959.51,270.000,YES
PR227,"Q_RES_0402LF-2.2,1%,1/16W,CHIPA",2.2,1%,R0402,1903.32,13959.01,270.000,YES
PR242,"Q_RES_0402LF-0,5%,1/16W,CHIP,CA",0,5%,R0402,4510.14,13989.79,270.000,NO
PR250,"Q_RES_0402LF-2.2,1%,1/16W,CHIPA",2.2,1%,R0402,2013.60,6712.42,90.000,YES
PR254,"Q_RES_0402LF-2.2,1%,1/16W,CHIPA",2.2,1%,R0402,2122.54,6066.19,0.000,YES
PR255,"Q_RES_0402LF-2.2,1%,1/16W,CHIPA",2.2,1%,R0402,2122.54,5726.19,0.000,YES
PR258,"Q_RES_0402LF-28K,1%,1/16W,EMPTA",28K,1%,R0402,1064.50,5179.25,180.000,YES
PR259,"Q_RES_0402LF-8.45K,1%,1/16W,CHA",8.45K,1%,R0402,1064.50,5133.74,0.000,YES
PR260,"Q_RES_0402LF-0,5%,1/16W,EMPTY,A",0,5%,R0402,1064.50,5093.74,180.000,YES
PR261,"Q_RES_0402LF-0,5%,1/16W,CHIP,CA",0,5%,R0402,1064.50,5053.74,180.000,YES
PR273,"Q_RES_0402LF-0,5%,1/16W,CHIP,CA",0,5%,R0402,1384.89,5269.49,270.000,NO
PR274,"Q_RES_0402LF-0,5%,1/16W,CHIP,CA",0,5%,R0402,1086.43,5253.17,270.000,NO
PR275,"Q_RES_0402LF-0,5%,1/16W,CHIP,CA",0,5%,R0402,1187.54,5078.77,180.000,YES
PR276,"Q_RES_0402LF-1K,1%,1/16W,EMPTYA",1K,1%,R0402,1187.24,5016.38,180.000,YES
PR283,"Q_RES_0402LF-1,1%,1/16W,CHIP,CA",1,1%,R0402,1064.50,4934.74,0.000,YES
PR285,"Q_RES_0402LF-8.87K,1%,1/16W,EMA",8.87K,1%,R0402,5374.37,13703.19,0.000,NO
PR286,"Q_RES_0402LF-8.87K,1%,1/16W,EMA",8.87K,1%,R0402,3136.46,13698.07,0.000,NO
PR287,"Q_RES_0402LF-2.2,1%,1/16W,CHIPA",2.2,1%,R0402,5334.23,13540.47,270.000,YES
PR288,"Q_RES_0402LF-2.2,1%,1/16W,CHIPA",2.2,1%,R0402,3062.07,13540.47,270.000,YES
PR289,"Q_RES_0402LF-0,5%,1/16W,CHIP,CA",0,5%,R0402,5289.29,13600.91,270.000,YES
PR290,"Q_RES_0402LF-0,5%,1/16W,CHIP,CA",0,5%,R0402,3024.01,13615.36,270.000,YES
PR291,"Q_RES_0402LF-8.87K,1%,1/16W,EMA",8.87K,1%,R0402,3446.69,13475.21,0.000,NO
PR292,"Q_RES_0402LF-8.87K,1%,1/16W,EMA",8.87K,1%,R0402,5053.09,13475.21,0.000,NO
PR293,"Q_RES_0402LF-2.2,1%,1/16W,CHIPA",2.2,1%,R0402,3383.00,13312.49,270.000,YES
PR294,"Q_RES_0402LF-2.2,1%,1/16W,CHIPA",2.2,1%,R0402,5010.13,13310.98,270.000,YES
PR295,"Q_RES_0402LF-0,5%,1/16W,CHIP,CA",0,5%,R0402,3361.79,13385.18,270.000,YES
PR296,"Q_RES_0402LF-0,5%,1/16W,CHIP,CA",0,5%,R0402,4963.19,13370.18,270.000,YES
PR297,"Q_RES_0402LF-8.87K,1%,1/16W,EMA",8.87K,1%,R0402,4731.81,13340.95,0.000,NO
PR298,"Q_RES_0402LF-8.87K,1%,1/16W,EMA",8.87K,1%,R0402,4410.53,13340.95,0.000,NO
PR299,"Q_RES_0402LF-2.2,1%,1/16W,CHIPA",2.2,1%,R0402,4687.90,13176.91,270.000,YES
PR300,"Q_RES_0402LF-2.2,1%,1/16W,CHIPA",2.2,1%,R0402,4367.01,13177.29,270.000,YES
PR301,"Q_RES_0402LF-0,5%,1/16W,CHIP,CA",0,5%,R0402,4641.91,13235.92,270.000,YES
PR302,"Q_RES_0402LF-0,5%,1/16W,CHIP,CA",0,5%,R0402,4317.28,13235.67,270.000,YES
PR303,"Q_RES_0402LF-0,5%,1/16W,CHIP,CA",0,5%,R0402,4479.70,14242.69,0.000,YES
PR304,"Q_RES_0402LF-0,5%,1/16W,EMPTY,A",0,5%,R0402,4502.94,14189.69,270.000,YES
PR305,"Q_RES_0402LF-0,5%,1/16W,CHIP,CA",0,5%,R0402,4364.84,14152.75,0.000,YES
PR306,"Q_RES_0402LF-28K,1%,1/16W,EMPTA",28K,1%,R0402,4502.74,14072.29,0.000,YES
PR313,"Q_RES_0402LF-1K,1%,1/16W,EMPTYA",1K,1%,R0402,4394.54,14206.59,0.000,YES
PR317,"Q_RES_0402LF-0,5%,1/16W,CHIP,CA",0,5%,R0402,4103.15,13903.25,0.000,NO
PR318,"Q_RES_0402LF-5.23K,1%,1/16W,CHA",5.23K,1%,R0402,4364.74,14077.89,0.000,YES
PR323,"Q_RES_0402LF-1,1%,1/16W,CHIP,CA",1,1%,R0402,4479.70,14279.68,180.000,YES
PR325,"Q_RES_0402LF-8.87K,1%,1/16W,EMA",8.87K,1%,R0402,4105.43,13340.95,0.000,NO
PR326,"Q_RES_0402LF-8.87K,1%,1/16W,EMA",8.87K,1%,R0402,3767.97,13340.95,0.000,NO
PR327,"Q_RES_0402LF-2.2,1%,1/16W,CHIPA",2.2,1%,R0402,4051.56,13182.88,270.000,YES
PR328,"Q_RES_0402LF-2.2,1%,1/16W,CHIPA",2.2,1%,R0402,3724.28,13179.23,270.000,YES
PR329,"Q_RES_0402LF-0,5%,1/16W,CHIP,CA",0,5%,R0402,4004.62,13235.92,270.000,YES
PR330,"Q_RES_0402LF-0,5%,1/16W,CHIP,CA",0,5%,R0402,3683.91,13239.31,270.000,YES
PR338,"Q_RES_0402LF-0,5%,1/16W,CHIP,CA",0,5%,R0402,10370.00,2950.12,90.000,YES
PR345,"Q_RES_0402LF-0,5%,1/16W,CHIP,CA",0,5%,R0402,14271.55,13989.79,270.000,NO
PR353,"Q_RES_0402LF-8.87K,1%,1/16W,EMA",8.87K,1%,R0402,11700.12,14485.02,0.000,NO
PR354,"Q_RES_0402LF-8.87K,1%,1/16W,EMA",8.87K,1%,R0402,16333.43,14457.94,0.000,NO
PR355,"Q_RES_0402LF-2.2,1%,1/16W,CHIPA",2.2,1%,R0402,16286.00,14296.27,270.000,YES
PR356,"Q_RES_0402LF-2.2,1%,1/16W,CHIPA",2.2,1%,R0402,11636.43,14322.30,270.000,YES
PR357,"Q_RES_0402LF-28K,1%,1/16W,EMPTA",28K,1%,R0402,16859.31,4952.90,0.000,NO
PR358,"Q_RES_0402LF-3.57K,1%,1/16W,CHA",3.57K,1%,R0402,16859.31,4992.90,0.000,NO
PR369,"Q_RES_0402LF-1K,1%,1/16W,EMPTYA",1K,1%,R0402,16959.60,4814.22,180.000,YES
PR370,"Q_RES_0402LF-1K,1%,1/16W,CHIP,A",1K,1%,R0402,17214.29,4828.69,180.000,NO
PR371,"Q_RES_0402LF-0,5%,1/16W,CHIP,CA",0,5%,R0402,17176.86,5009.77,270.000,NO
PR372,"Q_RES_0402LF-1K,1%,1/16W,CHIP,A",1K,1%,R0402,16866.69,5022.79,0.000,YES
PR373,"Q_RES_0402LF-1K,1%,1/16W,EMPTYA",1K,1%,R0402,16952.22,4755.83,180.000,YES
PR375,"Q_RES_0402LF-1,1%,1/16W,CHIP,CA",1,1%,R0402,16876.77,4669.50,0.000,YES
PR380,"Q_RES_0402LF-2.2,1%,1/16W,CHIPA",2.2,1%,R0402,16417.19,6479.63,180.000,YES
PR389,"Q_RES_0402LF-1,1%,1/16W,CHIP,CA",1,1%,R0402,17463.66,2850.32,90.000,NO
PR395,"Q_RES_0402LF-0,5%,1/16W,CHIP,CA",0,5%,R0402,15039.58,2800.56,180.000,NO
PR396,"Q_RES_0402LF-0,5%,1/16W,EMPTY,A",0,5%,R0402,14974.09,2800.27,0.000,NO
PR400,"Q_RES_0402LF-10K,1%,1/16W,EMPTA",10K,1%,R0402,14276.76,14121.08,180.000,YES
PR402,"Q_RES_0402LF-0,5%,1/16W,CHIP,CA",0,5%,R0402,12723.46,13540.47,90.000,YES
PR403,"Q_RES_0402LF-0,5%,1/16W,EMPTY,A",0,5%,R0402,12758.56,13540.47,90.000,YES
PR409,"Q_RES_0402LF-0,5%,1/16W,EMPTY,A",0,5%,R0402,16829.38,4882.88,0.000,YES
PR410,"Q_RES_0402LF-0,5%,1/16W,EMPTY,A",0,5%,R0402,1256.00,6468.22,180.000,YES
PR435,"Q_RES_0402LF-10K,1%,1/16W,EMPTA",10K,1%,R0402,16492.91,5507.35,90.000,NO
PR436,"Q_RES_0402LF-10K,1%,1/16W,EMPTA",10K,1%,R0402,16622.76,5419.61,270.000,YES
PR442,"Q_RES_0402LF-0,5%,1/16W,CHIP,CA",0,5%,R0402,16611.20,6154.62,270.000,NO
PR443,"Q_RES_0402LF-0,5%,1/16W,EMPTY,A",0,5%,R0402,16611.20,6156.62,90.000,YES
PR444,"Q_RES_0402LF-0,5%,1/16W,CHIP,CA",0,5%,R0402,16189.02,14298.96,0.000,NO
PR447,"Q_RES_0402LF-0,5%,1/16W,CHIP,CA",0,5%,R0402,11174.28,14326.04,0.000,NO
PR451,"Q_RES_0402LF-10K,1%,1/16W,EMPTA",10K,1%,R0402,14150.80,14115.04,0.000,YES
PR453,"Q_RES_0402LF-10K,1%,1/16W,EMPTA",10K,1%,R0402,4389.39,14115.04,0.000,YES
PR501,"Q_RES_0402LF-8.25K,0.1%,1/16W,A",8.25K,0.1%,R0402,17024.20,6917.30,0.000,NO
PR502,"Q_RES_0402LF-8.25K,0.1%,1/16W,A",8.25K,0.1%,R0402,880.08,6906.44,0.000,NO
PR519,"Q_RES_0402LF-100,1%,1/16W,CHIPA",100,1%,R0402,15674.56,7321.65,0.000,NO
PR520,"Q_RES_0402LF-100,1%,1/16W,CHIPA",100,1%,R0402,15639.94,5827.17,90.000,NO
PR521,"Q_RES_0402LF-100,1%,1/16W,CHIPA",100,1%,R0402,15674.56,7356.91,0.000,NO
PR522,"Q_RES_0402LF-100,1%,1/16W,CHIPA",100,1%,R0402,15679.94,5827.17,90.000,NO
PR527,"Q_RES_0402LF-100,1%,1/16W,CHIPA",100,1%,R0402,12769.80,13132.52,270.000,YES
PR531,"Q_RES_0402LF-100,1%,1/16W,CHIPA",100,1%,R0402,12769.80,13056.17,90.000,YES
PR558,"Q_RES_0402LF-100,1%,1/16W,CHIPA",100,1%,R0402,2911.20,6307.57,180.000,NO
PR559,"Q_RES_0402LF-100,1%,1/16W,CHIPA",100,1%,R0402,2911.20,6342.83,180.000,NO
PR560,"Q_RES_0402LF-100,1%,1/16W,CHIPA",100,1%,R0402,2242.13,13228.59,180.000,NO
PR561,"Q_RES_0402LF-100,1%,1/16W,CHIPA",100,1%,R0402,2242.13,13268.59,180.000,NO
PR566,"Q_RES_0402LF-100,1%,1/16W,CHIPA",100,1%,R0402,2885.20,5695.48,180.000,NO
PR567,"Q_RES_0402LF-100,1%,1/16W,CHIPA",100,1%,R0402,2893.94,6885.97,180.000,NO
PR568,"Q_RES_0402LF-100,1%,1/16W,CHIPA",100,1%,R0402,2885.20,5660.22,180.000,NO
PR569,"Q_RES_0402LF-100,1%,1/16W,CHIPA",100,1%,R0402,2893.94,6850.71,180.000,NO
PR574,"Q_RES_0402LF-100,1%,1/16W,CHIPA",100,1%,R0402,3008.39,13171.91,270.000,YES
PR578,"Q_RES_0402LF-100,1%,1/16W,CHIPA",100,1%,R0402,3008.39,13095.56,90.000,YES
PR586,"Q_RES_0402LF-100,1%,1/16W,CHIPA",100,1%,R0402,11954.95,13596.36,180.000,NO
PR587,"Q_RES_0402LF-100,1%,1/16W,CHIPA",100,1%,R0402,11954.95,13631.46,180.000,NO
PR591,"Q_RES_0402LF-100,1%,1/16W,CHIPA",100,1%,R0402,15645.79,6594.16,0.000,NO
PR592,"Q_RES_0402LF-100,1%,1/16W,CHIPA",100,1%,R0402,15645.79,6554.16,0.000,NO
PR632,"Q_RES_0402LF-0,5%,1/16W,EMPTY,A",0,5%,R0402,16189.02,14263.66,0.000,NO
PR633,"Q_RES_0402LF-0,5%,1/16W,EMPTY,A",0,5%,R0402,11174.28,14290.74,0.000,NO
PR634,"Q_RES_0402LF-10K,1%,1/16W,EMPTA",10K,1%,R0402,16814.88,4917.90,180.000,NO
PR637,"Q_RES_0402LF-10K,1%,1/16W,EMPTA",10K,1%,R0402,4515.49,14116.78,180.000,YES
PR639,"Q_RES_0402LF-0,5%,1/16W,CHIP,CA",0,5%,R0402,5690.70,13552.47,180.000,NO
PR640,"Q_RES_0402LF-0,5%,1/16W,EMPTY,A",0,5%,R0402,5690.70,13587.77,180.000,NO
PR665,"Q_RES_0402LF-10K,1%,1/16W,EMPTA",10K,1%,R0402,975.14,5128.70,180.000,NO
PR667,"Q_RES_0402LF-10K,1%,1/16W,EMPTA",10K,1%,R0402,1124.97,5152.64,270.000,YES
PR678,"Q_RES_0402LF-0,5%,1/16W,CHIP,CA",0,5%,R0402,2053.20,6753.62,270.000,YES
PR699,"Q_RES_0402LF-0,5%,1/16W,EMPTY,A",0,5%,R0402,2092.20,6753.62,270.000,YES
PR701,"Q_RES_0402LF-0,5%,1/16W,CHIP,CA",0,5%,R0402,6577.36,13963.00,0.000,NO
PR702,"Q_RES_0402LF-0,5%,1/16W,CHIP,CA",0,5%,R0402,1441.17,13962.75,0.000,NO
PR703,"Q_RES_0402LF-0,5%,1/16W,EMPTY,A",0,5%,R0402,6577.36,13927.70,0.000,NO
PR704,"Q_RES_0402LF-0,5%,1/16W,EMPTY,A",0,5%,R0402,1441.17,13927.45,0.000,NO
PR705,"Q_RES_0402LF-10K,1%,1/16W,EMPTA",10K,1%,R0402,1301.81,6436.03,0.000,NO
PR830,"Q_RES_0402LF-15K,0.1%,1/16W,CHA",15K,0.1%,R0402,17621.63,3064.17,90.000,NO
PR831,"Q_RES_0402LF-47K,0.1%,1/16W,CHA",47K,0.1%,R0402,17656.63,3064.17,90.000,NO
PR832,"Q_RES_0402LF-0,5%,1/16W,CHIP,CA",0,5%,R0402,17585.63,3064.17,90.000,NO
PR833,"Q_RES_0402LF-1.5K,1%,1/16W,EMPA",1.5K,1%,R0402,17728.63,3064.17,90.000,NO
PR834,"Q_RES_0402LF-21.5K,1%,1/16W,CHA",21.5K,1%,R0402,17549.63,3064.17,90.000,NO
PR835,"Q_RES_0402LF-0,5%,1/16W,CHIP,CA",0,5%,R0402,17814.43,2956.43,0.000,NO
PR836,"Q_RES_0402LF-1K,1%,1/16W,CHIP,A",1K,1%,R0402,17814.43,2992.43,0.000,NO
PR1101,"Q_RES_0402LF-2K,0.1%,1/16W,CHIA",2K,0.1%,R0402,8086.52,15857.93,180.000,NO
PR1131,"Q_RES_0402LF-2K,0.1%,1/16W,CHIA",2K,0.1%,R0402,7061.12,15756.83,180.000,NO
PR1133,"Q_RES_0402LF-2K,0.1%,1/16W,CHIA",2K,0.1%,R0402,7061.12,15716.83,180.000,NO
PR1134,"Q_RES_0402LF-120K,1%,1/16W,CHIA",120K,1%,R0402,8086.52,16057.93,180.000,NO
PR1297,"Q_RES_0402LF-8.87K,1%,1/16W,EMA",8.87K,1%,R0402,11318.69,14485.02,0.000,NO
PR1298,"Q_RES_0402LF-8.87K,1%,1/16W,EMA",8.87K,1%,R0402,16714.86,14457.94,0.000,NO
PR1299,"Q_RES_0402LF-2.2,1%,1/16W,CHIPA",2.2,1%,R0402,16651.17,14295.22,270.000,YES
PR1300,"Q_RES_0402LF-2.2,1%,1/16W,CHIPA",2.2,1%,R0402,11271.00,14322.55,270.000,YES
PR1301,"Q_RES_0402LF-60.4K,1%,1/16W,CHA",60.4K,1%,R0402,17091.07,7237.85,90.000,NO
PR1303,"Q_RES_0402LF-22.6K,1%,1/16W,CHA",22.6K,1%,R0402,16954.46,7055.18,270.000,NO
PR1304,"Q_RES_0402LF-8.87K,1%,1/16W,EMA",8.87K,1%,R0402,1585.58,14121.73,0.000,NO
PR1305,"Q_RES_0402LF-8.87K,1%,1/16W,EMA",8.87K,1%,R0402,7103.20,14121.98,0.000,NO
PR1306,"Q_RES_0402LF-2.2,1%,1/16W,CHIPA",2.2,1%,R0402,7039.51,13959.26,270.000,YES
PR1307,"Q_RES_0402LF-2.2,1%,1/16W,CHIPA",2.2,1%,R0402,1537.89,13959.26,270.000,YES
PR1310,"Q_RES_0402LF-11.3K,0.1%,1/16W,A",11.3K,0.1%,R0402,14576.09,14059.70,90.000,NO
PR1311,"Q_RES_0402LF-0,5%,1/16W,CHIP,CA",0,5%,R0402,16951.86,4868.06,180.000,YES
PR1314,"Q_RES_0402LF-11.3K,0.1%,1/16W,A",11.3K,0.1%,R0402,4814.68,14059.70,90.000,NO
PR1315,"Q_RES_0402LF-0,5%,1/16W,CHIP,CA",0,5%,R0402,1164.83,6463.27,0.000,YES
PR1322,"Q_RES_0402LF-0,5%,1/16W,CHIP,CA",0,5%,R0402,16220.77,14385.16,270.000,YES
PR1323,"Q_RES_0402LF-0,5%,1/16W,CHIP,CA",0,5%,R0402,11641.72,14455.29,270.000,YES
PR1324,"Q_RES_0402LF-0,5%,1/16W,CHIP,CA",0,5%,R0402,16656.66,14427.81,270.000,YES
PR1325,"Q_RES_0402LF-0,5%,1/16W,CHIP,CA",0,5%,R0402,11217.53,14395.79,270.000,YES
PR1326,"Q_RES_0402LF-0,5%,1/16W,CHIP,CA",0,5%,R0402,10358.33,2641.30,0.000,NO
PR1327,"Q_RES_0402LF-8.45K,1%,1/16W,CHA",8.45K,1%,R0402,10386.06,2977.10,90.000,NO
PR1328,"Q_RES_0402LF-7.32K,0.1%,1/16W,A",7.32K,0.1%,R0402,10258.33,3013.13,0.000,NO
PR1329,"Q_RES_0402LF-5.1,5%,1/16W,CHIPA",5.1,5%,R0402,15042.78,2864.55,90.000,NO
PR1330,"Q_RES_0402LF-150K,1%,1/16W,CHIA",150K,1%,R0402,15046.02,3087.56,90.000,NO
PR1331,"Q_RES_0402LF-0,5%,1/16W,CHIP,CA",0,5%,R0402,6619.42,14032.35,270.000,YES
PR1332,"Q_RES_0402LF-0,5%,1/16W,CHIP,CA",0,5%,R0402,1909.71,14091.70,270.000,YES
PR1333,"Q_RES_0402LF-0,5%,1/16W,CHIP,CA",0,5%,R0402,7018.30,14031.95,270.000,YES
PR1334,"Q_RES_0402LF-0,5%,1/16W,CHIP,CA",0,5%,R0402,1499.90,14077.78,0.000,YES
PR1335,"Q_RES_0402LF-0,5%,1/16W,CHIP,CA",0,5%,R0402,14838.12,14224.94,180.000,NO
PR1336,"Q_RES_0402LF-9.76K,1%,1/16W,CHA",9.76K,1%,R0402,14563.93,14174.93,90.000,NO
PR1337,"Q_RES_0402LF-38.3K,0.1%,1/16W,A",38.3K,0.1%,R0402,14488.42,14059.70,90.000,NO
PR1338,"Q_RES_0402LF-0,5%,1/16W,CHIP,CA",0,5%,R0402,5076.71,14224.94,180.000,NO
PR1339,"Q_RES_0402LF-9.76K,1%,1/16W,CHA",9.76K,1%,R0402,4802.52,14174.93,90.000,NO
PR1340,"Q_RES_0402LF-38.3K,0.1%,1/16W,A",38.3K,0.1%,R0402,4727.01,14059.70,90.000,NO
PR1380,"Q_RES_0402LF-49.9,1%,1/16W,CHIA",49.9,1%,R0402,16806.78,4825.90,180.000,YES
PR1390,"Q_RES_0402LF-49.9,1%,1/16W,CHIA",49.9,1%,R0402,16806.78,4790.78,180.000,YES
PR1400,"Q_RES_0402LF-49.9,1%,1/16W,CHIA",49.9,1%,R0402,1371.91,6529.19,0.000,YES
PR1410,"Q_RES_0402LF-49.9,1%,1/16W,CHIA",49.9,1%,R0402,1371.91,6564.31,0.000,YES
PR1647,"Q_RES_0402LF-10K,1%,1/16W,EMPTA",10K,1%,R0402,10177.20,3093.62,90.000,YES
PR1649,"Q_RES_0402LF-2K,1%,1/16W,CHIP,A",2K,1%,R0402,10200.69,3014.13,270.000,YES
PR1653,"Q_RES_0402LF-470,1%,1/16W,CHIPA",470,1%,R0402,14830.49,3092.57,180.000,YES
PR1707,"Q_RES_0402LF-8.87K,1%,1/16W,EMA",8.87K,1%,R0402,16580.85,7116.11,270.000,NO
PR1708,"Q_RES_0402LF-8.87K,1%,1/16W,EMA",8.87K,1%,R0402,16580.85,6776.11,270.000,NO
PR1709,"Q_RES_0402LF-8.87K,1%,1/16W,EMA",8.87K,1%,R0402,16439.32,6148.45,180.000,NO
PR1726,"Q_RES_0402LF-8.87K,1%,1/16W,EMA",8.87K,1%,R0402,1958.88,6109.71,90.000,NO
PR1727,"Q_RES_0402LF-8.87K,1%,1/16W,EMA",8.87K,1%,R0402,1958.88,5769.71,90.000,NO
PR1728,"Q_RES_0402LF-8.87K,1%,1/16W,EMA",8.87K,1%,R0402,2130.41,6737.37,0.000,NO
PR1746,"Q_RES_0402LF-8.87K,1%,1/16W,EMA",8.87K,1%,R0402,1958.88,6449.71,90.000,NO
PR1766,"Q_RES_0402LF-3.3,1%,1/16W,CHIPA",3.3,1%,R0402,4171.04,13314.18,90.000,NO
PR1767,"Q_RES_0402LF-3.3,1%,1/16W,CHIPA",3.3,1%,R0402,3860.04,13314.18,90.000,NO
PR1768,"Q_RES_0402LF-3.3,1%,1/16W,CHIPA",3.3,1%,R0402,14573.95,13314.10,90.000,NO
PR1769,"Q_RES_0402LF-3.3,1%,1/16W,CHIPA",3.3,1%,R0402,14250.14,13314.18,90.000,NO
PR1770,"Q_RES_0402LF-3.3,1%,1/16W,CHIPA",3.3,1%,R0402,13288.83,13453.93,90.000,NO
PR1771,"Q_RES_0402LF-3.3,1%,1/16W,CHIPA",3.3,1%,R0402,14895.23,13453.93,90.000,NO
PR1772,"Q_RES_0402LF-3.3,1%,1/16W,CHIPA",3.3,1%,R0402,15216.51,13681.91,90.000,NO
PR1773,"Q_RES_0402LF-3.3,1%,1/16W,CHIPA",3.3,1%,R0402,12968.75,13684.27,90.000,NO
PR1774,"Q_RES_0402LF-3.3,1%,1/16W,CHIPA",3.3,1%,R0402,16554.08,6697.91,0.000,NO
PR1775,"Q_RES_0402LF-3.3,1%,1/16W,CHIPA",3.3,1%,R0402,16554.08,7037.91,0.000,NO
PR1776,"Q_RES_0402LF-0,5%,1/16W,CHIP,CA",0,5%,R0402,16477.98,6877.42,180.000,YES
PR1777,"Q_RES_0402LF-0,5%,1/16W,CHIP,CA",0,5%,R0402,16479.16,7217.61,180.000,YES
PR1778,"Q_RES_0402LF-3.3,1%,1/16W,CHIPA",3.3,1%,R0402,16643.60,5985.22,0.000,NO
PR1779,"Q_RES_0402LF-0,5%,1/16W,CHIP,CA",0,5%,R0402,16532.20,6166.62,90.000,NO
PR1780,"Q_RES_0402LF-3.3,1%,1/16W,CHIPA",3.3,1%,R0402,16414.16,14436.66,90.000,NO
PR1781,"Q_RES_0402LF-3.3,1%,1/16W,CHIPA",3.3,1%,R0402,11780.85,14463.74,90.000,NO
PR1782,"Q_RES_0402LF-3.3,1%,1/16W,CHIPA",3.3,1%,R0402,16795.59,14436.66,90.000,NO
PR1783,"Q_RES_0402LF-3.3,1%,1/16W,CHIPA",3.3,1%,R0402,11399.42,14463.74,90.000,NO
PR1784,"Q_RES_0402LF-3.3,1%,1/16W,CHIPA",3.3,1%,R0402,16554.08,6357.91,0.000,NO
PR1785,"Q_RES_0402LF-0,5%,1/16W,CHIP,CA",0,5%,R0402,16477.98,6537.41,180.000,YES
PR1786,"Q_RES_0402LF-3.3,1%,1/16W,CHIPA",3.3,1%,R0402,13932.45,13314.18,90.000,NO
PR1787,"Q_RES_0402LF-3.3,1%,1/16W,CHIPA",3.3,1%,R0402,13621.45,13314.18,90.000,NO
PR1788,"Q_RES_0402LF-3.3,1%,1/16W,CHIPA",3.3,1%,R0402,4812.54,13314.10,90.000,NO
PR1789,"Q_RES_0402LF-3.3,1%,1/16W,CHIPA",3.3,1%,R0402,4488.73,13314.18,90.000,NO
PR1790,"Q_RES_0402LF-3.3,1%,1/16W,CHIPA",3.3,1%,R0402,3527.42,13453.93,90.000,NO
PR1791,"Q_RES_0402LF-3.3,1%,1/16W,CHIPA",3.3,1%,R0402,5133.82,13453.93,90.000,NO
PR1792,"Q_RES_0402LF-3.3,1%,1/16W,CHIPA",3.3,1%,R0402,5455.10,13681.91,90.000,NO
PR1793,"Q_RES_0402LF-3.3,1%,1/16W,CHIPA",3.3,1%,R0402,3206.14,13681.91,90.000,NO
PR1794,"Q_RES_0402LF-3.3,1%,1/16W,CHIPA",3.3,1%,R0402,1985.65,6187.91,180.000,NO
PR1795,"Q_RES_0402LF-3.3,1%,1/16W,CHIPA",3.3,1%,R0402,1985.65,5847.91,180.000,NO
PR1796,"Q_RES_0402LF-0,5%,1/16W,CHIP,CA",0,5%,R0402,2061.36,6008.01,0.000,YES
PR1797,"Q_RES_0402LF-0,5%,1/16W,CHIP,CA",0,5%,R0402,2045.40,5659.82,0.000,YES
PR1798,"Q_RES_0402LF-3.3,1%,1/16W,CHIPA",3.3,1%,R0402,1926.42,6896.83,180.000,NO
PR1799,"Q_RES_0402LF-0,5%,1/16W,CHIP,CA",0,5%,R0402,2012.20,6715.62,270.000,NO
PR1800,"Q_RES_0402LF-3.3,1%,1/16W,CHIPA",3.3,1%,R0402,6802.50,14100.70,90.000,NO
PR1801,"Q_RES_0402LF-3.3,1%,1/16W,CHIPA",3.3,1%,R0402,2041.74,14102.45,90.000,NO
PR1802,"Q_RES_0402LF-3.3,1%,1/16W,CHIPA",3.3,1%,R0402,7183.93,14100.70,90.000,NO
PR1803,"Q_RES_0402LF-3.3,1%,1/16W,CHIPA",3.3,1%,R0402,1666.31,14109.45,90.000,NO
PR1804,"Q_RES_0402LF-3.3,1%,1/16W,CHIPA",3.3,1%,R0402,1985.65,6527.91,180.000,NO
PR1805,"Q_RES_0402LF-0,5%,1/16W,CHIP,CA",0,5%,R0402,2060.46,6348.82,0.000,YES
PR1850,"Q_RES_0402LF-1K,1%,1/16W,EMPTYA",1K,1%,R0402,15163.00,3127.12,0.000,YES
PR2106,"Q_RES_0402LF-10K,1%,1/16W,CHIPA",10K,1%,R0402,7065.12,15956.23,180.000,YES
PR2149,"Q_RES_0402LF-0,5%,1/16W,CHIP,CA",0,5%,R0402,7061.12,15916.83,0.000,YES
PR2220,"Q_RES_0402LF-60.4K,1%,1/16W,CHA",60.4K,1%,R0402,972.50,7188.80,0.000,NO
PR2222,"Q_RES_0402LF-34.8K,1%,1/16W,CHA",34.8K,1%,R0402,820.14,7010.92,270.000,NO
PR2336,"Q_RES_0402LF-26.1K,0.1%,1/16W,A",26.1K,0.1%,R0402,14447.20,14059.62,90.000,NO
PR2381,"Q_RES_0402LF-26.1K,0.1%,1/16W,A",26.1K,0.1%,R0402,4686.20,14059.62,90.000,NO
PR2510,"Q_RES_0402LF-1,1%,1/16W,EMPTY,A",1,1%,R0402,11750.95,15867.38,90.000,YES
PR2511,"Q_RES_0402LF-1,1%,1/16W,EMPTY,A",1,1%,R0402,11456.87,15867.38,90.000,YES
PR2512,"Q_RES_0402LF-1,1%,1/16W,EMPTY,A",1,1%,R0402,11650.95,15867.38,90.000,YES
PR2513,"Q_RES_0402LF-1,1%,1/16W,EMPTY,A",1,1%,R0402,11556.87,15867.38,90.000,YES
PR2514,"Q_RES_0402LF-10,1%,1/16W,EMPTYA",10,1%,R0402,11356.87,15867.38,90.000,YES
PR2515,"Q_RES_0402LF-10,1%,1/16W,EMPTYA",10,1%,R0402,11710.95,15867.38,90.000,YES
PR2516,"Q_RES_0402LF-10,1%,1/16W,EMPTYA",10,1%,R0402,11416.87,15867.38,90.000,YES
PR2517,"Q_RES_0402LF-10,1%,1/16W,EMPTYA",10,1%,R0402,11610.95,15867.38,90.000,YES
PR2518,"Q_RES_0402LF-10,1%,1/16W,EMPTYA",10,1%,R0402,11516.87,15867.38,90.000,YES
PR2519,"Q_RES_0402LF-100,1%,1/16W,EMPTA",100,1%,R0402,11316.87,15867.38,90.000,YES
PR2520,"Q_RES_0402LF-1,1%,1/16W,EMPTY,A",1,1%,R0402,11750.95,15787.38,270.000,YES
PR2521,"Q_RES_0402LF-1,1%,1/16W,EMPTY,A",1,1%,R0402,11456.87,15787.38,270.000,YES
PR2522,"Q_RES_0402LF-1,1%,1/16W,EMPTY,A",1,1%,R0402,11650.95,15787.38,270.000,YES
PR2523,"Q_RES_0402LF-1,1%,1/16W,EMPTY,A",1,1%,R0402,11556.87,15787.38,270.000,YES
PR2524,"Q_RES_0402LF-10,1%,1/16W,EMPTYA",10,1%,R0402,11710.95,15787.38,270.000,YES
PR2525,"Q_RES_0402LF-10,1%,1/16W,EMPTYA",10,1%,R0402,11416.87,15787.38,270.000,YES
PR2526,"Q_RES_0402LF-10,1%,1/16W,EMPTYA",10,1%,R0402,11610.95,15787.38,270.000,YES
PR2527,"Q_RES_0402LF-10,1%,1/16W,EMPTYA",10,1%,R0402,11516.87,15787.38,270.000,YES
PR2528,"Q_RES_0402LF-10,1%,1/16W,EMPTYA",10,1%,R0402,10097.11,15518.55,0.000,NO
PR2529,"Q_RES_0402LF-10,1%,1/16W,EMPTYA",10,1%,R0402,10330.77,15518.55,0.000,NO
PR2530,"Q_RES_0402LF-10,1%,1/16W,EMPTYA",10,1%,R0402,10564.43,15518.55,0.000,NO
PR2531,"Q_RES_0402LF-10,1%,1/16W,EMPTYA",10,1%,R0402,10798.09,15518.55,0.000,NO
PR2532,"Q_SP_RES4P-0.0003,1%,4W,SMLF,EA",,,R2725_4P,10583.98,16040.00,270.000,NO
PR2533,"Q_SP_RES4P-0.0003,1%,4W,SMLF,EA",,,R2725_4P,9951.98,16040.00,270.000,NO
PR2534,"Q_SP_RES4P-0.0003,1%,4W,SMLF,EA",,,R2725_4P,10267.98,16040.00,270.000,NO
PR2535,"Q_RES_0402LF-10,1%,1/16W,EMPTYA",10,1%,R0402,9629.79,15518.55,0.000,NO
PR2536,"Q_RES_0402LF-10,1%,1/16W,EMPTYA",10,1%,R0402,9863.45,15518.55,0.000,NO
PR2537,"Q_RES_0402LF-10,1%,1/16W,EMPTYA",10,1%,R0402,9586.46,15632.56,180.000,YES
PR2538,"Q_RES_0402LF-10,1%,1/16W,EMPTYA",10,1%,R0402,11031.75,15518.55,0.000,NO
PR2554,"Q_RES_2512LF-0.03,0.1%,1W,EMPTA",0.03,0.1%,R2512,13387.27,13973.55,90.000,YES
PR2556,"Q_RES_2512LF-0.03,0.1%,1W,EMPTA",0.03,0.1%,R2512,3660.37,13977.65,90.000,YES
PR2718,"Q_RES_0402LF-8.87K,1%,1/16W,EMA",8.87K,1%,R0402,16580.85,6436.11,270.000,NO
PR3002,"Q_RES_0402LF-0,5%,1/16W,CHIP,CA",0,5%,R0402,7061.12,15836.83,0.000,NO
PR3335,"Q_RES_0402LF-30.1K,1%,1/16W,CHA",30.1K,1%,R0402,14657.47,14153.65,270.000,YES
PR3336,"Q_RES_0402LF-30.1K,1%,1/16W,CHA",30.1K,1%,R0402,4885.70,14148.21,270.000,YES
PR3337,"Q_RES_0402LF-0,5%,1/16W,CHIP,CA",0,5%,R0402,17939.70,15056.52,0.000,YES
PR3338,"Q_RES_0402LF-0,5%,1/16W,CHIP,CA",0,5%,R0402,874.78,7256.40,180.000,YES
PR3339,"Q_RES_0402LF-0,5%,1/16W,CHIP,CA",0,5%,R0402,17034.60,7265.52,0.000,NO
PR3780,"Q_RES_0402LF-5.36K,1%,1/16W,CHA",5.36K,1%,R0402,17011.24,4296.75,90.000,NO
PR3781,"Q_RES_0402LF-845,1%,1/16W,CHIPA",845,1%,R0402,17625.48,871.07,180.000,NO
PR3782,"Q_RES_0402LF-10,1%,1/16W,CHIP,A",10,1%,R0402,3422.49,2255.09,90.000,NO
PR3786,"Q_RES_0402LF-160K,1%,1/16W,CHIA",160K,1%,R0402,17620.38,726.37,0.000,NO
PR3787,"Q_RES_0402LF-6.8K,1%,1/16W,CHIA",6.8K,1%,R0402,17676.38,711.16,270.000,NO
PR3788,"Q_RES_0402LF-15K,1%,1/16W,CHIPA",15K,1%,R0402,17620.38,686.37,180.000,NO
PR3789,"Q_RES_0402LF-25.5K,1%,1/16W,CHA",25.5K,1%,R0402,16901.54,4301.85,270.000,NO
PR3790,"Q_RES_0402LF-7.15K,1%,1/16W,CHA",7.15K,1%,R0402,16886.33,4246.94,180.000,NO
PR3791,"Q_RES_0402LF-15K,1%,1/16W,CHIPA",15K,1%,R0402,16861.54,4301.85,90.000,NO
PR3792,"Q_RES_0402LF-10,1%,1/16W,CHIP,A",10,1%,R0402,17718.91,988.20,270.000,NO
PR3795,"Q_RES_0402LF-25.5K,1%,1/16W,CHA",25.5K,1%,R0402,3179.95,2337.49,270.000,NO
PR3798,"Q_RES_0402LF-10,1%,1/16W,CHIP,A",10,1%,R0402,17165.27,4203.40,180.000,NO
PR3805,"Q_RES_0402LF-160K,1%,1/16W,CHIA",160K,1%,R0402,2969.17,715.13,0.000,NO
PR3806,"Q_RES_0402LF-6.8K,1%,1/16W,CHIA",6.8K,1%,R0402,3025.17,699.92,270.000,NO
PR3812,"Q_RES_0402LF-15K,1%,1/16W,CHIPA",15K,1%,R0402,3139.95,2337.49,90.000,NO
PR3821,"Q_RES_0402LF-30.1K,1%,1/16W,CHA",30.1K,1%,R0402,2974.27,824.83,180.000,NO
PR3822,"Q_RES_0402LF-5.36K,1%,1/16W,CHA",5.36K,1%,R0402,3289.65,2332.39,90.000,NO
PR3823,"Q_RES_0402LF-845,1%,1/16W,CHIPA",845,1%,R0402,2974.27,859.83,180.000,NO
PR3824,"Q_RES_0402LF-4.53K,1%,1/16W,CHA",4.53K,1%,R0402,3324.65,2332.39,90.000,NO
PR3828,"Q_RES_0402LF-15K,1%,1/16W,CHIPA",15K,1%,R0402,2969.17,675.13,180.000,NO
PR3829,"Q_RES_0402LF-7.15K,1%,1/16W,CHA",7.15K,1%,R0402,3164.74,2282.58,180.000,NO
PR3830,"Q_RES_0402LF-10,1%,1/16W,CHIP,A",10,1%,R0402,3053.15,972.99,270.000,NO
PR3835,"Q_RES_0402LF-14.3K,1%,1/16W,EMA",14.3K,1%,R0402,17434.18,1301.67,90.000,NO
PR3837,"Q_RES_0402LF-17.4K,1%,1/16W,EMA",17.4K,1%,R0402,17254.18,1266.67,90.000,NO
PR3838,"Q_RES_0402LF-100,1%,1/16W,EMPTA",100,1%,R0402,17346.18,887.87,180.000,NO
PR3839,"Q_RES_0402LF-10K,1%,1/16W,EMPTA",10K,1%,R0402,17239.18,1168.67,180.000,NO
PR3840,"Q_RES_0402LF-71.5K,1%,1/16W,EMA",71.5K,1%,R0402,17186.08,1073.84,90.000,NO
PR3841,"Q_RES_0402LF-120K,1%,1/16W,EMPA",120K,1%,R0402,17226.08,1073.84,90.000,NO
PR3842,"Q_RES_0402LF-10K,1%,1/16W,EMPTA",10K,1%,R0402,17266.08,1073.84,270.000,NO
PR3843,"Q_RES_0603LF-49.9,1%,1/10W,EMPA",49.9,1%,R0603,17295.08,938.57,0.000,NO
PR3844,"Q_RES_0402LF-71.5K,1%,1/16W,EMA",71.5K,1%,R0402,16636.10,3987.02,270.000,NO
PR3846,"Q_RES_0402LF-1.33K,1%,1/16W,EMA",1.33K,1%,R0402,16526.10,3987.02,90.000,NO
PR3847,"Q_RES_0402LF-14.3K,1%,1/16W,EMA",14.3K,1%,R0402,2682.97,1290.43,90.000,NO
PR3849,"Q_RES_0402LF-17.4K,1%,1/16W,EMA",17.4K,1%,R0402,2502.97,1255.43,90.000,NO
PR3850,"Q_RES_0402LF-100,1%,1/16W,EMPTA",100,1%,R0402,2592.97,875.43,180.000,NO
PR3851,"Q_RES_0402LF-10K,1%,1/16W,EMPTA",10K,1%,R0402,2487.97,1157.43,180.000,NO
PR3852,"Q_RES_0402LF-71.5K,1%,1/16W,EMA",71.5K,1%,R0402,2434.87,1062.60,90.000,NO
PR3853,"Q_RES_0402LF-120K,1%,1/16W,EMPA",120K,1%,R0402,2474.87,1062.60,90.000,NO
PR3854,"Q_RES_0402LF-10K,1%,1/16W,EMPTA",10K,1%,R0402,2514.87,1062.60,270.000,NO
PR3855,"Q_RES_0402LF-71.5K,1%,1/16W,EMA",71.5K,1%,R0402,2792.80,2108.02,0.000,NO
PR3856,"Q_RES_0402LF-1.33K,1%,1/16W,EMA",1.33K,1%,R0402,2642.20,2140.22,0.000,NO
PR3857,"Q_RES_0603LF-49.9,1%,1/10W,EMPA",49.9,1%,R0603,2543.87,927.33,0.000,NO
PR3910,"Q_RES_0402LF-0,5%,1/16W,CHIP,CA",0,5%,R0402,7651.88,15867.01,270.000,YES
PR3911,"Q_RES_0402LF-0,5%,1/16W,CHIP,CA",0,5%,R0402,8082.97,15897.83,270.000,YES
PR3912,"Q_RES_0402LF-120K,1%,1/16W,CHIA",120K,1%,R0402,8506.52,16057.93,180.000,NO
PR3914,"Q_RES_0402LF-2K,0.1%,1/16W,CHIA",2K,0.1%,R0402,7671.52,15778.93,180.000,NO
PR3915,"Q_RES_0402LF-2K,0.1%,1/16W,CHIA",2K,0.1%,R0402,8086.52,15817.93,180.000,NO
PR3916,"Q_RES_0402LF-0,5%,1/16W,CHIP,CA",0,5%,R0402,7671.52,15948.93,0.000,NO
PR3917,"Q_RES_0402LF-0,5%,1/16W,CHIP,CA",0,5%,R0402,8086.52,16097.93,0.000,NO
PR3918,"Q_RES_0402LF-2K,0.1%,1/16W,CHIA",2K,0.1%,R0402,7671.52,15818.93,180.000,NO
PR3919,"Q_RES_0402LF-0,5%,1/16W,CHIP,CA",0,5%,R0402,8086.52,15777.93,0.000,NO
PR3920,"Q_RES_0402LF-0,5%,1/16W,CHIP,CA",0,5%,R0402,8086.52,16017.93,0.000,NO
PR3921,"Q_RES_0402LF-0,5%,1/16W,CHIP,CA",0,5%,R0402,8506.52,15777.93,0.000,NO
PR3922,"Q_RES_0402LF-0,5%,1/16W,CHIP,CA",0,5%,R0402,8506.52,16017.93,0.000,NO
PR3926,"Q_RES_0402LF-75K,0.1%,1/16W,CHA",75K,0.1%,R0402,7292.52,16098.93,180.000,NO
PR3927,"Q_RES_0402LF-4.99K,0.1%,1/16W,A",4.99K,0.1%,R0402,7243.92,16057.63,270.000,YES
PR3928,"Q_RES_0402LF-0,5%,1/16W,CHIP,CA",0,5%,R0402,7561.12,15831.83,180.000,NO
PR3929,"Q_RES_0402LF-1K,1%,1/16W,EMPTYA",1K,1%,R0402,7061.42,15637.33,0.000,YES
PR3930,"Q_RES_0402LF-0,5%,1/16W,CHIP,CA",0,5%,R0402,7061.42,15637.33,0.000,NO
PR3931,"Q_RES_0402LF-75K,0.1%,1/16W,CHA",75K,0.1%,R0402,7282.52,15694.93,0.000,YES
PR3932,"Q_RES_0402LF-4.99K,0.1%,1/16W,A",4.99K,0.1%,R0402,7211.52,15694.93,0.000,YES
PR3935,"Q_RES_0402LF-10K,1%,1/16W,CHIPA",10K,1%,R0402,7061.12,15916.83,180.000,NO
PR3937,"Q_RES_0402LF-120K,1%,1/16W,CHIA",120K,1%,R0402,7561.12,15921.83,0.000,NO
PR3944,"Q_RES_0402LF-46.4K,1%,1/16W,EMA",46.4K,1%,R0402,10172.20,1990.76,0.000,NO
PR3945,"Q_RES_0402LF-71.5K,1%,1/16W,EMA",71.5K,1%,R0402,7496.60,2653.22,180.000,NO
PR3947,"Q_RES_0402LF-2.8K,1%,1/16W,EMPA",2.8K,1%,R0402,7496.60,2763.22,0.000,NO
PR3949,"Q_RES_0402LF-56K,1%,1/16W,EMPTA",56K,1%,R0402,10151.95,2144.23,0.000,NO
PR3950,"Q_RES_0402LF-100,1%,1/16W,EMPTA",100,1%,R0402,9771.95,2054.23,90.000,NO
PR3951,"Q_RES_0402LF-10K,1%,1/16W,EMPTA",10K,1%,R0402,10053.95,2159.23,90.000,NO
PR3952,"Q_RES_0402LF-71.5K,1%,1/16W,EMA",71.5K,1%,R0402,9959.12,2212.33,0.000,NO
PR3953,"Q_RES_0402LF-120K,1%,1/16W,EMPA",120K,1%,R0402,9959.12,2172.33,0.000,NO
PR3954,"Q_RES_0402LF-10K,1%,1/16W,EMPTA",10K,1%,R0402,9959.12,2132.33,180.000,NO
PR3957,"Q_RES_0603LF-49.9,1%,1/10W,EMPA",49.9,1%,R0603,9823.85,2103.33,270.000,NO
PR3960,"Q_RES_0402LF-160K,1%,1/16W,CHIA",160K,1%,R0402,9854.45,1770.83,270.000,NO
PR3961,"Q_RES_0402LF-6.8K,1%,1/16W,CHIA",6.8K,1%,R0402,9839.24,1714.83,180.000,NO
PR3962,"Q_RES_0402LF-15K,1%,1/16W,CHIPA",15K,1%,R0402,9814.45,1770.83,90.000,NO
PR3963,"Q_RES_0402LF-25.5K,1%,1/16W,CHA",25.5K,1%,R0402,8578.03,2690.57,0.000,NO
PR3964,"Q_RES_0402LF-7.15K,1%,1/16W,CHA",7.15K,1%,R0402,8632.94,2675.36,270.000,NO
PR3965,"Q_RES_0402LF-15K,1%,1/16W,CHIPA",15K,1%,R0402,8578.03,2650.57,180.000,NO
PR3966,"Q_RES_0402LF-10,1%,1/16W,CHIP,A",10,1%,R0402,10113.76,1672.78,180.000,NO
PR3967,"Q_RES_0402LF-10,1%,1/16W,CHIP,A",10,1%,R0402,8675.71,2953.85,270.000,NO
PR3968,"Q_RES_0402LF-9.31K,1%,1/16W,CHA",9.31K,1%,R0402,9964.15,1765.73,90.000,NO
PR3969,"Q_RES_0402LF-2.49K,1%,1/16W,CHA",2.49K,1%,R0402,8583.13,2800.27,180.000,NO
PR3970,"Q_RES_0402LF-2.67K,1%,1/16W,CHA",2.67K,1%,R0402,9999.15,1765.73,90.000,NO
PR3971,"Q_RES_0402LF-9.76K,1%,1/16W,CHA",9.76K,1%,R0402,8583.13,2835.27,180.000,NO
PR3980,"Q_RES_0402LF-0,5%,1/16W,CHIP,CA",0,5%,R0402,8504.15,15892.47,270.000,YES
PR3981,"Q_RES_0402LF-0,5%,1/16W,CHIP,CA",0,5%,R0402,8923.32,15896.43,270.000,YES
PR3982,"Q_RES_0402LF-120K,1%,1/16W,CHIA",120K,1%,R0402,8926.52,16057.93,180.000,NO
PR3984,"Q_RES_0402LF-120K,1%,1/16W,CHIA",120K,1%,R0402,9346.52,15933.93,180.000,NO
PR3986,"Q_RES_0402LF-2K,0.1%,1/16W,CHIA",2K,0.1%,R0402,8506.52,15817.93,180.000,NO
PR3987,"Q_RES_0402LF-2K,0.1%,1/16W,CHIA",2K,0.1%,R0402,8926.52,15817.93,180.000,NO
PR3988,"Q_RES_0402LF-0,5%,1/16W,CHIP,CA",0,5%,R0402,8506.52,16097.93,0.000,NO
PR3989,"Q_RES_0402LF-0,5%,1/16W,CHIP,CA",0,5%,R0402,8926.52,16097.93,0.000,NO
PR3990,"Q_RES_0402LF-2K,0.1%,1/16W,CHIA",2K,0.1%,R0402,8506.52,15857.93,180.000,NO
PR3991,"Q_RES_0402LF-2K,0.1%,1/16W,CHIA",2K,0.1%,R0402,8926.52,15857.93,180.000,NO
PR3992,"Q_RES_0402LF-0,5%,1/16W,CHIP,CA",0,5%,R0402,8926.52,15777.93,0.000,NO
PR3993,"Q_RES_0402LF-0,5%,1/16W,CHIP,CA",0,5%,R0402,8926.52,16017.93,0.000,NO
PR3994,"Q_RES_0402LF-0,5%,1/16W,CHIP,CA",0,5%,R0402,9346.52,15813.93,0.000,NO
PR3995,"Q_RES_0402LF-0,5%,1/16W,CHIP,CA",0,5%,R0402,9346.52,15893.93,0.000,NO
PR3999,"Q_RES_0402LF-24.3K,1%,1/16W,EMA",24.3K,1%,R0402,7009.63,1297.28,90.000,NO
PR4000,"Q_RES_0402LF-160K,1%,1/16W,CHIA",160K,1%,R0402,7314.93,909.98,0.000,NO
PR4001,"Q_RES_0402LF-6.8K,1%,1/16W,CHIA",6.8K,1%,R0402,7370.93,894.77,270.000,NO
PR4002,"Q_RES_0402LF-15K,1%,1/16W,CHIPA",15K,1%,R0402,7314.93,869.98,180.000,NO
PR4003,"Q_RES_0402LF-10,1%,1/16W,CHIP,A",10,1%,R0402,7412.70,1171.59,270.000,NO
PR4004,"Q_RES_0402LF-17.8K,1%,1/16W,CHA",17.8K,1%,R0402,7320.03,1019.68,180.000,NO
PR4005,"Q_RES_0402LF-30.1K,1%,1/16W,EMA",30.1K,1%,R0402,6834.53,1296.68,90.000,NO
PR4006,"Q_RES_0402LF-100,1%,1/16W,EMPTA",100,1%,R0402,6924.53,916.68,180.000,NO
PR4007,"Q_RES_0402LF-10K,1%,1/16W,EMPTA",10K,1%,R0402,6819.53,1195.68,180.000,NO
PR4008,"Q_RES_0402LF-1.33K,1%,1/16W,CHA",1.33K,1%,R0402,7320.03,1054.68,180.000,NO
PR4009,"Q_RES_0402LF-71.5K,1%,1/16W,EMA",71.5K,1%,R0402,6766.43,1103.85,90.000,NO
PR4010,"Q_RES_0402LF-120K,1%,1/16W,EMPA",120K,1%,R0402,6806.23,1103.85,90.000,NO
PR4011,"Q_RES_0402LF-10K,1%,1/16W,EMPTA",10K,1%,R0402,6846.43,1103.85,270.000,NO
PR4012,"Q_RES_0402LF-0,5%,1/16W,CHIP,CA",0,5%,R0402,7586.18,893.48,0.000,NO
PR4014,"Q_RES_0603LF-49.9,1%,1/10W,EMPA",49.9,1%,R0603,6875.43,968.58,0.000,NO
PR4217,"Q_RES_0402LF-0,5%,1/16W,EMPTY,A",0,5%,R0402,11261.00,14462.82,270.000,YES
PR4218,"Q_RES_0402LF-0,5%,1/16W,EMPTY,A",0,5%,R0402,14069.63,14035.45,270.000,YES
PR4219,"Q_RES_0402LF-499,1%,1/16W,CHIPA",499,1%,R0402,13674.20,12800.62,270.000,YES
PR4220,"Q_RES_0402LF-0,5%,1/16W,CHIP,CA",0,5%,R0402,16680.47,5345.24,180.000,YES
PR4221,"Q_RES_0402LF-0,5%,1/16W,CHIP,CA",0,5%,R0402,16800.40,5656.52,90.000,NO
PR4222,"Q_RES_0402LF-0,5%,1/16W,CHIP,CA",0,5%,R0402,16760.40,5656.52,90.000,NO
PR4223,"Q_RES_0402LF-0,5%,1/16W,CHIP,CA",0,5%,R0402,16720.40,5656.52,90.000,NO
PR4224,"Q_RES_0402LF-0,5%,1/16W,CHIP,CA",0,5%,R0402,16680.40,5656.52,90.000,NO
PR4225,"Q_RES_0402LF-0,5%,1/16W,CHIP,CA",0,5%,R0402,16640.40,5656.52,90.000,NO
PR4226,"Q_RES_0402LF-499,1%,1/16W,CHIPA",499,1%,R0402,16059.20,7250.62,180.000,YES
PR4227,"Q_RES_0402LF-0,5%,1/16W,EMPTY,A",0,5%,R0402,16634.50,6073.32,0.000,YES
PR4228,"Q_RES_0402LF-0,5%,1/16W,EMPTY,A",0,5%,R0402,16572.20,6166.62,90.000,NO
PR4229,"Q_RES_0402LF-499,1%,1/16W,CHIPA",499,1%,R0402,16115.20,5833.62,180.000,YES
PR4230,"Q_RES_0402LF-0,5%,1/16W,CHIP,CA",0,5%,R0402,17037.20,5053.62,90.000,NO
PR4231,"Q_RES_0402LF-0,5%,1/16W,CHIP,CA",0,5%,R0402,16987.20,5053.62,90.000,NO
PR4232,"Q_RES_0402LF-0,5%,1/16W,CHIP,CA",0,5%,R0402,17117.20,4918.62,90.000,YES
PR4233,"Q_RES_0402LF-0,5%,1/16W,CHIP,CA",0,5%,R0402,17057.20,4918.62,90.000,YES
PR4234,"Q_RES_0402LF-0,5%,1/16W,CHIP,CA",0,5%,R0402,16997.20,4918.62,90.000,YES
PR4235,"Q_RES_0402LF-0,5%,1/16W,CHIP,CA",0,5%,R0402,16991.50,5070.52,270.000,YES
PR4236,"Q_RES_0402LF-0,5%,1/16W,CHIP,CA",0,5%,R0402,16943.39,4927.78,90.000,YES
PR4237,"Q_RES_0402LF-499,1%,1/16W,CHIPA",499,1%,R0402,15622.92,6510.39,180.000,NO
PR4238,"Q_RES_0402LF-0,5%,1/16W,EMPTY,A",0,5%,R0402,4243.20,14035.62,270.000,YES
PR4239,"Q_RES_0402LF-0,5%,1/16W,EMPTY,A",0,5%,R0402,4309.10,14035.72,270.000,YES
PR4240,"Q_RES_0402LF-499,1%,1/16W,CHIPA",499,1%,R0402,3908.20,12798.62,270.000,YES
PR4241,"Q_RES_0402LF-499,1%,1/16W,CHIPA",499,1%,R0402,1441.20,13573.12,270.000,YES
PR4242,"Q_RES_0402LF-0,5%,1/16W,CHIP,CA",0,5%,R0402,1273.77,5434.55,90.000,NO
PR4243,"Q_RES_0402LF-0,5%,1/16W,CHIP,CA",0,5%,R0402,1232.57,5433.85,90.000,NO
PR4244,"Q_RES_0402LF-0,5%,1/16W,CHIP,CA",0,5%,R0402,1190.87,5432.95,90.000,NO
PR4245,"Q_RES_0402LF-0,5%,1/16W,CHIP,CA",0,5%,R0402,1150.60,5432.22,90.000,NO
PR4246,"Q_RES_0402LF-0,5%,1/16W,CHIP,CA",0,5%,R0402,1109.87,5432.15,90.000,NO
PR4247,"Q_RES_0402LF-499,1%,1/16W,CHIPA",499,1%,R0402,2484.65,5986.32,180.000,NO
PR4248,"Q_RES_0402LF-0,5%,1/16W,EMPTY,A",0,5%,R0402,1935.20,6810.62,0.000,YES
PR4249,"Q_RES_0402LF-0,5%,1/16W,EMPTY,A",0,5%,R0402,1951.70,6750.92,180.000,NO
PR4250,"Q_RES_0402LF-499,1%,1/16W,CHIPA",499,1%,R0402,2428.77,7048.25,0.000,YES
PR4251,"Q_RES_0402LF-0,5%,1/16W,CHIP,CA",0,5%,R0402,980.13,6421.49,180.000,YES
PR4252,"Q_RES_0402LF-0,5%,1/16W,CHIP,CA",0,5%,R0402,979.83,6460.09,180.000,YES
PR4253,"Q_RES_0402LF-0,5%,1/16W,CHIP,CA",0,5%,R0402,979.43,6498.39,180.000,YES
PR4254,"Q_RES_0402LF-0,5%,1/16W,CHIP,CA",0,5%,R0402,1054.00,6410.62,270.000,YES
PR4255,"Q_RES_0402LF-0,5%,1/16W,CHIP,CA",0,5%,R0402,1092.00,6388.62,270.000,YES
PR4256,"Q_RES_0402LF-0,5%,1/16W,CHIP,CA",0,5%,R0402,1129.00,6394.62,270.000,YES
PR4257,"Q_RES_0402LF-0,5%,1/16W,CHIP,CA",0,5%,R0402,1190.00,6427.62,0.000,YES
PR4258,"Q_RES_0402LF-499,1%,1/16W,CHIPA",499,1%,R0402,2481.66,6338.48,180.000,NO
PR4265,"Q_RES_0402LF-499,1%,1/16W,CHIPA",499,1%,R0402,11174.20,13938.13,270.000,YES
PR4271,"Q_RES_0402LF-2.2,1%,1/16W,CHIPA",2.2,1%,R0402,17143.20,7062.62,90.000,NO
PR4272,"Q_RES_0402LF-2.2,1%,1/16W,CHIPA",2.2,1%,R0402,1009.31,7037.77,90.000,NO
PR4522,"Q_RES_0402LF-10M,1%,1/16W,CHIPA",10M,1%,R0402,3186.03,998.37,180.000,NO
PR4523,"Q_RES_0402LF-10M,1%,1/16W,CHIPA",10M,1%,R0402,3462.03,2121.27,90.000,NO
PR4524,"Q_RES_0402LF-10M,1%,1/16W,CHIPA",10M,1%,R0402,17836.36,1009.39,180.000,NO
PR4525,"Q_RES_0402LF-10M,1%,1/16W,CHIPA",10M,1%,R0402,17189.31,4085.37,90.000,NO
PR4526,"Q_RES_0402LF-10M,1%,1/16W,CHIPA",10M,1%,R0402,7531.35,1191.72,180.000,NO
PR4527,"Q_RES_0402LF-10M,1%,1/16W,CHIPA",10M,1%,R0402,8794.66,2986.65,180.000,NO
PR4528,"Q_RES_0402LF-10M,1%,1/16W,CHIPA",10M,1%,R0402,10152.75,1554.49,90.000,NO
PR4540,"Q_RES_0402LF-20K,1%,1/16W,EMPTA",20K,1%,R0402,6967.60,1297.32,270.000,YES
PR4541,"Q_RES_0402LF-20K,1%,1/16W,EMPTA",20K,1%,R0402,10143.30,1946.09,180.000,YES
PR4683,"Q_RES_0402LF-0,5%,1/16W,CHIP,CA",0,5%,R0402,17241.55,6882.11,0.000,NO
PR4698,"Q_RES_0402LF-0,5%,1/16W,EMPTY,A",0,5%,R0402,17131.59,6897.75,90.000,NO
PR4699,"Q_RES_0402LF-0,5%,1/16W,CHIP,CA",0,5%,R0402,1085.95,6854.90,0.000,NO
PR4700,"Q_RES_0402LF-0,5%,1/16W,EMPTY,A",0,5%,R0402,975.49,6870.65,90.000,NO
PR5481,"Q_RES_0402LF-4.53K,1%,1/16W,CHA",4.53K,1%,R0402,17046.24,4296.75,90.000,NO
PR5484,"Q_RES_0402LF-30.1K,1%,1/16W,CHA",30.1K,1%,R0402,17625.48,836.07,180.000,NO
PU6_P0_8,ISL99390FRZTR5935-ISL99390FRZ-A,,,QFN21_6X5XB,15186.62,13500.67,0.000,NO
PU7_P0_7,ISL99390FRZTR5935-ISL99390FRZ-A,,,QFN21_6X5XB,12938.86,13503.03,0.000,NO
PU8_P0_6,ISL99390FRZTR5935-ISL99390FRZ-A,,,QFN21_6X5XB,13258.94,13272.69,0.000,NO
PU9_P0_5,ISL99390FRZTR5935-ISL99390FRZ-A,,,QFN21_6X5XB,14865.34,13272.69,0.000,NO
PU10_P0_4,ISL99390FRZTR5935-ISL99390FRZ-A,,,QFN21_6X5XB,14544.06,13138.43,0.000,NO
PU11_P0_3,ISL99390FRZTR5935-ISL99390FRZ-A,,,QFN21_6X5XB,14222.78,13138.43,0.000,NO
PU12_P0_2,ISL99390FRZTR5935-ISL99390FRZ-A,,,QFN21_6X5XB,13901.50,13138.43,0.000,NO
PU13_P0_1,ISL99390FRZTR5935-ISL99390FRZ-A,,,QFN21_6X5XB,13580.22,13138.43,0.000,NO
PU23_P1_8,ISL99390FRZTR5935-ISL99390FRZ-A,,,QFN21_6X5XB,5425.21,13500.67,0.000,NO
PU24_P1_7,ISL99390FRZTR5935-ISL99390FRZ-A,,,QFN21_6X5XB,3176.25,13500.67,0.000,NO
PU25_P1_6,ISL99390FRZTR5935-ISL99390FRZ-A,,,QFN21_6X5XB,3497.53,13272.69,0.000,NO
PU26_P1_5,ISL99390FRZTR5935-ISL99390FRZ-A,,,QFN21_6X5XB,5103.93,13272.69,0.000,NO
PU27_P1_4,ISL99390FRZTR5935-ISL99390FRZ-A,,,QFN21_6X5XB,4782.65,13138.43,0.000,NO
PU28_P1_3,ISL99390FRZTR5935-ISL99390FRZ-A,,,QFN21_6X5XB,4461.37,13138.43,0.000,NO
PU30_P1_2,ISL99390FRZTR5935-ISL99390FRZ-A,,,QFN21_6X5XB,4140.09,13138.43,0.000,NO
PU31_P1_1,ISL99390FRZTR5935-ISL99390FRZ-A,,,QFN21_6X5XB,3818.81,13138.43,0.000,NO
PU43_P0_1,ISL99390FRZTR5935-ISL99390FRZ-A,,,QFN21_6X5XB,16378.33,6725.27,270.000,NO
PU44_P0_2,ISL99390FRZTR5935-ISL99390FRZ-A,,,QFN21_6X5XB,16378.33,7065.27,270.000,NO
PU50_P1_1,ISL99390FRZTR5935-ISL99390FRZ-A,,,QFN21_6X5XB,2161.40,6160.55,90.000,NO
PU51_P1_2,ISL99390FRZTR5935-ISL99390FRZ-A,,,QFN21_6X5XB,2161.40,5820.55,90.000,NO
PU69_P0_1,ISL99390FRZTR5935-ISL99390FRZ-A,,,QFN21_6X5XB,16384.27,14255.42,0.000,NO
PU70_P0_2,ISL99390FRZTR5935-ISL99390FRZ-A,,,QFN21_6X5XB,11750.96,14282.50,0.000,NO
PU71_P0_3,ISL99390FRZTR5935-ISL99390FRZ-A,,,QFN21_6X5XB,16765.70,14255.42,0.000,NO
PU72_P0_4,ISL99390FRZTR5935-ISL99390FRZ-A,,,QFN21_6X5XB,11369.53,14282.50,0.000,NO
PU75_P1_1,ISL99390FRZTR5935-ISL99390FRZ-A,,,QFN21_6X5XB,6772.61,13919.46,0.000,NO
PU76_P1_2,ISL99390FRZTR5935-ISL99390FRZ-A,,,QFN21_6X5XB,2017.85,13919.21,0.000,NO
PU77_P1_3,ISL99390FRZTR5935-ISL99390FRZ-A,,,QFN21_6X5XB,7154.04,13919.46,0.000,NO
PU78_P1_4,ISL99390FRZTR5935-ISL99390FRZ-A,,,QFN21_6X5XB,1636.42,13919.21,0.000,NO
PU5,"ISL69260IRAZT-ISL69260IRAZ-T,SA",,,QFN40_TH_0-4_5X5XE,16760.04,5370.65,90.000,NO
PU9,"NCP3284AMNTXG-NCP3284AMNTXG,SMA",,,PQFN22_6X5,17654.29,2875.10,0.000,NO
PU14,RAA229126GNPHA0-RAA229126GNP#HA,,,QFN48_THXT,14036.15,14127.89,270.000,NO
PU17,ISL99390FRZTR5935-ISL99390FRZ-A,,,QFN21_6X5XB,2161.40,6500.55,90.000,NO
PU18,"ISL69260IRAZT-ISL69260IRAZ-T,SA",,,QFN40_TH_0-4_5X5XE,1089.09,6489.26,270.000,NO
PU22,"ISL69260IRAZT-ISL69260IRAZ-T,SA",,,QFN40_TH_0-4_5X5XE,1262.25,5103.68,90.000,NO
PU29,RAA229126GNPHA0-RAA229126GNP#HA,,,QFN48_THXT,4274.74,14127.89,270.000,NO
PU35,"ISL69260IRAZT-ISL69260IRAZ-T,SA",,,QFN40_TH_0-4_5X5XE,17027.60,4842.07,90.000,NO
PU36,ISL99390FRZTR5935-ISL99390FRZ-A,,,QFN21_6X5XB,16378.33,6385.27,270.000,NO
PU42,RAA2213404GNPHB0-RAA2213404GNPA,,,PQFN17_TH_5X4,16475.60,6026.34,270.000,NO
PU49,RAA2213404GNPHB0-RAA2213404GNPA,,,PQFN17_TH_5X4,2094.13,6859.48,90.000,NO
PU73,MPQ8633BGLEC838Z-MPQ8633BGLE-CA,,,QFN14_4X3,10303.33,2812.64,270.000,NO
PU74,"NB695GDZ-NB695GD-Z,SMLF,IC,AL0A",,,QFN13_2X3,15132.28,2997.80,180.000,NO
PU79,MPQ8633AGLEC807Z-MPQ8633AGLE-CA,,,QFN14_4X3,14710.82,14112.62,0.000,NO
PU80,MPQ8633AGLEC807Z-MPQ8633AGLE-CA,,,QFN14_4X3,4949.41,14112.62,0.000,NO
PU81,"MPQ8626GDZ-MPQ8626GD-Z,SMLF,ICA",,,QFN14_0-5_3X2XA,17043.97,7125.05,0.000,NO
PU82,"MPQ8626GDZ-MPQ8626GD-Z,SMLF,ICA",,,QFN14_0-5_3X2XA,909.65,7083.79,0.000,NO
PU173,"MOSFET_N_SMLF-BSS138K,BSS138K,B",,,SOT23_GDSXD,14434.82,14282.93,270.000,NO
PU174,"MOSFET_N_SMLF-BSS138K,BSS138K,B",,,SOT23_GDSXD,4671.50,14271.73,270.000,NO
PU181,MPQ8633AGLEC807Z-MPQ8633AGLE-CA,,,QFN14_4X3,18025.50,15160.80,90.000,NO
PU200,"MAX15090BEWIT-MAX15090BEWI+T,SA",,,BGA28_0-5_3-525X2-065,3279.55,2182.39,270.000,NO
PU201,"MAX15090BEWIT-MAX15090BEWI+T,SA",,,BGA28_0-5_3-525X2-065,3124.27,814.73,0.000,NO
PU202,"MAX15090BEWIT-MAX15090BEWI+T,SA",,,BGA28_0-5_3-525X2-065,17001.14,4146.75,270.000,NO
PU203,"MAX15090BEWIT-MAX15090BEWI+T,SA",,,BGA28_0-5_3-525X2-065,17775.48,825.97,0.000,NO
PU204,"MP5022AGQVZ-MP5022AGQV-Z,SMLF,A",,,QFN22_TH_3X5,17415.48,1109.27,270.000,NO
PU205,"MP5016GQHLZ-MP5016GQH-L-Z,SMLFA",,,QFN8_2X1-5,16556.10,4142.02,0.000,NO
PU206,"MP5022AGQVZ-MP5022AGQV-Z,SMLF,A",,,QFN22_TH_3X5,2664.27,1098.03,270.000,NO
PU207,"MP5016GQHLZ-MP5016GQH-L-Z,SMLFA",,,QFN8_2X1-5,2717.40,2247.82,0.000,NO
PU287,"MP5991GLUZ-MP5991GLU-Z,SMLF,ICA",,,LGA32_TH_0-5_5X5,7880.79,15855.23,180.000,NO
PU288,"MP5991GLUZ-MP5991GLU-Z,SMLF,ICA",,,LGA32_TH_0-5_5X5,8300.79,15855.23,180.000,NO
PU289,MP5990GMA1111Z-MP5990GMA-1111-A,,,LGA45_TH_0-45_7X5,7319.45,15855.21,270.000,NO
PU292,"MP5022AGQVZ-MP5022AGQV-Z,SMLF,A",,,QFN22_TH_3X5,9994.55,1982.93,180.000,NO
PU293,"MP5016GQHLZ-MP5016GQH-L-Z,SMLFA",,,QFN8_2X1-5,7651.60,2733.22,270.000,NO
PU294,"MAX15090BEWIT-MAX15090BEWI+T,SA",,,BGA28_0-5_3-525X2-065,9954.05,1615.73,270.000,NO
PU295,"MAX15090BEWIT-MAX15090BEWI+T,SA",,,BGA28_0-5_3-525X2-065,8733.13,2790.17,0.000,NO
PU296,"MP5991GLUZ-MP5991GLU-Z,SMLF,ICA",,,LGA32_TH_0-5_5X5,8720.79,15855.23,180.000,NO
PU297,"MP5991GLUZ-MP5991GLU-Z,SMLF,ICA",,,LGA32_TH_0-5_5X5,9140.79,15855.23,180.000,NO
PU299,"MP5022AGQVZ-MP5022AGQV-Z,SMLF,A",,,QFN22_TH_3X5,6995.83,1139.28,270.000,NO
PU300,"MAX15090BEWIT-MAX15090BEWI+T,SA",,,BGA28_0-5_3-525X2-065,7470.03,1009.58,0.000,NO
Q15,"MOSFET_NCH_DUAL-PJT138K,SMLF,IA",,,SOT363XD,14371.56,7208.72,90.000,YES
Q16,"MOSFET_NCH_DUAL-PJT138K,SMLF,IA",,,SOT363XD,3517.46,7143.72,90.000,YES
Q33,MOSFET_NCH_GDS_ESD_PROTECTED-2A,,,SOT23_GDSXC,8092.20,4293.62,90.000,NO
Q34,MOSFET_NCH_GDS_ESD_PROTECTED-2A,,,SOT23_GDSXC,8108.98,3976.64,0.000,NO
Q35,MOSFET_NCH_GDS_ESD_PROTECTED-2A,,,SOT23_GDSXC,8108.98,4122.64,0.000,NO
Q37,"MOSFET_NCH_DUAL-PJT138K,SMLF,IA",,,SOT363XD,6543.18,5080.17,270.000,NO
Q39,MOSFET_NCH_GDS_ESD_PROTECTED-2A,,,SOT23_GDSXC,7630.29,1473.75,90.000,NO
Q46,MOSFET_NCH_GDS_ESD_PROTECTED-2A,,,SOT23_GDSXC,5400.64,2547.02,0.000,NO
Q50,"MOSFET_NCH_DUAL-PJT138K,SMLF,IA",,,SOT363XD,6029.10,4685.08,90.000,NO
Q52,MOSFET_NCH_GDS_ESD_PROTECTED-2A,,,SOT23_GDSXC,6192.20,5163.62,270.000,NO
Q53,MOSFET_NCH_GDS_ESD_PROTECTED-2A,,,SOT23_GDSXC,6332.20,5163.62,90.000,NO
Q54,MOSFET_NCH_GDS_ESD_PROTECTED-2A,,,SOT23_GDSXC,7976.10,5198.82,0.000,NO
Q56,"MOSFET_NCH_1D3S-PSMNR58-30YLH,A",,,SOT1023,17227.70,2175.80,0.000,NO
Q57,"MOSFET_NCH_1D3S-PSMNR58-30YLH,A",,,SOT1023,17376.11,14789.87,90.000,NO
Q67,"MOSFET_NCH_DUAL-PJT138K,SMLF,IA",,,SOT363XD,4572.20,16029.95,270.000,NO
Q69,"MOSFET_NCH_DUAL-PJT138K,SMLF,IA",,,SOT363XD,16857.48,15008.62,0.000,NO
Q70,"MOSFET_NCH_DUAL-PJT138K,SMLF,IA",,,SOT363XD,16857.48,15413.62,0.000,NO
Q71,"MOSFET_NCH_DUAL-PJT138K,SMLF,IA",,,SOT363XD,16857.48,15203.62,0.000,NO
Q72,"MOSFET_NCH_DUAL-PJT138K,SMLF,IA",,,SOT363XD,1105.58,16378.62,0.000,NO
Q74,"MOSFET_NCH_DUAL-PJT138K,SMLF,IA",,,SOT363XD,4455.20,15559.37,270.000,NO
Q75,"MOSFET_NCH_DUAL-PJT138K,SMLF,IA",,,SOT363XD,4595.20,15659.37,270.000,NO
Q76,"MOSFET_NCH_DUAL-PJT138K,SMLF,IA",,,SOT363XD,4252.63,3792.01,0.000,NO
Q77,"MOSFET_NCH_DUAL-PJT138K,SMLF,IA",,,SOT363XD,4252.22,4052.88,0.000,NO
Q78,"MOSFET_NCH_DUAL-PJT138K,SMLF,IA",,,SOT363XD,3974.35,3656.40,0.000,NO
Q79,"MOSFET_NCH_DUAL-PJT138K,SMLF,IA",,,SOT363XD,3973.89,4043.04,0.000,NO
Q80,"MOSFET_NCH_DUAL-PJT138K,SMLF,IA",,,SOT363XD,3369.14,3657.02,0.000,NO
Q81,"MOSFET_NCH_DUAL-PJT138K,SMLF,IA",,,SOT363XD,4255.09,3662.03,0.000,NO
Q83,"MOSFET_NCH_DUAL-PJT138K,SMLF,IA",,,SOT363XD,3922.20,3212.02,0.000,NO
Q84,"MOSFET_NCH_DUAL-PJT138K,SMLF,IA",,,SOT363XD,3704.19,3920.37,0.000,NO
Q85,"MOSFET_NCH_DUAL-PJT138K,SMLF,IA",,,SOT363XD,3369.14,3779.23,0.000,NO
Q86,"MOSFET_NCH_DUAL-PJT138K,SMLF,IA",,,SOT363XD,4250.99,3921.63,0.000,NO
Q87,"MOSFET_NCH_DUAL-PJT138K,SMLF,IA",,,SOT363XD,3973.41,3784.39,0.000,NO
Q88,"MOSFET_NCH_DUAL-PJT138K,SMLF,IA",,,SOT363XD,3973.30,3914.33,0.000,NO
Q95,"MOSFET_NCH_DUAL-PJT138K,SMLF,IA",,,SOT363XD,5357.20,1813.62,0.000,NO
Q96,"MOSFET_NCH_DUAL-PJT138K,SMLF,IA",,,SOT363XD,1105.58,15893.52,0.000,NO
Q97,"MOSFET_NCH_DUAL-NX6008NBKS,SMLA",,,SOT363XB,3702.57,3786.49,0.000,NO
Q98,"MOSFET_NCH_DUAL-NX6008NBKS,SMLA",,,SOT363XB,3702.57,3663.91,0.000,NO
Q99,"MOSFET_NCH_DUAL-NX6008NBKS,SMLA",,,SOT363XB,3371.11,3916.43,180.000,NO
Q100,"MOSFET_NCH_DUAL-NX6008NBKS,SMLA",,,SOT363XB,3371.11,4035.81,180.000,NO
Q101,"MOSFET_NCH_DUAL-PJT138K,SMLF,IA",,,SOT363XD,1105.58,16011.31,0.000,NO
Q102,"MOSFET_NCH_DUAL-PJT138K,SMLF,IA",,,SOT363XD,6828.88,16548.21,0.000,NO
Q103,"MOSFET_NCH_DUAL-PJT138K,SMLF,IA",,,SOT363XD,6773.52,16374.03,180.000,NO
Q104,"MOSFET_NCH_DUAL-PJT138K,SMLF,IA",,,SOT363XD,16857.48,15608.21,0.000,NO
Q105,"MOSFET_NCH_DUAL-NX6008NBKS,SMLA",,,SOT363XB,3702.57,4035.81,180.000,NO
Q106,"MOSFET_NCH_DUAL-PJT138K,SMLF,IA",,,SOT363XD,16857.48,15813.21,0.000,NO
Q107,"MOSFET_NCH_DUAL-PJT138K,SMLF,IA",,,SOT363XD,1105.58,16198.21,0.000,NO
Q108,"MOSFET_NCH_DUAL-PJT138K,SMLF,IA",,,SOT363XD,3781.09,16685.84,270.000,NO
Q118,"MOSFET_NCH_DUAL-PJT138K,SMLF,IA",,,SOT363XD,2459.55,1468.79,180.000,NO
Q119,"MOSFET_NCH_DUAL-PJT138K,SMLF,IA",,,SOT363XD,2459.95,1576.03,0.000,NO
Q123,"MOSFET_NCH_DUAL-PJT138K,SMLF,IA",,,SOT363XD,18350.17,1539.61,0.000,NO
Q124,"MOSFET_NCH_DUAL-PJT138K,SMLF,IA",,,SOT363XD,18170.75,1614.27,0.000,NO
Q125,"MOSFET_NCH_DUAL-PJT138K,SMLF,IA",,,SOT363XD,7649.85,1700.77,180.000,NO
Q126,"MOSFET_NCH_DUAL-PJT138K,SMLF,IA",,,SOT363XD,11532.63,2264.17,270.000,NO
Q127,"MOSFET_NCH_DUAL-PJT138K,SMLF,IA",,,SOT363XD,11558.23,2011.47,90.000,NO
Q128,"MOSFET_NCH_DUAL-PJT138K,SMLF,IA",,,SOT363XD,11939.00,16696.25,90.000,NO
Q129,"MOSFET_NCH_DUAL-PJT138K,SMLF,IA",,,SOT363XD,11722.30,16693.15,90.000,NO
Q130,"MOSFET_NCH_DUAL-PJT138K,SMLF,IA",,,SOT363XD,11936.40,17151.05,90.000,NO
Q131,"MOSFET_NCH_DUAL-PJT138K,SMLF,IA",,,SOT363XD,12152.10,17154.15,90.000,NO
Q132,"MOSFET_NCH_DUAL-PJT138K,SMLF,IA",,,SOT363XD,11832.30,16693.15,90.000,NO
Q133,"MOSFET_NCH_DUAL-PJT138K,SMLF,IA",,,SOT363XD,12044.10,17151.50,90.000,NO
Q134,"MOSFET_NCH_DUAL-PJT138K,SMLF,IA",,,SOT363XD,11612.30,16693.15,90.000,NO
Q135,"MOSFET_NCH_DUAL-PJT138K,SMLF,IA",,,SOT363XD,14365.33,15215.35,0.000,NO
Q136,"MOSFET_NCH_DUAL-PJT138K,SMLF,IA",,,SOT363XD,14369.23,15485.75,0.000,NO
Q137,"MOSFET_NCH_DUAL-PJT138K,SMLF,IA",,,SOT363XD,14367.73,15373.55,0.000,NO
Q138,"BC847BPN-BC847BPN,SMLF,IC,BA00A",,,SOT363XB,4827.20,3788.62,270.000,NO
Q139,"BC847BPN-BC847BPN,SMLF,IC,BA00A",,,SOT363XB,4961.20,3789.69,270.000,NO
Q140,"BC847BPN-BC847BPN,SMLF,IC,BA00A",,,SOT363XB,5262.20,4083.62,270.000,NO
Q141,"BC847BPN-BC847BPN,SMLF,IC,BA00A",,,SOT363XB,5102.20,4083.62,270.000,NO
Q142,"BC847BPN-BC847BPN,SMLF,IC,BA00A",,,SOT363XB,5292.20,3793.62,270.000,NO
Q143,"BC847BPN-BC847BPN,SMLF,IC,BA00A",,,SOT363XB,5122.20,3788.62,270.000,NO
Q144,"MOSFET_NCH_DUAL-PJT138K,SMLF,IA",,,SOT363XD,5905.00,5168.62,180.000,NO
Q145,"MOSFET_NCH_DUAL-PJT138K,SMLF,IA",,,SOT363XD,11382.52,16234.10,0.000,NO
Q146,"MOSFET_NCH_DUAL-PJT138K,SMLF,IA",,,SOT363XD,14195.00,16373.62,0.000,NO
Q148,"MOSFET_NCH_DUAL-PJT138K,SMLF,IA",,,SOT363XD,3708.90,16307.82,90.000,NO
Q150,"MOSFET_NCH_DUAL-PJT138K,SMLF,IA",,,SOT363XD,8234.24,2671.39,0.000,NO
Q151,"MOSFET_NCH_DUAL-PJT138K,SMLF,IA",,,SOT363XD,4227.00,16090.00,0.000,NO
Q152,"MOSFET_NCH_DUAL-PJT138K,SMLF,IA",,,SOT363XD,14120.00,15860.00,0.000,NO
Q153,"MOSFET_NCH_DUAL-PJT138K,SMLF,IA",,,SOT363XD,14538.00,16050.00,0.000,NO
Q154,"MOSFET_NCH_DUAL-PJT138K,SMLF,IA",,,SOT363XD,14230.10,16259.50,180.000,NO
Q236,"MOSFET_NCH_DUAL-PJT138K,SMLF,IA",,,SOT363XD,17120.80,1889.10,270.000,YES
R1,"Q_RES_0402LF-10,1%,1/16W,CHIP,A",10,1%,R0402,12741.98,7490.91,270.000,YES
R2,"Q_RES_0402LF-100,1%,1/16W,CHIPA",100,1%,R0402,12353.60,7619.65,270.000,YES
R3,"Q_RES_0402LF-33.2,1%,1/16W,CHIA",33.2,1%,R0402,12227.07,7619.25,270.000,YES
R4,"Q_RES_0402LF-200,1%,1/16W,CHIPA",200,1%,R0402,13342.98,7401.52,270.000,YES
R5,"Q_RES_0402LF-100,1%,1/16W,CHIPA",100,1%,R0402,12807.97,7419.65,270.000,YES
R6,"Q_RES_0402LF-100,1%,1/16W,CHIPA",100,1%,R0402,12847.97,7436.85,270.000,YES
R7,"Q_RES_0402LF-33.2,1%,1/16W,CHIA",33.2,1%,R0402,12092.20,1893.62,0.000,NO
R8,"Q_RES_0402LF-10K,1%,1/16W,CHIPA",10K,1%,R0402,13435.91,1247.18,0.000,YES
R10,"Q_RES_0402LF-33.2,1%,1/16W,CHIA",33.2,1%,R0402,15820.17,9020.65,270.000,YES
R11,"Q_RES_0402LF-33.2,1%,1/16W,CHIA",33.2,1%,R0402,6073.40,8850.97,270.000,YES
R12,"Q_RES_0402LF-0,5%,1/16W,CHIP,CA",0,5%,R0402,12004.97,7666.15,90.000,YES
R13,"Q_RES_0402LF-0,5%,1/16W,CHIP,CA",0,5%,R0402,12044.97,7666.15,90.000,YES
R14,"Q_RES_0402LF-200,1%,1/16W,CHIPA",200,1%,R0402,11950.97,7666.15,90.000,YES
R15,"Q_RES_0402LF-0,5%,1/16W,CHIP,CA",0,5%,R0402,12089.37,7583.05,90.000,YES
R16,"Q_RES_0402LF-0,5%,1/16W,CHIP,CA",0,5%,R0402,12092.47,7666.05,90.000,YES
R17,"Q_RES_0402LF-200,1%,1/16W,CHIPA",200,1%,R0402,12129.37,7583.05,90.000,YES
R18,"Q_RES_0402LF-499,1%,1/16W,CHIPA",499,1%,R0402,13135.97,7437.95,270.000,YES
R19,"Q_RES_0402LF-499,1%,1/16W,CHIPA",499,1%,R0402,13175.67,7438.05,270.000,YES
R20,"Q_RES_0402LF-0,5%,1/16W,CHIP,CA",0,5%,R0402,13147.07,7313.75,180.000,YES
R21,"Q_RES_0402LF-0,5%,1/16W,CHIP,CA",0,5%,R0402,13218.16,7276.69,90.000,YES
R22,"Q_RES_0402LF-100,1%,1/16W,CHIPA",100,1%,R0402,13163.07,7512.95,90.000,YES
R23,"Q_RES_0402LF-100,1%,1/16W,CHIPA",100,1%,R0402,13200.32,7512.95,90.000,YES
R24,"Q_RES_0402LF-10,1%,1/16W,CHIP,A",10,1%,R0402,13052.77,7512.95,90.000,YES
R25,"Q_RES_0402LF-10,1%,1/16W,CHIP,A",10,1%,R0402,13088.47,7512.95,90.000,YES
R26,"Q_RES_0402LF-10K,1%,1/16W,CHIPA",10K,1%,R0402,11935.01,12561.40,0.000,YES
R27,"Q_RES_0402LF-15.4K,1%,1/16W,CHA",15.4K,1%,R0402,12185.08,12567.89,0.000,YES
R28,"Q_RES_0402LF-23.2K,1%,1/16W,CHA",23.2K,1%,R0402,11345.48,12598.62,0.000,YES
R29,"Q_RES_0402LF-35.7K,1%,1/16W,CHA",35.7K,1%,R0402,11638.91,12566.04,270.000,YES
R30,"Q_RES_0402LF-54.9K,1%,1/16W,CHA",54.9K,1%,R0402,10746.04,12545.04,0.000,YES
R31,"Q_RES_0402LF-84.5K,1%,1/16W,CHA",84.5K,1%,R0402,11057.17,12563.81,270.000,YES
R32,"Q_RES_0402LF-127K,1%,1/16W,CHIA",127K,1%,R0402,10154.05,12542.63,0.000,YES
R33,"Q_RES_0402LF-196K,1%,1/16W,CHIA",196K,1%,R0402,10449.07,12547.13,0.000,YES
R34,"Q_RES_0402LF-10K,1%,1/16W,CHIPA",10K,1%,R0402,16381.14,12548.44,0.000,YES
R35,"Q_RES_0402LF-15.4K,1%,1/16W,CHA",15.4K,1%,R0402,16110.14,12549.44,0.000,YES
R36,"Q_RES_0402LF-23.2K,1%,1/16W,CHA",23.2K,1%,R0402,16975.14,12542.44,0.000,YES
R37,"Q_RES_0402LF-35.7K,1%,1/16W,CHA",35.7K,1%,R0402,16679.14,12550.44,0.000,YES
R38,"Q_RES_0402LF-54.9K,1%,1/16W,CHA",54.9K,1%,R0402,17566.14,12543.44,0.000,YES
R39,"Q_RES_0402LF-84.5K,1%,1/16W,CHA",84.5K,1%,R0402,17271.14,12543.44,0.000,YES
R40,"Q_RES_0402LF-127K,1%,1/16W,CHIA",127K,1%,R0402,18166.12,12550.85,90.000,YES
R41,"Q_RES_0402LF-196K,1%,1/16W,CHIA",196K,1%,R0402,17868.14,12547.44,0.000,YES
R42,"Q_RES_0402LF-10K,1%,1/16W,CHIPA",10K,1%,R0402,2176.38,12559.44,0.000,YES
R43,"Q_RES_0402LF-15.4K,1%,1/16W,CHA",15.4K,1%,R0402,2450.66,12558.81,270.000,YES
R44,"Q_RES_0402LF-23.2K,1%,1/16W,CHA",23.2K,1%,R0402,1559.89,12534.12,0.000,YES
R45,"Q_RES_0402LF-35.7K,1%,1/16W,CHA",35.7K,1%,R0402,1877.54,12559.43,0.000,YES
R46,"Q_RES_0402LF-54.9K,1%,1/16W,CHA",54.9K,1%,R0402,987.12,12544.64,0.000,YES
R47,"Q_RES_0402LF-84.5K,1%,1/16W,CHA",84.5K,1%,R0402,1281.78,12545.28,0.000,YES
R48,"Q_RES_0402LF-127K,1%,1/16W,CHIA",127K,1%,R0402,393.45,12544.00,0.000,YES
R49,"Q_RES_0402LF-499,1%,1/16W,CHIPA",499,1%,R0402,3179.67,7423.34,270.000,YES
R50,"Q_RES_0402LF-499,1%,1/16W,CHIPA",499,1%,R0402,2860.46,7216.69,270.000,YES
R51,"Q_RES_0402LF-100,1%,1/16W,CHIPA",100,1%,R0402,3179.67,7513.15,90.000,YES
R52,"Q_RES_0402LF-100,1%,1/16W,CHIPA",100,1%,R0402,2927.06,7508.08,90.000,YES
R53,"Q_RES_0402LF-10,1%,1/16W,CHIP,A",10,1%,R0402,2770.46,7216.69,90.000,YES
R54,"Q_RES_0402LF-10,1%,1/16W,CHIP,A",10,1%,R0402,2770.46,7314.64,90.000,YES
R55,"Q_RES_0402LF-0,5%,1/16W,CHIP,CA",0,5%,R0402,2770.46,7419.64,90.000,YES
R56,"Q_RES_0402LF-0,5%,1/16W,CHIP,CA",0,5%,R0402,2810.46,7509.64,90.000,YES
R57,"Q_RES_0402LF-200,1%,1/16W,CHIPA",200,1%,R0402,2770.46,7509.64,90.000,YES
R58,"Q_RES_0402LF-0,5%,1/16W,CHIP,CA",0,5%,R0402,2850.46,7509.64,90.000,YES
R59,"Q_RES_0402LF-0,5%,1/16W,CHIP,CA",0,5%,R0402,2810.46,7419.64,90.000,YES
R60,"Q_RES_0402LF-200,1%,1/16W,CHIPA",200,1%,R0402,2850.46,7419.64,90.000,YES
R61,"Q_RES_0402LF-10,1%,1/16W,CHIP,A",10,1%,R0402,3286.56,7247.88,270.000,YES
R62,"Q_RES_0402LF-100,1%,1/16W,CHIPA",100,1%,R0402,3010.38,7223.24,270.000,YES
R63,"Q_RES_0402LF-33.2,1%,1/16W,CHIA",33.2,1%,R0402,2967.06,7508.08,270.000,YES
R64,"Q_RES_0402LF-200,1%,1/16W,CHIPA",200,1%,R0402,3829.02,7508.08,270.000,YES
R65,"Q_RES_0402LF-100,1%,1/16W,CHIPA",100,1%,R0402,3444.46,7508.08,270.000,YES
R66,"Q_RES_0402LF-100,1%,1/16W,CHIPA",100,1%,R0402,3404.46,7508.08,270.000,YES
R67,"Q_RES_0402LF-33.2,1%,1/16W,CHIA",33.2,1%,R0402,15175.75,7429.30,270.000,YES
R68,"Q_RES_0402LF-33.2,1%,1/16W,CHIA",33.2,1%,R0402,6147.50,7589.65,270.000,YES
R69,"Q_RES_0402LF-10K,1%,1/16W,CHIPA",10K,1%,R0402,15175.75,7512.65,90.000,YES
R70,"Q_RES_0402LF-10K,1%,1/16W,CHIPA",10K,1%,R0402,6147.50,7659.65,270.000,YES
R71,"Q_RES_0402LF-10K,1%,1/16W,CHIPA",10K,1%,R0402,13466.04,1479.32,270.000,YES
R72,"Q_RES_0402LF-196K,1%,1/16W,CHIA",196K,1%,R0402,8093.33,12535.12,0.000,YES
R73,"Q_RES_0402LF-127K,1%,1/16W,CHIA",127K,1%,R0402,8408.70,12523.92,0.000,YES
R74,"Q_RES_0402LF-84.5K,1%,1/16W,CHA",84.5K,1%,R0402,7521.60,12567.62,0.000,YES
R75,"Q_RES_0402LF-54.9K,1%,1/16W,CHA",54.9K,1%,R0402,7798.68,12532.77,0.000,YES
R76,"Q_RES_0402LF-35.7K,1%,1/16W,CHA",35.7K,1%,R0402,6928.00,12570.62,0.000,YES
R77,"Q_RES_0402LF-23.2K,1%,1/16W,CHA",23.2K,1%,R0402,7205.19,12533.56,0.000,YES
R78,"Q_RES_0402LF-15.4K,1%,1/16W,CHA",15.4K,1%,R0402,6336.73,12547.48,270.000,YES
R79,"Q_RES_0402LF-10K,1%,1/16W,CHIPA",10K,1%,R0402,6723.85,12559.32,180.000,YES
R80,"Q_RES_0402LF-196K,1%,1/16W,CHIA",196K,1%,R0402,692.77,12545.93,0.000,YES
R87,"Q_RES_0402LF-1K,1%,1/16W,EMPTYA",1K,1%,R0402,11494.67,5905.22,270.000,YES
R90,"Q_RES_0402LF-240,1%,1/16W,EMPTA",240,1%,R0402,3046.02,7319.94,270.000,YES
R91,"Q_RES_0402LF-240,1%,1/16W,EMPTA",240,1%,R0402,6117.60,7454.70,270.000,YES
R92,"Q_RES_0402LF-240,1%,1/16W,EMPTA",240,1%,R0402,2116.02,7608.65,270.000,YES
R93,"Q_RES_0402LF-240,1%,1/16W,EMPTA",240,1%,R0402,7053.88,7586.61,270.000,YES
R94,"Q_RES_0402LF-240,1%,1/16W,EMPTA",240,1%,R0402,12422.60,7619.65,270.000,YES
R95,"Q_RES_0402LF-240,1%,1/16W,EMPTA",240,1%,R0402,15036.45,7512.65,270.000,YES
R96,"Q_RES_0402LF-240,1%,1/16W,EMPTA",240,1%,R0402,11106.80,7626.41,270.000,YES
R97,"Q_RES_0402LF-240,1%,1/16W,EMPTA",240,1%,R0402,16187.88,7601.95,270.000,YES
R106,"Q_RES_0402LF-2K,1%,1/16W,CHIP,A",2K,1%,R0402,9877.57,3636.60,0.000,NO
R107,"Q_RES_0402LF-33.2,1%,1/16W,CHIA",33.2,1%,R0402,9283.93,5200.91,90.000,YES
R108,"Q_RES_0402LF-33.2,1%,1/16W,CHIA",33.2,1%,R0402,9433.69,5065.78,90.000,YES
R109,"Q_RES_0402LF-33.2,1%,1/16W,CHIA",33.2,1%,R0402,7772.20,4232.12,0.000,NO
R110,"Q_RES_0402LF-33.2,1%,1/16W,CHIA",33.2,1%,R0402,9211.49,5215.56,270.000,YES
R111,"Q_RES_0402LF-10K,1%,1/16W,CHIPA",10K,1%,R0402,10711.55,3867.23,180.000,NO
R113,"Q_RES_0402LF-33.2,1%,1/16W,CHIA",33.2,1%,R0402,10712.05,3821.41,0.000,NO
R120,"Q_RES_0603LF-10M,1%,1/10W,CHIPA",10M,1%,R0603,12792.11,1274.47,135.000,NO
R122,"Q_RES_0402LF-0,5%,1/16W,CHIP,CA",0,5%,R0402,6164.57,4041.79,0.000,YES
R124,"Q_RES_0402LF-0,5%,1/16W,CHIP,CA",0,5%,R0402,6884.70,3931.62,270.000,NO
R126,"Q_RES_0402LF-0,5%,1/16W,CHIP,CA",0,5%,R0402,7900.07,4325.55,180.000,YES
R128,"Q_RES_0402LF-0,5%,1/16W,CHIP,CA",0,5%,R0402,8087.97,4349.25,270.000,YES
R130,"Q_RES_0402LF-0,5%,1/16W,CHIP,CA",0,5%,R0402,7282.20,3923.62,270.000,NO
R132,"Q_RES_0402LF-0,5%,1/16W,CHIP,CA",0,5%,R0402,7481.78,4064.19,90.000,YES
R135,"Q_RES_0402LF-100,1%,1/16W,CHIPA",100,1%,R0402,2504.57,7595.85,90.000,YES
R137,"Q_RES_0402LF-100,1%,1/16W,CHIPA",100,1%,R0402,2544.77,7596.95,90.000,YES
R139,"Q_RES_0402LF-10K,1%,1/16W,EMPTA",10K,1%,R0402,12585.39,1049.27,270.000,NO
R142,"Q_RES_0402LF-0,5%,1/16W,CHIP,CA",0,5%,R0402,6483.20,857.62,270.000,NO
R143,"Q_RES_0402LF-49.9,1%,1/16W,CHIA",49.9,1%,R0402,12157.20,2088.62,90.000,NO
R144,"Q_RES_0402LF-0,5%,1/16W,CHIP,CA",0,5%,R0402,6550.00,933.62,90.000,NO
R145,"Q_RES_0402LF-4.75K,1%,1/16W,EMA",4.75K,1%,R0402,12117.20,2088.62,90.000,NO
R146,"Q_RES_0402LF-4.75K,1%,1/16W,EMA",4.75K,1%,R0402,12072.20,2088.62,90.000,NO
R147,"Q_RES_0402LF-10K,1%,1/16W,CHIPA",10K,1%,R0402,12166.10,2206.52,90.000,NO
R148,"Q_RES_0402LF-10K,1%,1/16W,EMPTA",10K,1%,R0402,6590.00,933.62,270.000,NO
R149,"Q_RES_0402LF-0,5%,1/16W,CHIP,CA",0,5%,R0402,12126.10,2206.52,90.000,NO
R151,"Q_RES_0402LF-100,1%,1/16W,CHIPA",100,1%,R0402,6673.47,7598.85,90.000,YES
R153,"Q_RES_0402LF-100,1%,1/16W,CHIPA",100,1%,R0402,6725.37,7599.45,90.000,YES
R155,"Q_RES_0402LF-100,1%,1/16W,CHIPA",100,1%,R0402,2650.43,7216.69,270.000,YES
R156,"Q_RES_0402LF-100,1%,1/16W,CHIPA",100,1%,R0402,2690.46,7216.69,270.000,YES
R157,"Q_RES_0402LF-100,1%,1/16W,CHIPA",100,1%,R0402,2192.72,7613.85,90.000,YES
R158,"Q_RES_0402LF-100,1%,1/16W,CHIPA",100,1%,R0402,2602.66,9580.53,180.000,YES
R160,"Q_RES_0402LF-0,5%,1/16W,CHIP,CA",0,5%,R0402,6896.63,4058.99,90.000,YES
R162,"Q_RES_0402LF-0,5%,1/16W,CHIP,CA",0,5%,R0402,6922.47,3831.55,270.000,YES
R164,"Q_RES_0402LF-0,5%,1/16W,CHIP,CA",0,5%,R0402,7010.25,4175.00,180.000,YES
R166,"Q_RES_0402LF-0,5%,1/16W,CHIP,CA",0,5%,R0402,7104.33,4138.59,90.000,YES
R168,"Q_RES_0402LF-0,5%,1/16W,CHIP,CA",0,5%,R0402,7332.20,3823.62,270.000,NO
R171,"Q_RES_0402LF-0,5%,1/16W,CHIP,CA",0,5%,R0402,7304.60,4113.82,180.000,YES
R175,"Q_RES_0402LF-100,1%,1/16W,CHIPA",100,1%,R0402,11660.77,7648.25,90.000,YES
R177,"Q_RES_0402LF-100,1%,1/16W,CHIPA",100,1%,R0402,11776.77,7624.95,90.000,YES
R179,"Q_RES_0402LF-100,1%,1/16W,CHIPA",100,1%,R0402,15735.07,7510.85,90.000,YES
R181,"Q_RES_0402LF-100,1%,1/16W,CHIPA",100,1%,R0402,15775.07,7510.85,90.000,YES
R183,"Q_RES_0402LF-100,1%,1/16W,CHIPA",100,1%,R0402,13003.17,7388.95,90.000,YES
R184,"Q_RES_0402LF-100,1%,1/16W,CHIPA",100,1%,R0402,13014.87,7512.95,270.000,YES
R185,"Q_RES_0402LF-100,1%,1/16W,CHIPA",100,1%,R0402,11730.00,10163.62,0.000,YES
R186,"Q_RES_0402LF-100,1%,1/16W,CHIPA",100,1%,R0402,11730.00,10203.62,180.000,YES
R188,"Q_RES_0402LF-0,5%,1/16W,CHIP,CA",0,5%,R0402,7382.20,3923.62,270.000,NO
R195,"Q_RES_0402LF-49.9,1%,1/16W,CHIA",49.9,1%,R0402,12561.93,7321.65,270.000,YES
R196,"Q_RES_0402LF-49.9,1%,1/16W,CHIA",49.9,1%,R0402,3206.56,7247.88,270.000,YES
R197,"Q_RES_0402LF-301,1%,1/16W,CHIPA",301,1%,R0402,12584.07,7417.85,0.000,YES
R198,"Q_RES_0402LF-301,1%,1/16W,CHIPA",301,1%,R0402,3206.56,7317.88,90.000,YES
R200,"Q_RES_0402LF-100,1%,1/16W,CHIPA",100,1%,R0402,5057.20,3943.62,270.000,NO
R202,"Q_RES_0402LF-100,1%,1/16W,CHIPA",100,1%,R0402,5217.20,3943.62,270.000,NO
R203,"Q_RES_0402LF-1.5K,1%,1/16W,CHIA",1.5K,1%,R0402,5107.20,3648.62,90.000,NO
R204,"Q_RES_0402LF-1.5K,1%,1/16W,CHIA",1.5K,1%,R0402,5277.20,3648.62,90.000,NO
R205,"Q_RES_0402LF-1.5K,1%,1/16W,CHIA",1.5K,1%,R0402,5097.20,3943.62,90.000,NO
R206,"Q_RES_0402LF-1.5K,1%,1/16W,CHIA",1.5K,1%,R0402,5257.20,3943.62,90.000,NO
R208,"Q_RES_0402LF-0,5%,1/16W,CHIP,CA",0,5%,R0402,7132.20,3923.62,270.000,NO
R210,"Q_RES_0402LF-0,5%,1/16W,CHIP,CA",0,5%,R0402,7772.20,3982.12,0.000,NO
R219,"Q_RES_0402LF-100,1%,1/16W,CHIPA",100,1%,R0402,7132.20,3823.62,90.000,NO
R220,"Q_RES_0402LF-100,1%,1/16W,CHIPA",100,1%,R0402,7914.20,3982.12,180.000,NO
R223,"Q_RES_0402LF-1K,1%,1/16W,CHIP,A",1K,1%,R0402,855.65,6621.39,90.000,NO
R237,"Q_RES_0402LF-1.5K,1%,1/16W,CHIA",1.5K,1%,R0402,4787.20,3648.62,90.000,NO
R238,"Q_RES_0402LF-1.5K,1%,1/16W,CHIA",1.5K,1%,R0402,4947.20,3648.62,90.000,NO
R239,"Q_RES_0402LF-0,5%,1/16W,CHIP,CA",0,5%,R0402,12528.47,7397.95,270.000,YES
R240,"Q_RES_0402LF-0,5%,1/16W,CHIP,CA",0,5%,R0402,3166.56,7247.88,270.000,YES
R241,"Q_RES_0402LF-4.75K,1%,1/16W,CHA",4.75K,1%,R0402,4827.20,3648.62,90.000,NO
R242,"Q_RES_0402LF-4.75K,1%,1/16W,CHA",4.75K,1%,R0402,5027.20,3648.62,90.000,NO
R243,"Q_RES_0402LF-100,1%,1/16W,CHIPA",100,1%,R0402,12528.47,7469.95,90.000,YES
R244,"Q_RES_0402LF-100,1%,1/16W,CHIPA",100,1%,R0402,3166.56,7317.88,90.000,YES
R249,"Q_RES_0402LF-240,1%,1/16W,EMPTA",240,1%,R0402,10910.96,7624.79,270.000,YES
R250,"Q_RES_0402LF-240,1%,1/16W,EMPTA",240,1%,R0402,10832.96,7624.79,270.000,YES
R251,"Q_RES_0402LF-240,1%,1/16W,EMPTA",240,1%,R0402,10871.96,7624.79,270.000,YES
R252,"Q_RES_0402LF-240,1%,1/16W,CHIPA",240,1%,R0402,15949.97,7600.15,270.000,YES
R253,"Q_RES_0402LF-240,1%,1/16W,CHIPA",240,1%,R0402,10949.96,7624.79,270.000,YES
R254,"Q_RES_0402LF-240,1%,1/16W,CHIPA",240,1%,R0402,11066.96,7624.79,270.000,YES
R255,"Q_RES_0402LF-240,1%,1/16W,EMPTA",240,1%,R0402,1916.02,7608.65,270.000,YES
R256,"Q_RES_0402LF-240,1%,1/16W,EMPTA",240,1%,R0402,1836.02,7608.65,270.000,YES
R257,"Q_RES_0402LF-240,1%,1/16W,EMPTA",240,1%,R0402,1876.02,7608.65,270.000,YES
R258,"Q_RES_0402LF-240,1%,1/16W,CHIPA",240,1%,R0402,6933.10,7586.61,270.000,YES
R259,"Q_RES_0402LF-240,1%,1/16W,CHIPA",240,1%,R0402,1956.02,7608.65,270.000,YES
R260,"Q_RES_0402LF-240,1%,1/16W,CHIPA",240,1%,R0402,2036.02,7608.65,270.000,YES
R261,"Q_RES_0402LF-240,1%,1/16W,EMPTA",240,1%,R0402,3364.46,7508.08,270.000,YES
R262,"Q_RES_0402LF-240,1%,1/16W,EMPTA",240,1%,R0402,2970.87,7254.17,270.000,YES
R263,"Q_RES_0402LF-240,1%,1/16W,EMPTA",240,1%,R0402,3270.96,7402.98,270.000,YES
R264,"Q_RES_0402LF-240,1%,1/16W,EMPTA",240,1%,R0402,2821.20,7215.67,270.000,YES
R265,"Q_RES_0402LF-240,1%,1/16W,CHIPA",240,1%,R0402,6889.67,7889.92,270.000,YES
R266,"Q_RES_0402LF-240,1%,1/16W,EMPTA",240,1%,R0402,6973.36,7586.61,270.000,YES
R267,"Q_RES_0402LF-240,1%,1/16W,EMPTA",240,1%,R0402,7013.62,7586.61,270.000,YES
R268,"Q_RES_0402LF-240,1%,1/16W,EMPTA",240,1%,R0402,6900.52,7799.77,0.000,YES
R269,"Q_RES_0402LF-33.2,1%,1/16W,CHIA",33.2,1%,R0402,7622.20,4032.12,180.000,NO
R270,"Q_RES_0402LF-10K,1%,1/16W,CHIPA",10K,1%,R0402,7292.20,4998.62,270.000,NO
R271,"Q_RES_0402LF-10K,1%,1/16W,CHIPA",10K,1%,R0402,7112.20,4998.62,270.000,NO
R272,"Q_RES_0402LF-10K,1%,1/16W,CHIPA",10K,1%,R0402,7292.20,5128.62,270.000,NO
R273,"Q_RES_0402LF-10K,1%,1/16W,CHIPA",10K,1%,R0402,7052.20,4998.62,270.000,NO
R274,"Q_RES_0402LF-10K,1%,1/16W,CHIPA",10K,1%,R0402,7172.20,4998.62,270.000,NO
R275,"Q_RES_0402LF-240,1%,1/16W,CHIPA",240,1%,R0402,12772.57,7349.85,270.000,YES
R276,"Q_RES_0402LF-240,1%,1/16W,EMPTA",240,1%,R0402,12288.60,7627.65,270.000,YES
R277,"Q_RES_0402LF-240,1%,1/16W,CHIPA",240,1%,R0402,12639.37,7439.65,270.000,YES
R278,"Q_RES_0402LF-240,1%,1/16W,EMPTA",240,1%,R0402,12920.07,7287.35,270.000,YES
R279,"Q_RES_0402LF-240,1%,1/16W,EMPTA",240,1%,R0402,16067.88,7601.95,270.000,YES
R280,"Q_RES_0402LF-240,1%,1/16W,EMPTA",240,1%,R0402,16107.88,7601.95,270.000,YES
R281,"Q_RES_0402LF-240,1%,1/16W,EMPTA",240,1%,R0402,16147.88,7601.95,270.000,YES
R282,"Q_RES_0402LF-240,1%,1/16W,CHIPA",240,1%,R0402,16027.88,7601.95,270.000,YES
R283,"Q_RES_0402LF-10K,1%,1/16W,CHIPA",10K,1%,R0402,7232.20,5128.62,270.000,NO
R284,"Q_RES_0402LF-10K,1%,1/16W,CHIPA",10K,1%,R0402,7172.20,5128.62,270.000,NO
R285,"Q_RES_0402LF-10K,1%,1/16W,CHIPA",10K,1%,R0402,7232.20,4998.62,270.000,NO
R286,"Q_RES_0402LF-10K,1%,1/16W,CHIPA",10K,1%,R0402,7452.20,5128.62,270.000,NO
R287,"Q_RES_0402LF-10K,1%,1/16W,CHIPA",10K,1%,R0402,7352.20,5128.62,270.000,NO
R288,"Q_RES_0402LF-240,1%,1/16W,EMPTA",240,1%,R0402,5947.22,7409.55,0.000,YES
R289,"Q_RES_0402LF-240,1%,1/16W,EMPTA",240,1%,R0402,5877.12,7409.85,0.000,YES
R290,"Q_RES_0402LF-240,1%,1/16W,CHIPA",240,1%,R0402,2688.70,7455.68,270.000,YES
R291,"Q_RES_0402LF-240,1%,1/16W,EMPTA",240,1%,R0402,5870.06,7478.87,180.000,YES
R292,"Q_RES_0402LF-240,1%,1/16W,EMPTA",240,1%,R0402,15070.16,7359.66,90.000,YES
R293,"Q_RES_0402LF-240,1%,1/16W,EMPTA",240,1%,R0402,15023.96,7328.27,90.000,YES
R294,"Q_RES_0402LF-240,1%,1/16W,EMPTA",240,1%,R0402,12949.37,7509.65,270.000,YES
R295,"Q_RES_0402LF-240,1%,1/16W,EMPTA",240,1%,R0402,14786.56,7508.01,270.000,YES
R296,"Q_RES_0402LF-301,1%,1/16W,CHIPA",301,1%,R0402,12959.47,7267.25,270.000,YES
R297,"Q_RES_0402LF-0,5%,1/16W,CHIP,CA",0,5%,R0402,12959.47,7337.25,90.000,YES
R298,"Q_RES_0402LF-301,1%,1/16W,CHIPA",301,1%,R0402,2946.87,7060.70,270.000,YES
R299,"Q_RES_0402LF-0,5%,1/16W,CHIP,CA",0,5%,R0402,2909.53,7158.25,90.000,YES
R301,"Q_RES_0402LF-301,1%,1/16W,CHIPA",301,1%,R0402,12732.57,7350.65,270.000,YES
R302,"Q_RES_0402LF-0,5%,1/16W,CHIP,CA",0,5%,R0402,12742.57,7420.65,90.000,YES
R303,"Q_RES_0402LF-301,1%,1/16W,CHIPA",301,1%,R0402,3351.26,7322.98,270.000,YES
R304,"Q_RES_0402LF-0,5%,1/16W,CHIP,CA",0,5%,R0402,3345.46,7402.98,90.000,YES
R307,"Q_RES_0402LF-1K,1%,1/16W,CHIP,A",1K,1%,R0402,4031.25,14210.03,270.000,NO
R308,"Q_RES_0402LF-0,5%,1/16W,CHIP,CA",0,5%,R0402,3991.34,14209.81,270.000,NO
R309,"Q_RES_0402LF-0,5%,1/16W,CHIP,CA",0,5%,R0402,4161.27,14096.65,270.000,YES
R310,"Q_RES_0402LF-150,1%,1/16W,CHIPA",150,1%,R0402,4048.99,14077.27,0.000,NO
R311,"Q_RES_0402LF-0,5%,1/16W,CHIP,CA",0,5%,R0402,4049.04,14042.07,0.000,NO
R312,"Q_RES_0402LF-0,5%,1/16W,CHIP,CA",0,5%,R0402,4049.04,14006.84,0.000,NO
R315,"Q_RES_0402LF-33.2,1%,1/16W,CHIA",33.2,1%,R0402,12205.00,2088.62,270.000,NO
R318,"Q_RES_0402LF-10K,1%,1/16W,CHIPA",10K,1%,R0402,11534.67,5905.22,90.000,YES
R319,"Q_RES_0402LF-10K,1%,1/16W,CHIPA",10K,1%,R0402,16349.28,7601.95,270.000,YES
R320,"Q_RES_0402LF-10K,1%,1/16W,CHIPA",10K,1%,R0402,16309.28,7601.95,270.000,YES
R321,"Q_RES_0402LF-10K,1%,1/16W,CHIPA",10K,1%,R0402,16389.28,7601.95,270.000,YES
R322,"Q_RES_0402LF-33.2,1%,1/16W,CHIA",33.2,1%,R0402,15271.85,7512.65,90.000,YES
R323,"Q_RES_1206LF-0,,1/2W,EMPTY,CS0A",0,,R1206XI,15812.20,7353.62,0.000,NO
R324,"Q_RES_1206LF-0,,1/2W,CHIP,CS00A",0,,R1206XI,15812.20,7443.62,0.000,NO
R325,"Q_RES_0402LF-10K,1%,1/16W,CHIPA",10K,1%,R0402,7146.88,7586.61,270.000,YES
R326,"Q_RES_0402LF-10K,1%,1/16W,CHIPA",10K,1%,R0402,7106.88,7586.61,270.000,YES
R327,"Q_RES_0402LF-10K,1%,1/16W,CHIPA",10K,1%,R0402,7186.88,7586.61,270.000,YES
R328,"Q_RES_0402LF-100,1%,1/16W,CHIPA",100,1%,R0402,11995.97,7576.79,90.000,YES
R329,"Q_RES_1206LF-0,,1/2W,EMPTY,CS0A",0,,R1206XI,2962.95,6241.81,0.000,NO
R330,"Q_RES_1206LF-0,,1/2W,CHIP,CS00A",0,,R1206XI,1743.75,7164.71,0.000,NO
R331,"Q_RES_0402LF-1K,1%,1/16W,EMPTYA",1K,1%,R0402,15989.16,14246.69,180.000,NO
R332,"Q_RES_0402LF-10K,1%,1/16W,CHIPA",10K,1%,R0402,15989.16,14201.69,0.000,NO
R333,"Q_RES_0402LF-1K,1%,1/16W,EMPTYA",1K,1%,R0402,15989.16,14471.53,180.000,NO
R334,"Q_RES_0402LF-10K,1%,1/16W,CHIPA",10K,1%,R0402,15989.16,14520.71,0.000,NO
R335,"Q_RES_0402LF-1K,1%,1/16W,EMPTYA",1K,1%,R0402,15989.16,14291.69,180.000,NO
R336,"Q_RES_0402LF-0,5%,1/16W,CHIP,CA",0,5%,R0402,12637.87,7340.15,90.000,YES
R337,"Q_RES_0402LF-0,5%,1/16W,CHIP,CA",0,5%,R0402,3246.56,7247.88,90.000,YES
R338,"Q_RES_0402LF-0,5%,1/16W,CHIP,CA",0,5%,R0402,5483.00,4099.07,270.000,NO
R340,"Q_RES_0402LF-0,5%,1/16W,CHIP,CA",0,5%,R0402,12462.60,7619.65,90.000,YES
R341,"Q_RES_0402LF-0,5%,1/16W,CHIP,CA",0,5%,R0402,3079.67,7248.44,90.000,YES
R342,"Q_RES_0402LF-0,5%,1/16W,CHIP,CA",0,5%,R0402,5543.00,4099.07,270.000,NO
R344,"Q_RES_0402LF-0,5%,1/16W,CHIP,CA",0,5%,R0402,12502.60,7619.65,90.000,YES
R345,"Q_RES_0402LF-0,5%,1/16W,CHIP,CA",0,5%,R0402,3126.56,7247.88,90.000,YES
R346,"Q_RES_0402LF-0,5%,1/16W,CHIP,CA",0,5%,R0402,5643.00,4099.07,270.000,NO
R361,"Q_RES_0402LF-1K,1%,1/16W,CHIP,A",1K,1%,R0402,17203.61,4722.52,0.000,YES
R362,"Q_RES_0402LF-0,5%,1/16W,CHIP,CA",0,5%,R0402,17203.61,4757.52,0.000,YES
R363,"Q_RES_0402LF-0,5%,1/16W,CHIP,CA",0,5%,R0402,17203.61,4792.52,0.000,YES
R365,"Q_RES_0402LF-0,5%,1/16W,CHIP,CA",0,5%,R0402,7942.20,4268.62,270.000,NO
R366,"Q_RES_0402LF-249,1%,1/16W,CHIPA",249,1%,R0402,7646.70,3174.32,0.000,NO
R367,"Q_RES_0402LF-1K,1%,1/16W,EMPTYA",1K,1%,R0402,5054.50,864.22,0.000,NO
R369,"Q_RES_0402LF-1K,1%,1/16W,CHIP,A",1K,1%,R0402,7772.20,3932.12,180.000,NO
R371,"Q_RES_0402LF-1K,1%,1/16W,EMPTYA",1K,1%,R0402,12495.93,2117.62,0.000,NO
R372,"Q_RES_0402LF-10K,1%,1/16W,CHIPA",10K,1%,R0402,12405.93,2094.62,180.000,NO
R374,"Q_RES_0402LF-1K,1%,1/16W,EMPTYA",1K,1%,R0402,12998.90,1287.42,270.000,YES
R375,"Q_RES_0402LF-10K,1%,1/16W,CHIPA",10K,1%,R0402,13037.28,1287.90,90.000,YES
R378,"Q_RES_0402LF-1K,1%,1/16W,EMPTYA",1K,1%,R0402,12175.35,1210.02,0.000,YES
R379,"Q_RES_0402LF-1K,1%,1/16W,CHIP,A",1K,1%,R0402,12100.93,1209.62,0.000,YES
R380,"Q_RES_0402LF-1K,1%,1/16W,EMPTYA",1K,1%,R0402,12300.93,1681.62,0.000,NO
R381,"Q_RES_0402LF-10K,1%,1/16W,CHIPA",10K,1%,R0402,12185.93,1689.62,180.000,NO
R401,"Q_RES_0402LF-10K,1%,1/16W,EMPTA",10K,1%,R0402,12605.93,2174.62,0.000,NO
R409,"Q_RES_0402LF-4.7K,1%,1/16W,EMPA",4.7K,1%,R0402,17580.75,417.09,270.000,YES
R410,"Q_RES_0402LF-4.7K,1%,1/16W,CHIA",4.7K,1%,R0402,17620.75,417.09,90.000,YES
R413,"Q_RES_0402LF-100K,1%,1/16W,CHIA",100K,1%,R0402,3067.20,443.62,270.000,YES
R414,"Q_RES_0402LF-4.7K,1%,1/16W,EMPA",4.7K,1%,R0402,17737.91,328.54,90.000,YES
R415,"Q_RES_0402LF-4.7K,1%,1/16W,CHIA",4.7K,1%,R0402,17697.91,328.54,270.000,YES
R416,"Q_RES_0402LF-0,5%,1/16W,CHIP,CA",0,5%,R0402,17255.20,638.62,270.000,NO
R417,"Q_RES_0402LF-0,5%,1/16W,CHIP,CA",0,5%,R0402,17169.65,772.09,270.000,NO
R418,"Q_RES_0402LF-0,5%,1/16W,CHIP,CA",0,5%,R0402,17208.95,639.69,270.000,NO
R419,"Q_RES_0402LF-33.2,1%,1/16W,CHIA",33.2,1%,R0402,17168.75,639.69,270.000,NO
R420,"Q_RES_0402LF-1K,1%,1/16W,CHIP,A",1K,1%,R0402,17819.90,417.55,90.000,YES
R421,"Q_RES_0402LF-10K,1%,1/16W,CHIPA",10K,1%,R0402,17777.54,418.69,90.000,YES
R422,"Q_RES_0402LF-10K,1%,1/16W,CHIPA",10K,1%,R0402,17735.54,417.09,90.000,YES
R423,"Q_RES_0402LF-1K,1%,1/16W,CHIP,A",1K,1%,R0402,17699.00,417.09,90.000,YES
R424,"Q_RES_0402LF-33.2,1%,1/16W,CHIA",33.2,1%,R0402,17733.75,1783.03,0.000,YES
R425,"Q_RES_0402LF-33.2,1%,1/16W,CHIA",33.2,1%,R0402,17733.75,1739.03,0.000,YES
R429,"Q_RES_0402LF-0,5%,1/16W,CHIP,CA",0,5%,R0402,17877.06,515.40,90.000,YES
R435,"Q_RES_0402LF-33.2,1%,1/16W,CHIA",33.2,1%,R0402,17100.25,198.92,270.000,YES
R442,"Q_RES_0603LF-1,1%,1/10W,CHIP,CA",1,1%,R0603_H24,9519.14,3840.62,270.000,YES
R444,"Q_RES_0402LF-0,5%,1/16W,CHIP,CA",0,5%,R0402,15286.54,561.15,90.000,NO
R445,"Q_RES_0402LF-0,5%,1/16W,CHIP,CA",0,5%,R0402,15246.54,561.15,90.000,NO
R447,"Q_RES_0603LF-1,1%,1/10W,CHIP,CA",1,1%,R0603_H24,10290.39,4127.28,180.000,YES
R448,"Q_RES_0402LF-0,5%,1/16W,EMPTY,A",0,5%,R0402,15527.20,5858.62,270.000,NO
R453,"Q_RES_0402LF-10K,1%,1/16W,CHIPA",10K,1%,R0402,12185.93,1539.62,180.000,NO
R456,"Q_RES_0402LF-10K,1%,1/16W,CHIPA",10K,1%,R0402,12680.93,2334.62,0.000,NO
R474,"Q_RES_0402LF-33.2,1%,1/16W,CHIA",33.2,1%,R0402,12115.19,1716.11,180.000,NO
R477,"Q_RES_0402LF-60.4,1%,1/16W,CHIA",60.4,1%,R0402,13406.34,2122.39,180.000,YES
R478,"Q_RES_0402LF-4.7K,1%,1/16W,CHIA",4.7K,1%,R0402,7117.20,2218.62,180.000,NO
R480,"Q_RES_0402LF-0,5%,1/16W,CHIP,CA",0,5%,R0402,14707.77,3659.96,90.000,NO
R481,"Q_RES_0402LF-0,5%,1/16W,CHIP,CA",0,5%,R0402,14667.77,3659.96,90.000,NO
R482,"Q_RES_0402LF-0,5%,1/16W,CHIP,CA",0,5%,R0402,14537.77,3659.96,90.000,NO
R483,"Q_RES_0402LF-0,5%,1/16W,CHIP,CA",0,5%,R0402,14814.84,3657.88,270.000,NO
R486,"Q_RES_0402LF-0,5%,1/16W,CHIP,CA",0,5%,R0402,6477.20,1663.62,0.000,NO
R487,"Q_RES_0402LF-1K,1%,1/16W,CHIP,A",1K,1%,R0402,6477.20,1713.62,0.000,NO
R491,"Q_RES_0402LF-4.7K,1%,1/16W,EMPA",4.7K,1%,R0402,5188.25,1684.43,180.000,NO
R494,"Q_RES_0402LF-1K,1%,1/16W,CHIP,A",1K,1%,R0402,12300.93,1342.62,180.000,YES
R495,"Q_RES_0402LF-100,1%,1/16W,CHIPA",100,1%,R0402,13420.47,1746.63,210.007,YES
R496,"Q_RES_0402LF-113,1%,1/16W,CHIPA",113,1%,R0402,13785.50,1201.61,270.000,NO
R497,"Q_RES_0402LF-200,1%,1/16W,CHIPA",200,1%,R0402,12092.20,1953.62,180.000,NO
R498,"Q_RES_0402LF-10K,1%,1/16W,CHIPA",10K,1%,R0402,13885.05,2351.88,0.000,YES
R499,"Q_RES_0402LF-33.2,1%,1/16W,CHIA",33.2,1%,R0402,13192.88,1236.02,90.000,YES
R501,"Q_RES_0402LF-33.2,1%,1/16W,CHIA",33.2,1%,R0402,13101.50,1306.04,90.000,YES
R502,"Q_RES_0402LF-20K,1%,1/16W,CHIPA",20K,1%,R0402,13575.62,1241.23,0.000,YES
R506,"Q_RES_0402LF-0,5%,1/16W,CHIP,CA",0,5%,R0402,5397.20,368.62,270.000,YES
R515,"Q_RES_0402LF-10K,1%,1/16W,CHIPA",10K,1%,R0402,15989.16,14336.69,0.000,NO
R519,"Q_RES_0603LF-1,1%,1/10W,CHIP,CA",1,1%,R0603_H24,10374.69,3679.44,0.000,NO
R536,"Q_RES_0402LF-10K,1%,1/16W,EMPTA",10K,1%,R0402,5175.86,5398.19,180.000,NO
R537,"Q_RES_0402LF-1K,1%,1/16W,CHIP,A",1K,1%,R0402,5055.18,5398.19,0.000,NO
R538,"Q_RES_0402LF-10K,1%,1/16W,EMPTA",10K,1%,R0402,4383.18,5477.69,0.000,NO
R539,"Q_RES_0402LF-1K,1%,1/16W,CHIP,A",1K,1%,R0402,4468.28,5425.19,180.000,NO
R540,"Q_RES_0402LF-10K,1%,1/16W,EMPTA",10K,1%,R0402,4383.18,5527.69,0.000,NO
R548,"Q_RES_0402LF-49.9,1%,1/16W,CHIA",49.9,1%,R0402,11950.97,7577.07,90.000,YES
R553,"Q_RES_0402LF-0,5%,1/16W,CHIP,CA",0,5%,R0402,10125.06,4258.04,90.000,NO
R554,"Q_RES_0402LF-0,5%,1/16W,CHIP,CA",0,5%,R0402,10165.06,4258.04,90.000,NO
R555,"Q_RES_0402LF-100,1%,1/16W,CHIPA",100,1%,R0402,12085.37,7498.05,90.000,YES
R556,"Q_RES_0402LF-49.9,1%,1/16W,CHIA",49.9,1%,R0402,12125.37,7498.05,90.000,YES
R557,"Q_RES_0402LF-100,1%,1/16W,CHIPA",100,1%,R0402,2730.00,7420.04,270.000,YES
R558,"Q_RES_0402LF-49.9,1%,1/16W,CHIA",49.9,1%,R0402,2732.46,7511.64,90.000,YES
R559,"Q_RES_0402LF-100,1%,1/16W,CHIPA",100,1%,R0402,2886.46,7508.64,270.000,YES
R560,"Q_RES_0402LF-49.9,1%,1/16W,CHIA",49.9,1%,R0402,2810.46,7314.64,90.000,YES
R563,"Q_RES_0402LF-22,1%,1/16W,CHIP,A",22,1%,R0402,9006.33,5015.73,180.000,NO
R564,"Q_RES_0402LF-22,1%,1/16W,CHIP,A",22,1%,R0402,9006.33,4975.73,180.000,NO
R565,"Q_RES_0402LF-22,1%,1/16W,CHIP,A",22,1%,R0402,9006.48,4932.99,180.000,NO
R566,"Q_RES_0402LF-22,1%,1/16W,CHIP,A",22,1%,R0402,9006.48,4892.99,180.000,NO
R567,"Q_RES_0402LF-4.7K,1%,1/16W,EMPA",4.7K,1%,R0402,9643.47,5052.91,90.000,YES
R568,"Q_RES_0402LF-4.7K,1%,1/16W,CHIA",4.7K,1%,R0402,9606.20,5052.62,270.000,YES
R569,"Q_RES_0402LF-4.7K,1%,1/16W,EMPA",4.7K,1%,R0402,9683.55,5052.38,90.000,YES
R570,"Q_RES_0402LF-4.7K,1%,1/16W,CHIA",4.7K,1%,R0402,9723.79,5052.91,270.000,YES
R571,"Q_RES_0603LF-2.2,1%,1/10W,CHIPA",2.2,1%,R0603,9221.69,4757.94,180.000,YES
R572,"Q_RES_0603LF-2.2,1%,1/10W,CHIPA",2.2,1%,R0603,9195.15,4843.12,270.000,YES
R573,"Q_RES_0402LF-4.7K,1%,1/16W,EMPA",4.7K,1%,R0402,9363.89,4937.01,0.000,YES
R574,"Q_RES_0402LF-4.7K,1%,1/16W,CHIA",4.7K,1%,R0402,9363.94,4980.83,180.000,YES
R575,"Q_RES_0402LF-49.9,1%,1/16W,CHIA",49.9,1%,R0402,9247.61,5215.39,90.000,YES
R576,"Q_RES_0402LF-49.9,1%,1/16W,CHIA",49.9,1%,R0402,9045.74,5073.48,180.000,YES
R577,"Q_RES_0402LF-33.2,1%,1/16W,CHIA",33.2,1%,R0402,9346.70,5213.48,0.000,YES
R578,"Q_RES_0402LF-33.2,1%,1/16W,CHIA",33.2,1%,R0402,9376.43,5133.50,270.000,YES
R579,"Q_RES_0402LF-33.2,1%,1/16W,CHIA",33.2,1%,R0402,185.00,2003.62,180.000,NO
R580,"Q_RES_0402LF-33.2,1%,1/16W,CHIA",33.2,1%,R0402,185.00,1933.62,180.000,NO
R581,"Q_RES_0402LF-33.2,1%,1/16W,CHIA",33.2,1%,R0402,292.20,2403.62,180.000,NO
R582,"Q_RES_0402LF-33.2,1%,1/16W,CHIA",33.2,1%,R0402,292.20,2323.62,180.000,NO
R587,"Q_RES_0402LF-1K,1%,1/16W,CHIP,A",1K,1%,R0402,4468.28,5475.19,180.000,NO
R588,"Q_RES_0402LF-33.2,1%,1/16W,CHIA",33.2,1%,R0402,6182.20,387.02,0.000,YES
R589,"Q_RES_0402LF-33.2,1%,1/16W,CHIA",33.2,1%,R0402,6450.83,351.06,90.000,YES
R592,"Q_RES_0402LF-2.2K,5%,1/16W,EMPA",2.2K,5%,R0402,6311.30,572.82,270.000,YES
R593,"Q_RES_0402LF-0,5%,1/16W,CHIP,CA",0,5%,R0402,7494.77,535.45,270.000,YES
R594,"Q_RES_0402LF-0,5%,1/16W,CHIP,CA",0,5%,R0402,7454.74,535.45,270.000,YES
R595,"Q_RES_0402LF-0,5%,1/16W,CHIP,CA",0,5%,R0402,7413.77,535.45,270.000,YES
R596,"Q_RES_0402LF-0,5%,1/16W,CHIP,CA",0,5%,R0402,7375.95,535.45,270.000,YES
R597,"Q_RES_0402LF-0,5%,1/16W,CHIP,CA",0,5%,R0402,7336.42,535.45,270.000,YES
R598,"Q_RES_0402LF-0,5%,1/16W,CHIP,CA",0,5%,R0402,7292.93,535.45,270.000,YES
R599,"Q_RES_0402LF-0,5%,1/16W,CHIP,CA",0,5%,R0402,7246.44,535.45,270.000,YES
R600,"Q_RES_0402LF-0,5%,1/16W,CHIP,CA",0,5%,R0402,7199.49,535.45,270.000,YES
R601,"Q_RES_0402LF-2.2K,5%,1/16W,EMPA",2.2K,5%,R0402,6252.90,612.72,180.000,YES
R607,"Q_RES_0402LF-1K,1%,1/16W,EMPTYA",1K,1%,R0402,12185.93,1769.62,180.000,NO
R608,"Q_RES_0402LF-10K,1%,1/16W,CHIPA",10K,1%,R0402,12100.93,1769.62,180.000,NO
R609,"Q_RES_0402LF-1K,1%,1/16W,EMPTYA",1K,1%,R0402,12917.04,1135.94,270.000,YES
R610,"Q_RES_0402LF-10K,1%,1/16W,CHIPA",10K,1%,R0402,12958.07,1135.93,90.000,YES
R611,"Q_RES_0402LF-1K,1%,1/16W,CHIP,A",1K,1%,R0402,12605.93,2214.62,0.000,NO
R612,"Q_RES_0402LF-10K,1%,1/16W,EMPTA",10K,1%,R0402,12495.93,2234.62,180.000,NO
R613,"Q_RES_0402LF-10K,1%,1/16W,CHIPA",10K,1%,R0402,12834.85,1135.55,270.000,YES
R614,"Q_RES_0402LF-1K,1%,1/16W,EMPTYA",1K,1%,R0402,12794.85,1120.25,90.000,YES
R615,"Q_RES_0402LF-1K,1%,1/16W,CHIP,A",1K,1%,R0402,12605.93,2475.62,0.000,NO
R617,"Q_RES_0402LF-1K,1%,1/16W,EMPTYA",1K,1%,R0402,12605.93,2294.62,0.000,NO
R618,"Q_RES_0402LF-10K,1%,1/16W,CHIPA",10K,1%,R0402,12495.93,2274.62,180.000,NO
R619,"Q_RES_0402LF-10K,1%,1/16W,CHIPA",10K,1%,R0402,12605.93,2254.62,0.000,NO
R621,"Q_RES_0402LF-1K,1%,1/16W,EMPTYA",1K,1%,R0402,12667.23,1051.60,270.000,YES
R622,"Q_RES_0402LF-1K,1%,1/16W,CHIP,A",1K,1%,R0402,12623.83,1051.60,90.000,YES
R623,"Q_RES_0402LF-1K,1%,1/16W,EMPTYA",1K,1%,R0402,12495.93,2157.62,0.000,NO
R624,"Q_RES_0402LF-10K,1%,1/16W,CHIPA",10K,1%,R0402,12405.93,2134.62,180.000,NO
R625,"Q_RES_0402LF-1K,1%,1/16W,EMPTYA",1K,1%,R0402,7635.20,13840.62,180.000,NO
R626,"Q_RES_0402LF-10K,1%,1/16W,CHIPA",10K,1%,R0402,7635.20,13885.62,0.000,NO
R627,"Q_RES_0402LF-1K,1%,1/16W,EMPTYA",1K,1%,R0402,7634.20,14147.62,180.000,NO
R628,"Q_RES_0402LF-10K,1%,1/16W,CHIPA",10K,1%,R0402,7634.20,14102.62,0.000,NO
R629,"Q_RES_0402LF-1K,1%,1/16W,CHIP,A",1K,1%,R0402,7635.20,13972.62,180.000,NO
R630,"Q_RES_0402LF-10K,1%,1/16W,EMPTA",10K,1%,R0402,7635.20,13927.62,0.000,NO
R635,"Q_RES_0402LF-10K,1%,1/16W,CHIPA",10K,1%,R0402,13496.21,1082.22,270.000,NO
R650,"Q_RES_0402LF-1K,1%,1/16W,CHIP,A",1K,1%,R0402,15989.16,14426.69,180.000,NO
R651,"Q_RES_0402LF-2.2K,5%,1/16W,CHIA",2.2K,5%,R0402,5175.86,5169.69,180.000,NO
R652,"Q_RES_0402LF-2.2K,5%,1/16W,CHIA",2.2K,5%,R0402,5175.86,5114.69,180.000,NO
R661,"Q_RES_0402LF-1K,1%,1/16W,CHIP,A",1K,1%,R0402,3281.06,6008.73,90.000,NO
R662,"Q_RES_0402LF-499,1%,1/16W,CHIPA",499,1%,R0402,3629.02,7508.08,270.000,YES
R663,"Q_RES_0402LF-499,1%,1/16W,CHIPA",499,1%,R0402,3709.02,7508.08,270.000,YES
R664,"Q_RES_0402LF-499,1%,1/16W,CHIPA",499,1%,R0402,5955.97,7494.30,270.000,YES
R665,"Q_RES_0402LF-0,5%,1/16W,EMPTY,A",0,5%,R0402,3077.19,5953.18,0.000,NO
R666,"Q_RES_0402LF-0,5%,1/16W,EMPTY,A",0,5%,R0402,3069.56,5613.67,90.000,NO
R667,"Q_RES_0402LF-0,5%,1/16W,EMPTY,A",0,5%,R0402,3218.05,5631.76,0.000,NO
R668,"Q_RES_0402LF-0,5%,1/16W,EMPTY,A",0,5%,R0402,3162.25,5959.98,180.000,NO
R669,"Q_RES_0402LF-499,1%,1/16W,CHIPA",499,1%,R0402,5997.63,7494.46,270.000,YES
R670,"Q_RES_0402LF-0,5%,1/16W,CHIP,CA",0,5%,R0402,3669.02,7508.08,90.000,YES
R671,"Q_RES_0402LF-33.2,1%,1/16W,CHIA",33.2,1%,R0402,3749.02,7508.08,90.000,YES
R672,"Q_RES_0402LF-0,5%,1/16W,CHIP,CA",0,5%,R0402,5920.76,7494.65,90.000,YES
R673,"Q_RES_0402LF-33.2,1%,1/16W,CHIA",33.2,1%,R0402,6032.76,7494.65,90.000,YES
R674,"Q_RES_0402LF-0,5%,1/16W,CHIP,CA",0,5%,R0402,3077.19,5993.18,180.000,NO
R675,"Q_RES_0402LF-33.2,1%,1/16W,CHIA",33.2,1%,R0402,3026.84,5613.67,270.000,NO
R676,"Q_RES_0402LF-0,5%,1/16W,CHIP,CA",0,5%,R0402,3218.09,5592.18,180.000,NO
R677,"Q_RES_0402LF-33.2,1%,1/16W,CHIA",33.2,1%,R0402,3162.15,5999.26,0.000,NO
R678,"Q_RES_0402LF-1K,1%,1/16W,CHIP,A",1K,1%,R0402,12031.08,5887.14,0.000,YES
R679,"Q_RES_0402LF-499,1%,1/16W,CHIPA",499,1%,R0402,13247.83,7417.07,0.000,YES
R680,"Q_RES_0402LF-499,1%,1/16W,CHIPA",499,1%,R0402,13308.88,7510.09,270.000,YES
R681,"Q_RES_0402LF-499,1%,1/16W,CHIPA",499,1%,R0402,14867.41,7508.02,270.000,YES
R682,"Q_RES_0402LF-0,5%,1/16W,EMPTY,A",0,5%,R0402,11534.77,5975.42,270.000,YES
R683,"Q_RES_0402LF-0,5%,1/16W,EMPTY,A",0,5%,R0402,11535.37,6045.12,270.000,YES
R684,"Q_RES_0402LF-0,5%,1/16W,EMPTY,A",0,5%,R0402,11973.96,6043.36,270.000,YES
R685,"Q_RES_0402LF-0,5%,1/16W,EMPTY,A",0,5%,R0402,11973.96,5973.21,270.000,YES
R686,"Q_RES_0402LF-499,1%,1/16W,CHIPA",499,1%,R0402,14909.92,7511.64,270.000,YES
R687,"Q_RES_0402LF-0,5%,1/16W,CHIP,CA",0,5%,R0402,13247.83,7377.47,180.000,YES
R688,"Q_RES_0402LF-33.2,1%,1/16W,CHIA",33.2,1%,R0402,13346.41,7510.09,90.000,YES
R689,"Q_RES_0402LF-0,5%,1/16W,CHIP,CA",0,5%,R0402,14827.51,7508.02,90.000,YES
R690,"Q_RES_0402LF-33.2,1%,1/16W,CHIA",33.2,1%,R0402,14949.63,7511.62,90.000,YES
R691,"Q_RES_0402LF-0,5%,1/16W,CHIP,CA",0,5%,R0402,11479.87,5991.22,0.000,YES
R692,"Q_RES_0402LF-33.2,1%,1/16W,CHIA",33.2,1%,R0402,11479.77,6060.82,0.000,YES
R693,"Q_RES_0402LF-0,5%,1/16W,CHIP,CA",0,5%,R0402,12032.47,6056.05,180.000,YES
R694,"Q_RES_0402LF-33.2,1%,1/16W,CHIA",33.2,1%,R0402,12028.87,5991.33,180.000,YES
R696,"Q_RES_0402LF-4.75K,1%,1/16W,CHA",4.75K,1%,R0402,12575.79,1613.01,225.000,YES
R697,"Q_RES_0402LF-33.2,1%,1/16W,CHIA",33.2,1%,R0402,12510.08,1549.53,225.000,YES
R698,"Q_RES_0402LF-49.9,1%,1/16W,CHIA",49.9,1%,R0402,12300.93,1779.62,180.000,NO
R699,"Q_RES_0402LF-33.2,1%,1/16W,CHIA",33.2,1%,R0402,12405.60,1912.79,0.000,NO
R700,"Q_RES_0402LF-0,5%,1/16W,CHIP,CA",0,5%,R0402,7622.20,3932.12,0.000,NO
R701,"Q_RES_0402LF-10K,1%,1/16W,EMPTA",10K,1%,R0402,957.79,7604.44,270.000,YES
R702,"Q_RES_0402LF-10K,1%,1/16W,EMPTA",10K,1%,R0402,7570.09,7622.64,270.000,YES
R703,"Q_RES_0402LF-10K,1%,1/16W,EMPTA",10K,1%,R0402,1400.29,7595.44,270.000,YES
R704,"Q_RES_0402LF-10K,1%,1/16W,EMPTA",10K,1%,R0402,7409.09,7622.04,270.000,YES
R705,"Q_RES_0402LF-10K,1%,1/16W,EMPTA",10K,1%,R0402,17069.48,7620.68,270.000,YES
R706,"Q_RES_0402LF-10K,1%,1/16W,EMPTA",10K,1%,R0402,11198.69,7625.64,270.000,YES
R707,"Q_RES_0402LF-10K,1%,1/16W,EMPTA",10K,1%,R0402,10537.49,7618.24,270.000,YES
R708,"Q_RES_0402LF-10K,1%,1/16W,EMPTA",10K,1%,R0402,16546.67,7612.34,270.000,YES
R710,"Q_RES_0402LF-1K,1%,1/16W,CHIP,A",1K,1%,R0402,11520.10,3732.31,0.000,NO
R713,"Q_RES_0402LF-10K,1%,1/16W,EMPTA",10K,1%,R0402,10929.90,3690.61,0.000,NO
R714,"Q_RES_0402LF-1K,1%,1/16W,CHIP,A",1K,1%,R0402,10814.90,3690.61,180.000,NO
R717,"Q_RES_0402LF-10K,1%,1/16W,EMPTA",10K,1%,R0402,10930.50,3741.31,0.000,NO
R718,"Q_RES_0402LF-1K,1%,1/16W,CHIP,A",1K,1%,R0402,10815.50,3741.31,180.000,NO
R721,"Q_RES_0402LF-10K,1%,1/16W,CHIPA",10K,1%,R0402,10931.10,3792.51,0.000,NO
R722,"Q_RES_0402LF-1K,1%,1/16W,EMPTYA",1K,1%,R0402,10816.10,3792.51,180.000,NO
R727,"Q_RES_0402LF-10K,1%,1/16W,CHIPA",10K,1%,R0402,13450.83,953.43,270.000,NO
R734,"Q_RES_0402LF-4.75K,1%,1/16W,CHA",4.75K,1%,R0402,9678.56,3941.78,0.000,YES
R735,"Q_RES_0402LF-10K,1%,1/16W,CHIPA",10K,1%,R0402,7913.40,4698.62,180.000,NO
R736,"Q_RES_0402LF-1K,1%,1/16W,EMPTYA",1K,1%,R0402,7913.40,4748.62,0.000,NO
R737,"Q_RES_0402LF-0,5%,1/16W,CHIP,CA",0,5%,R0402,7951.24,7639.96,0.000,YES
R738,"Q_RES_0402LF-0,5%,1/16W,CHIP,CA",0,5%,R0402,7951.27,7584.55,0.000,YES
R739,"Q_RES_0402LF-10K,1%,1/16W,CHIPA",10K,1%,R0402,7875.27,7638.55,0.000,YES
R740,"Q_RES_0402LF-10K,1%,1/16W,CHIPA",10K,1%,R0402,7875.27,7596.55,0.000,YES
R741,"Q_RES_0402LF-150,1%,1/16W,CHIPA",150,1%,R0402,13303.28,7401.42,90.000,YES
R742,"Q_RES_0402LF-75,1%,1/16W,CHIP,A",75,1%,R0402,3589.02,7508.08,270.000,YES
R743,"Q_RES_0402LF-150,1%,1/16W,CHIPA",150,1%,R0402,3869.02,7508.08,270.000,YES
R744,"Q_RES_0402LF-75,1%,1/16W,CHIP,A",75,1%,R0402,12898.17,7425.70,90.000,YES
R745,"Q_RES_0402LF-33.2,1%,1/16W,CHIA",33.2,1%,R0402,7686.87,7531.79,180.000,YES
R746,"Q_RES_0402LF-0,5%,1/16W,CHIP,CA",0,5%,R0402,14728.83,2254.48,0.000,NO
R747,"Q_RES_0402LF-150,1%,1/16W,CHIPA",150,1%,R0402,14863.83,2334.48,180.000,NO
R748,"Q_RES_0402LF-75,1%,1/16W,CHIP,A",75,1%,R0402,14103.83,2279.48,0.000,NO
R749,"Q_RES_0402LF-75,1%,1/16W,CHIP,A",75,1%,R0402,14465.00,2118.62,0.000,NO
R750,"Q_RES_0402LF-150,1%,1/16W,CHIPA",150,1%,R0402,14630.00,1573.62,90.000,NO
R751,"Q_RES_0402LF-150,1%,1/16W,CHIPA",150,1%,R0402,14860.85,2553.78,180.000,NO
R752,"Q_RES_0402LF-10,1%,1/16W,CHIP,A",10,1%,R0402,14728.83,2334.48,0.000,NO
R753,"Q_RES_0402LF-10,1%,1/16W,CHIP,A",10,1%,R0402,14228.83,2279.48,180.000,NO
R754,"Q_RES_0402LF-10,1%,1/16W,CHIP,A",10,1%,R0402,14465.00,2158.62,0.000,NO
R755,"Q_RES_0402LF-10,1%,1/16W,CHIP,A",10,1%,R0402,14730.85,2633.78,0.000,NO
R756,"Q_RES_0402LF-10,1%,1/16W,CHIP,A",10,1%,R0402,14730.85,2553.78,0.000,NO
R757,"Q_RES_0402LF-120,1%,1/16W,CHIPA",120,1%,R0402,3381.61,7167.90,270.000,YES
R758,"Q_RES_0402LF-150,1%,1/16W,CHIPA",150,1%,R0402,3010.38,7151.85,270.000,YES
R759,"Q_RES_0402LF-150,1%,1/16W,CHIPA",150,1%,R0402,3326.56,7247.88,90.000,YES
R760,"Q_RES_0402LF-499,1%,1/16W,CHIPA",499,1%,R0402,2730.46,7216.69,90.000,YES
R761,"Q_RES_0402LF-499,1%,1/16W,CHIPA",499,1%,R0402,2730.46,7314.64,90.000,YES
R762,"Q_RES_0402LF-0,5%,1/16W,CHIP,CA",0,5%,R0402,15185.68,2586.16,0.000,NO
R763,"Q_RES_0402LF-10,1%,1/16W,CHIP,A",10,1%,R0402,15185.68,2546.16,0.000,NO
R764,"Q_RES_0402LF-0,5%,1/16W,CHIP,CA",0,5%,R0402,15185.68,2433.62,0.000,NO
R765,"Q_RES_0402LF-0,5%,1/16W,CHIP,CA",0,5%,R0402,15172.63,1948.37,90.000,NO
R766,"Q_RES_0402LF-1K,1%,1/16W,EMPTYA",1K,1%,R0402,15905.78,2115.26,0.000,YES
R767,"Q_RES_0402LF-1K,1%,1/16W,CHIP,A",1K,1%,R0402,15903.39,2562.44,180.000,NO
R768,"Q_RES_0402LF-1K,1%,1/16W,CHIP,A",1K,1%,R0402,15185.68,2351.16,0.000,NO
R769,"Q_RES_0402LF-10K,1%,1/16W,CHIPA",10K,1%,R0402,15903.39,2480.08,0.000,NO
R770,"Q_RES_0402LF-10K,1%,1/16W,CHIPA",10K,1%,R0402,13365.49,1099.45,270.000,NO
R771,"Q_RES_0402LF-1K,1%,1/16W,CHIP,A",1K,1%,R0402,15185.68,2391.16,180.000,NO
R772,"Q_RES_0402LF-1K,1%,1/16W,CHIP,A",1K,1%,R0402,15905.78,2075.67,180.000,YES
R773,"Q_RES_0402LF-1K,1%,1/16W,CHIP,A",1K,1%,R0402,15905.62,2359.82,180.000,YES
R774,"Q_RES_0402LF-75,1%,1/16W,CHIP,A",75,1%,R0402,3444.40,7437.72,90.000,YES
R775,"Q_RES_0402LF-10,1%,1/16W,CHIP,A",10,1%,R0402,15185.00,2723.62,180.000,NO
R776,"Q_RES_0402LF-100,1%,1/16W,CHIPA",100,1%,R0402,15186.38,2682.14,180.000,NO
R777,"Q_RES_0402LF-10,1%,1/16W,CHIP,A",10,1%,R0402,15903.59,2438.90,0.000,NO
R778,"Q_RES_0402LF-1K,1%,1/16W,CHIP,A",1K,1%,R0402,15905.62,2314.90,0.000,YES
R779,"Q_RES_0402LF-150,1%,1/16W,CHIPA",150,1%,R0402,14583.00,3659.62,90.000,NO
R780,"Q_RES_0402LF-49.9,1%,1/16W,CHIA",49.9,1%,R0402,15905.78,2275.26,0.000,NO
R803,"Q_RES_0402LF-33.2,1%,1/16W,CHIA",33.2,1%,R0402,4929.36,2632.57,90.000,NO
R804,"Q_RES_0402LF-33.2,1%,1/16W,CHIA",33.2,1%,R0402,5158.04,2634.63,90.000,NO
R805,"Q_RES_0402LF-33.2,1%,1/16W,CHIA",33.2,1%,R0402,4752.52,2625.10,90.000,NO
R806,"Q_RES_0402LF-33.2,1%,1/16W,CHIA",33.2,1%,R0402,4520.71,2624.89,90.000,NO
R815,"Q_RES_0402LF-0,5%,1/16W,CHIP,CA",0,5%,R0402,7490.09,7622.64,270.000,YES
R816,"Q_RES_0402LF-0,5%,1/16W,CHIP,CA",0,5%,R0402,1440.29,7595.44,270.000,YES
R817,"Q_RES_0402LF-0,5%,1/16W,CHIP,CA",0,5%,R0402,1037.79,7604.44,270.000,YES
R818,"Q_RES_0402LF-0,5%,1/16W,CHIP,CA",0,5%,R0402,7329.09,7622.04,270.000,YES
R819,"Q_RES_0402LF-1K,1%,1/16W,CHIP,A",1K,1%,R0402,7450.09,7622.64,270.000,YES
R820,"Q_RES_0402LF-1K,1%,1/16W,CHIP,A",1K,1%,R0402,1480.29,7595.44,270.000,YES
R821,"Q_RES_0402LF-1K,1%,1/16W,CHIP,A",1K,1%,R0402,1077.79,7604.44,270.000,YES
R822,"Q_RES_0402LF-1K,1%,1/16W,CHIP,A",1K,1%,R0402,7289.09,7622.04,270.000,YES
R835,"Q_RES_0402LF-0,5%,1/16W,CHIP,CA",0,5%,R0402,17109.15,7620.76,270.000,YES
R836,"Q_RES_0402LF-0,5%,1/16W,CHIP,CA",0,5%,R0402,11238.69,7625.64,270.000,YES
R837,"Q_RES_0402LF-0,5%,1/16W,CHIP,CA",0,5%,R0402,10617.49,7618.24,270.000,YES
R838,"Q_RES_0402LF-0,5%,1/16W,CHIP,CA",0,5%,R0402,16626.56,7612.34,270.000,YES
R839,"Q_RES_0402LF-1K,1%,1/16W,CHIP,A",1K,1%,R0402,17149.55,7620.76,270.000,YES
R840,"Q_RES_0402LF-1K,1%,1/16W,CHIP,A",1K,1%,R0402,11278.69,7625.64,270.000,YES
R841,"Q_RES_0402LF-1K,1%,1/16W,CHIP,A",1K,1%,R0402,10657.49,7618.24,270.000,YES
R842,"Q_RES_0402LF-1K,1%,1/16W,CHIP,A",1K,1%,R0402,16666.86,7612.34,270.000,YES
R851,"Q_RES_0402LF-0,5%,1/16W,CHIP,CA",0,5%,R0402,4375.20,4718.37,270.000,NO
R852,"Q_RES_0402LF-0,5%,1/16W,CHIP,CA",0,5%,R0402,4425.20,4718.37,270.000,NO
R853,"Q_RES_0402LF-0,5%,1/16W,CHIP,CA",0,5%,R0402,4565.20,4718.37,270.000,NO
R854,"Q_RES_0402LF-0,5%,1/16W,CHIP,CA",0,5%,R0402,4615.20,4718.37,270.000,NO
R859,"Q_RES_0402LF-0,5%,1/16W,CHIP,CA",0,5%,R0402,4741.69,4716.96,270.000,NO
R860,"Q_RES_0402LF-0,5%,1/16W,CHIP,CA",0,5%,R0402,4791.69,4716.96,270.000,NO
R861,"Q_RES_0402LF-0,5%,1/16W,CHIP,CA",0,5%,R0402,4931.69,4716.96,270.000,NO
R880,"Q_RES_0402LF-33.2,1%,1/16W,CHIA",33.2,1%,R0402,11726.49,12558.62,90.000,YES
R884,"Q_RES_0402LF-33.2,1%,1/16W,CHIA",33.2,1%,R0402,10525.04,12556.61,90.000,YES
R885,"Q_RES_0402LF-33.2,1%,1/16W,CHIA",33.2,1%,R0402,16472.26,12574.92,180.000,YES
R886,"Q_RES_0402LF-33.2,1%,1/16W,CHIA",33.2,1%,R0402,16161.14,12555.44,90.000,YES
R889,"Q_RES_0402LF-33.2,1%,1/16W,CHIA",33.2,1%,R0402,17645.14,12555.44,90.000,YES
R890,"Q_RES_0402LF-33.2,1%,1/16W,CHIA",33.2,1%,R0402,17347.14,12556.44,90.000,YES
R893,"Q_RES_0402LF-33.2,1%,1/16W,CHIA",33.2,1%,R0402,2260.99,12575.20,180.000,YES
R894,"Q_RES_0402LF-33.2,1%,1/16W,CHIA",33.2,1%,R0402,2411.60,12464.92,90.000,YES
R895,"Q_RES_0402LF-33.2,1%,1/16W,CHIA",33.2,1%,R0402,1668.99,12569.64,180.000,YES
R896,"Q_RES_0402LF-33.2,1%,1/16W,CHIA",33.2,1%,R0402,1965.99,12569.64,180.000,YES
R897,"Q_RES_0402LF-33.2,1%,1/16W,CHIA",33.2,1%,R0402,1074.99,12569.64,180.000,YES
R898,"Q_RES_0402LF-33.2,1%,1/16W,CHIA",33.2,1%,R0402,1359.50,12561.42,90.000,YES
R899,"Q_RES_0402LF-33.2,1%,1/16W,CHIA",33.2,1%,R0402,480.99,12569.64,180.000,YES
R900,"Q_RES_0402LF-33.2,1%,1/16W,CHIA",33.2,1%,R0402,777.99,12569.64,180.000,YES
R901,"Q_RES_0402LF-33.2,1%,1/16W,CHIA",33.2,1%,R0402,6577.88,12528.95,0.000,YES
R902,"Q_RES_0402LF-33.2,1%,1/16W,CHIA",33.2,1%,R0402,6443.35,12547.93,90.000,YES
R903,"Q_RES_0402LF-33.2,1%,1/16W,CHIA",33.2,1%,R0402,7303.28,12559.98,90.000,YES
R905,"Q_RES_0402LF-33.2,1%,1/16W,CHIA",33.2,1%,R0402,7916.85,12558.94,90.000,YES
R906,"Q_RES_0402LF-33.2,1%,1/16W,CHIA",33.2,1%,R0402,7618.17,12575.72,180.000,YES
R907,"Q_RES_0402LF-33.2,1%,1/16W,CHIA",33.2,1%,R0402,8472.71,12552.23,90.000,YES
R908,"Q_RES_0402LF-33.2,1%,1/16W,CHIA",33.2,1%,R0402,8194.01,12544.94,90.000,YES
R909,"Q_RES_0402LF-33.2,1%,1/16W,CHIA",33.2,1%,R0402,14746.56,7508.01,90.000,YES
R910,"Q_RES_0402LF-240,1%,1/16W,CHIPA",240,1%,R0402,14689.47,7401.35,90.000,YES
R911,"Q_RES_0402LF-240,1%,1/16W,CHIPA",240,1%,R0402,14690.67,7328.55,270.000,YES
R912,"Q_RES_0402LF-4.75K,1%,1/16W,EMA",4.75K,1%,R0402,9677.89,3861.89,180.000,YES
R913,"Q_RES_0402LF-10K,1%,1/16W,CHIPA",10K,1%,R0402,13296.46,1089.69,270.000,NO
R915,"Q_RES_0402LF-0,5%,1/16W,CHIP,CA",0,5%,R0402,13142.69,1236.13,90.000,YES
R916,"Q_RES_0402LF-0,5%,1/16W,CHIP,CA",0,5%,R0402,13234.93,1307.30,90.000,YES
R917,"Q_RES_0402LF-0,5%,1/16W,CHIP,CA",0,5%,R0402,13274.28,1247.77,90.000,YES
R918,"Q_RES_0402LF-0,5%,1/16W,CHIP,CA",0,5%,R0402,13178.91,1306.03,90.000,YES
R919,"Q_RES_0402LF-10K,1%,1/16W,CHIPA",10K,1%,R0402,6482.20,4628.62,180.000,YES
R920,"Q_RES_0402LF-1K,1%,1/16W,EMPTYA",1K,1%,R0402,6332.20,4628.62,0.000,YES
R927,"Q_RES_0402LF-10K,1%,1/16W,CHIPA",10K,1%,R0402,4990.96,2632.14,90.000,NO
R928,"Q_RES_0402LF-10K,1%,1/16W,CHIPA",10K,1%,R0402,5094.96,2635.39,90.000,NO
R929,"Q_RES_0402LF-10K,1%,1/16W,CHIPA",10K,1%,R0402,4683.23,2625.71,90.000,NO
R930,"Q_RES_0402LF-4.7K,1%,1/16W,CHIA",4.7K,1%,R0402,4582.64,2624.57,270.000,NO
R932,"Q_RES_0402LF-10K,1%,1/16W,CHIPA",10K,1%,R0402,4375.20,4808.37,90.000,NO
R933,"Q_RES_0402LF-10K,1%,1/16W,CHIPA",10K,1%,R0402,4741.69,4806.96,90.000,NO
R934,"Q_RES_0402LF-10K,1%,1/16W,CHIPA",10K,1%,R0402,4425.20,4808.37,90.000,NO
R935,"Q_RES_0402LF-10K,1%,1/16W,CHIPA",10K,1%,R0402,4791.69,4806.96,90.000,NO
R936,"Q_RES_0402LF-10K,1%,1/16W,CHIPA",10K,1%,R0402,4565.20,4808.37,90.000,NO
R937,"Q_RES_0402LF-10K,1%,1/16W,CHIPA",10K,1%,R0402,4931.69,4806.96,90.000,NO
R938,"Q_RES_0402LF-10K,1%,1/16W,CHIPA",10K,1%,R0402,4615.20,4808.37,90.000,NO
R939,"Q_RES_0402LF-10K,1%,1/16W,CHIPA",10K,1%,R0402,4981.69,4806.96,90.000,NO
R940,"Q_RES_0402LF-10K,1%,1/16W,CHIPA",10K,1%,R0402,12237.93,12453.86,90.000,YES
R941,"Q_RES_0402LF-10K,1%,1/16W,CHIPA",10K,1%,R0402,11184.07,12574.49,0.000,YES
R942,"Q_RES_0402LF-10K,1%,1/16W,CHIPA",10K,1%,R0402,17090.13,12553.89,90.000,YES
R943,"Q_RES_0402LF-10K,1%,1/16W,CHIPA",10K,1%,R0402,17974.17,12463.90,90.000,YES
R944,"Q_RES_0402LF-10K,1%,1/16W,CHIPA",10K,1%,R0402,2558.67,12557.56,180.000,YES
R945,"Q_RES_0402LF-10K,1%,1/16W,CHIPA",10K,1%,R0402,1493.99,12529.64,0.000,YES
R946,"Q_RES_0402LF-10K,1%,1/16W,CHIPA",10K,1%,R0402,7341.11,12560.19,90.000,YES
R947,"Q_RES_0402LF-10K,1%,1/16W,CHIPA",10K,1%,R0402,8497.67,12414.76,270.000,YES
R953,"Q_RES_0402LF-4.75K,1%,1/16W,CHA",4.75K,1%,R0402,9678.56,3903.02,0.000,YES
R960,"Q_RES_0402LF-33.2,1%,1/16W,CHIA",33.2,1%,R0402,14706.56,7508.01,90.000,YES
R961,"Q_RES_0402LF-33.2,1%,1/16W,CHIA",33.2,1%,R0402,6071.30,8913.64,180.000,YES
R962,"Q_RES_0402LF-33.2,1%,1/16W,CHIA",33.2,1%,R0402,6071.30,8953.84,180.000,YES
R963,"Q_RES_0402LF-240,1%,1/16W,CHIPA",240,1%,R0402,697.84,7592.46,0.000,YES
R964,"Q_RES_0402LF-240,1%,1/16W,CHIPA",240,1%,R0402,697.84,7547.26,0.000,YES
R965,"Q_RES_0402LF-1K,1%,1/16W,CHIP,A",1K,1%,R0402,14532.18,7259.88,90.000,YES
R966,"Q_RES_0402LF-1K,1%,1/16W,CHIP,A",1K,1%,R0402,415.68,7268.74,0.000,YES
R967,"Q_RES_0402LF-1K,1%,1/16W,CHIP,A",1K,1%,R0402,14491.18,7259.88,90.000,YES
R968,"Q_RES_0402LF-1K,1%,1/16W,CHIP,A",1K,1%,R0402,415.68,7223.74,0.000,YES
R969,"Q_RES_0402LF-240,1%,1/16W,CHIPA",240,1%,R0402,15517.37,6341.65,180.000,NO
R970,"Q_RES_0402LF-240,1%,1/16W,CHIPA",240,1%,R0402,8863.22,8744.05,0.000,NO
R971,"Q_RES_0402LF-240,1%,1/16W,CHIPA",240,1%,R0402,15447.37,6341.65,0.000,NO
R972,"Q_RES_0402LF-240,1%,1/16W,CHIPA",240,1%,R0402,8933.22,8744.05,180.000,NO
R977,"Q_RES_0402LF-560,1%,1/16W,CHIPA",560,1%,R0402,15487.20,5858.62,90.000,NO
R978,"Q_RES_0402LF-560,1%,1/16W,CHIPA",560,1%,R0402,8868.92,9203.25,0.000,NO
R979,"Q_RES_0402LF-560,1%,1/16W,CHIPA",560,1%,R0402,15437.20,5858.62,90.000,NO
R980,"Q_RES_0402LF-560,1%,1/16W,CHIPA",560,1%,R0402,8938.92,9203.25,180.000,NO
R981,"Q_RES_0402LF-33.2,1%,1/16W,CHIA",33.2,1%,R0402,6182.20,4778.62,180.000,NO
R982,"Q_RES_0402LF-33.2,1%,1/16W,CHIA",33.2,1%,R0402,6182.20,4678.62,180.000,NO
R983,"Q_RES_0402LF-33.2,1%,1/16W,CHIA",33.2,1%,R0402,6182.20,4728.62,180.000,NO
R984,"Q_RES_0402LF-33.2,1%,1/16W,CHIA",33.2,1%,R0402,6702.20,4998.62,90.000,NO
R985,"Q_RES_0402LF-33.2,1%,1/16W,CHIA",33.2,1%,R0402,6332.20,4728.62,0.000,YES
R986,"Q_RES_0402LF-33.2,1%,1/16W,CHIA",33.2,1%,R0402,6332.20,4678.62,0.000,YES
R987,"Q_RES_0402LF-33.2,1%,1/16W,CHIA",33.2,1%,R0402,6332.20,4778.62,0.000,YES
R988,"Q_RES_0402LF-33.2,1%,1/16W,CHIA",33.2,1%,R0402,6332.20,4878.62,0.000,YES
R990,"Q_RES_0402LF-2K,1%,1/16W,CHIP,A",2K,1%,R0402,7772.20,4182.12,0.000,NO
R991,"Q_RES_0402LF-2K,1%,1/16W,CHIP,A",2K,1%,R0402,6752.20,5128.62,90.000,NO
R992,"Q_RES_0402LF-2K,1%,1/16W,EMPTYA",2K,1%,R0402,7332.20,3923.62,270.000,NO
R993,"Q_RES_0402LF-33.2,1%,1/16W,CHIA",33.2,1%,R0402,15501.62,6392.16,270.000,NO
R994,"Q_RES_0402LF-33.2,1%,1/16W,CHIA",33.2,1%,R0402,15463.12,6392.16,270.000,NO
R995,"Q_RES_0402LF-33.2,1%,1/16W,CHIA",33.2,1%,R0402,8878.97,8693.54,90.000,NO
R996,"Q_RES_0402LF-33.2,1%,1/16W,CHIA",33.2,1%,R0402,8917.47,8693.54,90.000,NO
R997,"Q_RES_0402LF-10K,1%,1/16W,EMPTA",10K,1%,R0402,15989.16,14381.69,0.000,NO
R998,"Q_RES_0402LF-0,5%,1/16W,CHIP,CA",0,5%,R0402,14281.00,7219.44,180.000,YES
R999,"Q_RES_0402LF-0,5%,1/16W,CHIP,CA",0,5%,R0402,3519.46,7244.72,90.000,YES
R1000,"Q_RES_0402LF-4.7K,5%,1/16W,CHIA",4.7K,5%,R0402,14280.97,7178.65,180.000,YES
R1001,"Q_RES_0402LF-4.7K,5%,1/16W,CHIA",4.7K,5%,R0402,3480.37,7244.75,90.000,YES
R1002,"Q_RES_0402LF-4.7K,5%,1/16W,CHIA",4.7K,5%,R0402,14386.97,7125.75,0.000,YES
R1003,"Q_RES_0402LF-4.7K,5%,1/16W,CHIA",4.7K,5%,R0402,3529.97,7059.65,0.000,YES
R1004,"Q_RES_0402LF-1K,1%,1/16W,CHIP,A",1K,1%,R0402,7635.20,14015.62,180.000,NO
R1005,"Q_RES_0402LF-10K,1%,1/16W,EMPTA",10K,1%,R0402,7635.20,14060.62,0.000,NO
R1006,"Q_RES_0402LF-4.7K,5%,1/16W,CHIA",4.7K,5%,R0402,14332.60,7322.12,180.000,YES
R1007,"Q_RES_0402LF-4.7K,5%,1/16W,CHIA",4.7K,5%,R0402,3559.46,7244.75,90.000,YES
R1008,"Q_RES_0402LF-1K,1%,1/16W,EMPTYA",1K,1%,R0402,2690.46,7314.64,270.000,YES
R1009,"Q_RES_0402LF-1K,1%,1/16W,EMPTYA",1K,1%,R0402,12541.53,7524.49,180.000,YES
R1010,"Q_RES_0402LF-0,5%,1/16W,CHIP,CA",0,5%,R0402,9871.39,4259.56,90.000,NO
R1011,"Q_RES_0402LF-0,5%,1/16W,CHIP,CA",0,5%,R0402,9911.40,4259.56,90.000,NO
R1012,"Q_RES_0402LF-0,5%,1/16W,CHIP,CA",0,5%,R0402,9500.59,4242.98,180.000,NO
R1013,"Q_RES_0402LF-0,5%,1/16W,EMPTY,A",0,5%,R0402,13324.48,5426.47,0.000,YES
R1014,"Q_RES_0402LF-0,5%,1/16W,CHIP,CA",0,5%,R0402,9499.82,4281.24,180.000,NO
R1015,"Q_RES_0402LF-0,5%,1/16W,EMPTY,A",0,5%,R0402,13323.71,5373.21,0.000,YES
R1016,"Q_RES_0402LF-0,5%,1/16W,CHIP,CA",0,5%,R0402,9500.32,4340.18,180.000,NO
R1017,"Q_RES_0402LF-0,5%,1/16W,EMPTY,A",0,5%,R0402,9330.01,5277.51,0.000,YES
R1018,"Q_RES_0402LF-0,5%,1/16W,CHIP,CA",0,5%,R0402,9499.55,4378.44,180.000,NO
R1019,"Q_RES_0402LF-0,5%,1/16W,EMPTY,A",0,5%,R0402,9330.78,5330.77,0.000,YES
R1020,"Q_RES_0402LF-0,5%,1/16W,CHIP,CA",0,5%,R0402,13292.98,5426.47,180.000,YES
R1021,"Q_RES_0402LF-0,5%,1/16W,CHIP,CA",0,5%,R0402,13292.21,5373.21,180.000,YES
R1022,"Q_RES_0402LF-0,5%,1/16W,CHIP,CA",0,5%,R0402,9298.51,5277.51,180.000,YES
R1023,"Q_RES_0402LF-0,5%,1/16W,CHIP,CA",0,5%,R0402,9299.28,5330.77,180.000,YES
R1024,"Q_RES_0402LF-100,1%,1/16W,CHIPA",100,1%,R0402,13661.24,1055.29,270.000,NO
R1025,"Q_RES_0402LF-75,1%,1/16W,EMPTYA",75,1%,R0402,13660.01,970.95,90.000,NO
R1026,"Q_RES_0402LF-1K,1%,1/16W,CHIP,A",1K,1%,R0402,15185.68,2496.98,180.000,NO
R1044,"Q_RES_0402LF-130,1%,1/16W,CHIPA",130,1%,R0402,3420.00,2565.87,270.000,NO
R1089,"Q_RES_0402LF-2.2K,5%,1/16W,CHIA",2.2K,5%,R0402,4383.18,5097.33,0.000,NO
R1090,"Q_RES_0402LF-2.2K,5%,1/16W,CHIA",2.2K,5%,R0402,4383.18,5152.33,0.000,NO
R1099,"Q_RES_0402LF-10K,1%,1/16W,CHIPA",10K,1%,R0402,7772.20,4468.62,90.000,NO
R1100,"Q_RES_0402LF-33.2,1%,1/16W,CHIA",33.2,1%,R0402,7582.20,4433.62,90.000,NO
R1106,"Q_RES_0402LF-10K,1%,1/16W,CHIPA",10K,1%,R0402,7763.40,4888.62,180.000,YES
R1117,"Q_RES_0402LF-6.19K,1%,1/16W,CHA",6.19K,1%,R0402,7077.12,16019.83,0.000,YES
R1123,"Q_RES_0402LF-1K,1%,1/16W,EMPTYA",1K,1%,R0402,17617.41,4613.93,0.000,NO
R1124,"Q_RES_0402LF-1K,1%,1/16W,CHIP,A",1K,1%,R0402,17715.51,4613.93,180.000,NO
R1126,"Q_RES_0402LF-1K,1%,1/16W,CHIP,A",1K,1%,R0402,17715.51,4658.93,180.000,NO
R1127,"Q_RES_0402LF-1K,1%,1/16W,EMPTYA",1K,1%,R0402,18339.51,4539.21,180.000,NO
R1128,"Q_RES_0402LF-1K,1%,1/16W,CHIP,A",1K,1%,R0402,18339.41,4591.21,0.000,NO
R1129,"Q_RES_0402LF-1K,1%,1/16W,CHIP,A",1K,1%,R0402,17586.41,4332.21,0.000,NO
R1130,"Q_RES_0402LF-33.2,1%,1/16W,CHIA",33.2,1%,R0402,18339.41,4631.93,180.000,NO
R1131,"Q_RES_0402LF-33.2,1%,1/16W,CHIA",33.2,1%,R0402,18339.41,4673.21,180.000,NO
R1132,"Q_RES_0402LF-1K,1%,1/16W,EMPTYA",1K,1%,R0402,3382.00,1418.62,180.000,NO
R1138,"Q_RES_0402LF-10K,1%,1/16W,CHIPA",10K,1%,R0402,8449.35,917.51,90.000,NO
R1139,"Q_RES_0402LF-0,5%,1/16W,CHIP,CA",0,5%,R0402,8500.15,917.51,270.000,NO
R1140,"Q_RES_0402LF-27.4,1%,1/16W,CHIA",27.4,1%,R0402,8388.25,904.51,180.000,NO
R1141,"Q_RES_0402LF-27.4,1%,1/16W,CHIA",27.4,1%,R0402,8315.39,643.43,270.000,NO
R1147,"Q_RES_0402LF-0,5%,1/16W,CHIP,CA",0,5%,R0402,18177.99,4032.25,0.000,NO
R1148,"Q_RES_0402LF-0,5%,1/16W,CHIP,CA",0,5%,R0402,18172.99,4279.32,0.000,NO
R1149,"Q_RES_0402LF-10K,1%,1/16W,CHIPA",10K,1%,R0402,18308.79,3991.85,180.000,NO
R1150,"Q_RES_0402LF-10K,1%,1/16W,CHIPA",10K,1%,R0402,18253.39,4342.02,180.000,NO
R1184,"Q_RES_0402LF-0,5%,1/16W,CHIP,CA",0,5%,R0402,4855.00,2953.62,90.000,NO
R1194,"Q_RES_0402LF-4.75K,1%,1/16W,EMA",4.75K,1%,R0402,10172.63,4169.74,0.000,YES
R1195,"Q_RES_0402LF-130,1%,1/16W,CHIPA",130,1%,R0402,8663.20,4314.62,0.000,NO
R1196,"Q_RES_0402LF-4.75K,1%,1/16W,CHA",4.75K,1%,R0402,10172.63,4205.48,180.000,YES
R1197,"Q_RES_0402LF-1K,1%,1/16W,EMPTYA",1K,1%,R0402,12515.86,1241.07,180.000,YES
R1198,"Q_RES_0402LF-10K,1%,1/16W,CHIPA",10K,1%,R0402,12290.93,1169.62,180.000,YES
R1200,"Q_RES_0402LF-100,1%,1/16W,CHIPA",100,1%,R0402,12715.93,2254.62,180.000,YES
R1201,"Q_RES_0402LF-49.9,1%,1/16W,CHIA",49.9,1%,R0402,12405.93,2174.62,180.000,YES
R1202,"Q_RES_0402LF-20K,1%,1/16W,CHIPA",20K,1%,R0402,12802.91,988.28,0.000,NO
R1203,"Q_RES_0402LF-1K,1%,1/16W,CHIP,A",1K,1%,R0402,11838.00,1116.00,180.000,NO
R1204,"Q_RES_0402LF-10K,1%,1/16W,EMPTA",10K,1%,R0402,10032.46,4191.62,0.000,YES
R1205,"Q_RES_0402LF-33.2,1%,1/16W,CHIA",33.2,1%,R0402,7613.40,4748.62,0.000,YES
R1206,"Q_RES_0402LF-33.2,1%,1/16W,CHIA",33.2,1%,R0402,7772.20,4132.12,0.000,NO
R1207,"Q_RES_0402LF-33.2,1%,1/16W,CHIA",33.2,1%,R0402,12819.40,892.72,90.000,NO
R1214,"Q_RES_0402LF-0,5%,1/16W,CHIP,CA",0,5%,R0402,13241.20,899.08,270.000,NO
R1215,"Q_RES_0402LF-49.9,1%,1/16W,CHIA",49.9,1%,R0402,13218.69,637.82,270.000,NO
R1216,"Q_RES_0402LF-1.5K,1%,1/16W,CHIA",1.5K,1%,R0402,15039.76,7413.15,0.000,YES
R1217,"Q_RES_0402LF-1.5K,1%,1/16W,CHIA",1.5K,1%,R0402,6147.50,7519.65,90.000,YES
R1220,"Q_RES_0402LF-1K,1%,1/16W,EMPTYA",1K,1%,R0402,12605.93,2334.62,0.000,NO
R1221,"Q_RES_0402LF-1K,1%,1/16W,CHIP,A",1K,1%,R0402,12495.93,2334.62,180.000,NO
R1226,"Q_RES_0402LF-10K,1%,1/16W,CHIPA",10K,1%,R0402,15219.75,7512.65,90.000,YES
R1227,"Q_RES_0402LF-10K,1%,1/16W,CHIPA",10K,1%,R0402,6116.38,7747.12,180.000,YES
R1229,"Q_RES_0402LF-240,1%,1/16W,EMPTA",240,1%,R0402,7636.20,13754.62,180.000,NO
R1230,"Q_RES_0402LF-240,1%,1/16W,EMPTA",240,1%,R0402,6550.63,9892.41,180.000,YES
R1232,"Q_RES_0402LF-240,1%,1/16W,EMPTA",240,1%,R0402,15989.16,14156.69,180.000,NO
R1233,"Q_RES_0402LF-240,1%,1/16W,EMPTA",240,1%,R0402,15909.15,7600.45,270.000,YES
R1235,"Q_RES_0402LF-240,1%,1/16W,EMPTA",240,1%,R0402,7636.20,13799.62,180.000,NO
R1236,"Q_RES_0402LF-240,1%,1/16W,EMPTA",240,1%,R0402,6550.63,9853.21,180.000,YES
R1237,"Q_RES_0402LF-240,1%,1/16W,EMPTA",240,1%,R0402,13384.95,7508.01,90.000,YES
R1238,"Q_RES_0402LF-240,1%,1/16W,EMPTA",240,1%,R0402,15989.16,14111.69,180.000,NO
R1239,"Q_RES_0402LF-240,1%,1/16W,EMPTA",240,1%,R0402,15909.15,7672.05,90.000,YES
R1240,"Q_RES_0402LF-0,5%,1/16W,CHIP,CA",0,5%,R0402,14992.45,7512.65,90.000,YES
R1241,"Q_RES_0402LF-249,1%,1/16W,CHIPA",249,1%,R0402,12412.77,9074.85,0.000,YES
R1242,"Q_RES_0402LF-301,1%,1/16W,CHIPA",301,1%,R0402,15008.42,7452.40,0.000,YES
R1243,"Q_RES_0402LF-249,1%,1/16W,CHIPA",249,1%,R0402,2756.39,8654.47,90.000,YES
R1244,"Q_RES_0402LF-301,1%,1/16W,CHIPA",301,1%,R0402,6082.50,7514.65,270.000,YES
R1247,"Q_RES_0402LF-0,5%,1/16W,CHIP,CA",0,5%,R0402,12716.58,2352.06,0.000,YES
R1249,"Q_RES_0402LF-0,5%,1/16W,CHIP,CA",0,5%,R0402,12607.93,2515.62,0.000,NO
R1253,"Q_RES_0402LF-1K,1%,1/16W,CHIP,A",1K,1%,R0402,13298.91,953.23,270.000,NO
R1254,"Q_RES_0402LF-10K,1%,1/16W,CHIPA",10K,1%,R0402,13032.64,762.90,90.000,NO
R1255,"Q_RES_0402LF-1K,1%,1/16W,CHIP,A",1K,1%,R0402,13075.78,740.04,270.000,NO
R1257,"Q_RES_0402LF-10K,1%,1/16W,CHIPA",10K,1%,R0402,12187.20,1948.62,180.000,NO
R1259,"Q_RES_0402LF-10K,1%,1/16W,CHIPA",10K,1%,R0402,12300.93,1729.62,0.000,NO
R1260,"Q_RES_0402LF-10K,1%,1/16W,EMPTA",10K,1%,R0402,12605.14,2228.82,90.000,YES
R1262,"Q_RES_0402LF-10K,1%,1/16W,EMPTA",10K,1%,R0402,12407.20,1933.62,180.000,YES
R1263,"Q_RES_0402LF-33.2,1%,1/16W,CHIA",33.2,1%,R0402,12405.93,2058.62,180.000,NO
R1266,"Q_RES_0402LF-75,1%,1/16W,CHIP,A",75,1%,R0402,12496.78,2454.42,0.000,NO
R1267,"Q_RES_0402LF-1K,1%,1/16W,CHIP,A",1K,1%,R0402,10032.46,4226.82,180.000,YES
R1268,"Q_RES_0402LF-33.2,1%,1/16W,CHIA",33.2,1%,R0402,12976.65,811.69,0.000,NO
R1269,"Q_RES_0402LF-4.75K,1%,1/16W,CHA",4.75K,1%,R0402,12990.11,851.38,180.000,NO
R1270,"Q_RES_0402LF-240,1%,1/16W,EMPTA",240,1%,R0402,6547.29,9734.28,180.000,YES
R1271,"Q_RES_0402LF-2.21K,1%,1/16W,EMA",2.21K,1%,R0402,12860.13,808.99,90.000,NO
R1273,"Q_RES_0402LF-22,1%,1/16W,CHIP,A",22,1%,R0402,9008.53,4849.13,180.000,NO
R1274,"Q_RES_0402LF-22,1%,1/16W,CHIP,A",22,1%,R0402,9008.53,4809.13,180.000,NO
R1275,"Q_RES_0402LF-22,1%,1/16W,CHIP,A",22,1%,R0402,9092.93,4634.28,270.000,NO
R1276,"Q_RES_0402LF-22,1%,1/16W,CHIP,A",22,1%,R0402,9132.93,4634.28,270.000,NO
R1289,"Q_RES_0402LF-100K,1%,1/16W,CHIA",100K,1%,R0402,18367.50,3779.83,270.000,NO
R1290,"Q_RES_0402LF-22,1%,1/16W,EMPTYA",22,1%,R0402,7538.35,3112.45,270.000,YES
R1291,"Q_RES_0402LF-22,1%,1/16W,CHIP,A",22,1%,R0402,7652.42,2992.79,0.000,NO
R1292,"Q_RES_0402LF-22,1%,1/16W,CHIP,A",22,1%,R0402,7876.26,3034.10,180.000,NO
R1293,"Q_RES_0402LF-22,1%,1/16W,CHIP,A",22,1%,R0402,7875.41,3087.55,180.000,NO
R1294,"Q_RES_0402LF-0,5%,1/16W,CHIP,CA",0,5%,R0402,8455.05,2859.91,90.000,NO
R1295,"Q_RES_0402LF-0,5%,1/16W,CHIP,CA",0,5%,R0402,8231.08,2798.85,0.000,NO
R1296,"Q_RES_0402LF-0,5%,1/16W,CHIP,CA",0,5%,R0402,8231.08,2748.85,0.000,NO
R1297,"Q_RES_0402LF-0,5%,1/16W,CHIP,CA",0,5%,R0402,12075.30,2205.52,90.000,NO
R1298,"Q_RES_0402LF-1K,1%,1/16W,EMPTYA",1K,1%,R0402,12300.93,1299.62,0.000,YES
R1299,"Q_RES_0402LF-10K,1%,1/16W,CHIPA",10K,1%,R0402,12187.33,1269.42,180.000,YES
R1300,"Q_RES_0402LF-33.2,1%,1/16W,CHIA",33.2,1%,R0402,12100.93,1649.62,180.000,NO
R1302,"Q_RES_0402LF-2K,1%,1/16W,EMPTYA",2K,1%,R0402,7012.63,4122.55,180.000,YES
R1305,"Q_RES_0402LF-10K,1%,1/16W,EMPTA",10K,1%,R0402,10527.05,3646.95,270.000,NO
R1306,"Q_RES_0402LF-33.2,1%,1/16W,CHIA",33.2,1%,R0402,13435.91,1206.18,180.000,YES
R1307,"Q_RES_0402LF-33.2,1%,1/16W,CHIA",33.2,1%,R0402,12122.02,1191.17,270.000,NO
R1308,"Q_RES_0402LF-10K,1%,1/16W,EMPTA",10K,1%,R0402,7512.20,5263.62,90.000,NO
R1309,"Q_RES_0402LF-33.2,1%,1/16W,CHIA",33.2,1%,R0402,13505.92,1206.18,0.000,YES
R1310,"Q_RES_0402LF-33.2,1%,1/16W,CHIA",33.2,1%,R0402,12978.21,1015.88,270.000,YES
R1311,"Q_RES_0402LF-10K,1%,1/16W,CHIPA",10K,1%,R0402,13369.30,1257.07,90.000,YES
R1312,"Q_RES_0402LF-10K,1%,1/16W,EMPTA",10K,1%,R0402,7622.20,4182.12,180.000,YES
R1313,"Q_RES_0402LF-33.2,1%,1/16W,CHIA",33.2,1%,R0402,7613.40,4748.62,180.000,NO
R1316,"Q_RES_0603LF-200K,0.1%,1/10W,EA",200K,0.1%,R0603_H24,13244.37,2559.66,0.000,NO
R1317,"Q_RES_0402LF-1K,1%,1/16W,CHIP,A",1K,1%,R0402,17132.80,1659.09,180.000,NO
R1318,"Q_RES_0402LF-0,5%,1/16W,CHIP,CA",0,5%,R0402,7402.00,3697.25,270.000,NO
R1319,"Q_RES_0402LF-2K,1%,1/16W,EMPTYA",2K,1%,R0402,7234.00,840.62,270.000,YES
R1320,"Q_RES_0402LF-1K,1%,1/16W,CHIP,A",1K,1%,R0402,17133.29,1619.00,180.000,NO
R1324,"Q_RES_0402LF-1K,1%,1/16W,CHIP,A",1K,1%,R0402,17133.29,1578.92,180.000,NO
R1325,"Q_RES_0402LF-1K,1%,1/16W,CHIP,A",1K,1%,R0402,16280.33,1296.27,0.000,NO
R1326,"Q_RES_0402LF-2K,1%,1/16W,EMPTYA",2K,1%,R0402,6882.47,3831.55,270.000,YES
R1327,"Q_RES_0402LF-2K,1%,1/16W,EMPTYA",2K,1%,R0402,7009.85,4215.40,180.000,YES
R1328,"Q_RES_0402LF-2K,1%,1/16W,EMPTYA",2K,1%,R0402,7160.47,4122.69,180.000,YES
R1329,"Q_RES_0402LF-2K,1%,1/16W,EMPTYA",2K,1%,R0402,6164.57,4001.49,0.000,YES
R1330,"Q_RES_0402LF-2K,1%,1/16W,EMPTYA",2K,1%,R0402,6882.90,3839.22,90.000,NO
R1331,"Q_RES_0402LF-4.7K,5%,1/16W,EMPA",4.7K,5%,R0402,11520.10,3680.41,180.000,NO
R1332,"Q_RES_0402LF-4.7K,5%,1/16W,EMPA",4.7K,5%,R0402,11520.80,3632.31,180.000,NO
R1333,"Q_RES_0402LF-1K,1%,1/16W,CHIP,A",1K,1%,R0402,16195.15,1160.59,270.000,NO
R1335,"Q_RES_0402LF-1K,1%,1/16W,CHIP,A",1K,1%,R0402,16280.33,1176.27,0.000,NO
R1336,"Q_RES_0402LF-2.2K,5%,1/16W,EMPA",2.2K,5%,R0402,6902.20,541.82,270.000,YES
R1338,"Q_RES_0402LF-10K,1%,1/16W,CHIPA",10K,1%,R0402,12092.20,2003.09,180.000,NO
R1339,"Q_RES_0402LF-10K,1%,1/16W,CHIPA",10K,1%,R0402,12405.93,2014.62,0.000,YES
R1340,"Q_RES_0402LF-20K,1%,1/16W,CHIPA",20K,1%,R0402,11912.06,1375.49,90.000,NO
R1341,"Q_RES_0402LF-10K,1%,1/16W,CHIPA",10K,1%,R0402,11969.88,2126.48,180.000,NO
R1342,"Q_RES_0402LF-10K,1%,1/16W,CHIPA",10K,1%,R0402,11814.76,1653.06,270.000,NO
R1343,"Q_RES_0402LF-10K,1%,1/16W,CHIPA",10K,1%,R0402,11733.74,1716.31,90.000,NO
R1345,"Q_RES_0402LF-0,5%,1/16W,CHIP,CA",0,5%,R0402,5077.50,2945.83,270.000,NO
R1346,"Q_RES_0402LF-100,1%,1/16W,CHIPA",100,1%,R0402,14838.00,4219.82,180.000,NO
R1347,"Q_RES_0402LF-1K,1%,1/16W,CHIP,A",1K,1%,R0402,14627.77,3659.96,270.000,NO
R1348,"Q_RES_0402LF-0,5%,1/16W,CHIP,CA",0,5%,R0402,3802.20,2088.62,180.000,NO
R1349,"Q_RES_0402LF-0,5%,1/16W,CHIP,CA",0,5%,R0402,4297.20,2098.62,0.000,NO
R1350,"Q_RES_0402LF-100K,1%,1/16W,CHIA",100K,1%,R0402,7790.42,2992.79,0.000,NO
R1351,"Q_RES_0402LF-100K,1%,1/16W,CHIA",100K,1%,R0402,7745.26,3034.10,180.000,NO
R1352,"Q_RES_0402LF-100K,1%,1/16W,CHIA",100K,1%,R0402,7744.41,3087.55,180.000,NO
R1353,"Q_RES_0402LF-100K,1%,1/16W,CHIA",100K,1%,R0402,8455.05,2962.77,90.000,NO
R1354,"Q_RES_0402LF-100K,1%,1/16W,CHIA",100K,1%,R0402,8346.35,2800.45,0.000,NO
R1355,"Q_RES_0402LF-100K,1%,1/16W,CHIA",100K,1%,R0402,8346.35,2750.45,0.000,NO
R1356,"Q_RES_0402LF-1K,1%,1/16W,CHIP,A",1K,1%,R0402,6538.20,857.62,90.000,NO
R1365,"Q_RES_0402LF-1K,1%,1/16W,CHIP,A",1K,1%,R0402,4254.20,2405.62,0.000,NO
R1366,"Q_RES_0402LF-100,1%,1/16W,CHIPA",100,1%,R0402,14773.84,4152.88,270.000,NO
R1367,"Q_RES_0402LF-100,1%,1/16W,CHIPA",100,1%,R0402,14893.84,4152.88,270.000,NO
R1368,"Q_RES_0402LF-1K,1%,1/16W,CHIP,A",1K,1%,R0402,14813.84,4152.88,90.000,NO
R1369,"Q_RES_0402LF-1K,1%,1/16W,CHIP,A",1K,1%,R0402,14933.84,4152.88,90.000,NO
R1370,"Q_RES_0402LF-100,1%,1/16W,CHIPA",100,1%,R0402,3547.20,2218.62,0.000,NO
R1371,"Q_RES_0402LF-130,1%,1/16W,CHIPA",130,1%,R0402,3171.29,2562.31,270.000,NO
R1374,"Q_RES_0402LF-1K,1%,1/16W,CHIP,A",1K,1%,R0402,3802.20,2253.62,180.000,NO
R1375,"Q_RES_0402LF-10K,1%,1/16W,CHIPA",10K,1%,R0402,3802.20,2128.62,180.000,NO
R1380,"Q_RES_0402LF-1K,1%,1/16W,CHIP,A",1K,1%,R0402,5067.57,3154.04,0.000,NO
R1381,"Q_RES_0402LF-1K,1%,1/16W,CHIP,A",1K,1%,R0402,14496.00,3983.12,270.000,NO
R1382,"Q_RES_0402LF-1K,1%,1/16W,CHIP,A",1K,1%,R0402,14938.74,3656.98,270.000,NO
R1383,"Q_RES_0402LF-1K,1%,1/16W,CHIP,A",1K,1%,R0402,5685.00,368.62,270.000,YES
R1384,"Q_RES_0402LF-2K,1%,1/16W,EMPTYA",2K,1%,R0402,6390.00,618.62,270.000,YES
R1385,"Q_RES_0402LF-2K,1%,1/16W,EMPTYA",2K,1%,R0402,6350.00,618.62,270.000,YES
R1386,"Q_RES_0402LF-2K,1%,1/16W,EMPTYA",2K,1%,R0402,7027.90,541.72,90.000,YES
R1387,"Q_RES_0402LF-2K,1%,1/16W,EMPTYA",2K,1%,R0402,7040.00,778.62,90.000,NO
R1388,"Q_RES_0402LF-2K,1%,1/16W,EMPTYA",2K,1%,R0402,7773.13,4326.65,180.000,YES
R1389,"Q_RES_0402LF-0,5%,1/16W,CHIP,CA",0,5%,R0402,10199.39,2989.13,270.000,NO
R1390,"Q_RES_0402LF-1K,1%,1/16W,EMPTYA",1K,1%,R0402,9950.23,3631.55,0.000,NO
R1391,"Q_RES_0402LF-240,1%,1/16W,EMPTA",240,1%,R0402,10988.96,7624.79,270.000,YES
R1392,"Q_RES_0402LF-240,1%,1/16W,EMPTA",240,1%,R0402,11027.96,7624.79,270.000,YES
R1393,"Q_RES_0402LF-240,1%,1/16W,EMPTA",240,1%,R0402,1996.02,7608.65,270.000,YES
R1394,"Q_RES_0402LF-240,1%,1/16W,EMPTA",240,1%,R0402,2076.02,7608.65,270.000,YES
R1395,"Q_RES_0402LF-33.2,1%,1/16W,CHIA",33.2,1%,R0402,13092.28,1235.68,90.000,YES
R1396,"Q_RES_0402LF-10K,1%,1/16W,CHIPA",10K,1%,R0402,7117.20,1573.62,0.000,NO
R1398,"Q_RES_0402LF-2K,1%,1/16W,EMPTYA",2K,1%,R0402,7282.20,3823.62,270.000,NO
R1399,"Q_RES_0402LF-10K,1%,1/16W,CHIPA",10K,1%,R0402,6852.20,5128.62,90.000,NO
R1401,"Q_RES_0402LF-10K,1%,1/16W,CHIPA",10K,1%,R0402,6482.20,4778.62,180.000,NO
R1402,"Q_RES_0402LF-2K,1%,1/16W,CHIP,A",2K,1%,R0402,12628.98,1474.13,45.000,YES
R1403,"Q_RES_0402LF-2K,1%,1/16W,CHIP,A",2K,1%,R0402,12438.82,950.08,180.000,NO
R1404,"Q_RES_0402LF-2K,1%,1/16W,CHIP,A",2K,1%,R0402,6802.20,4998.62,90.000,NO
R1405,"Q_RES_0402LF-2K,1%,1/16W,CHIP,A",2K,1%,R0402,6332.20,4778.62,180.000,NO
R1406,"Q_RES_0402LF-2K,1%,1/16W,CHIP,A",2K,1%,R0402,6482.20,4728.62,0.000,YES
R1407,"Q_RES_0402LF-2K,1%,1/16W,CHIP,A",2K,1%,R0402,6332.20,4728.62,180.000,NO
R1408,"Q_RES_0402LF-2K,1%,1/16W,CHIP,A",2K,1%,R0402,6482.20,4778.62,0.000,YES
R1409,"Q_RES_0402LF-2K,1%,1/16W,CHIP,A",2K,1%,R0402,6332.20,4678.62,180.000,NO
R1410,"Q_RES_0402LF-2K,1%,1/16W,CHIP,A",2K,1%,R0402,6482.20,4678.62,0.000,YES
R1411,"Q_RES_0402LF-2K,1%,1/16W,CHIP,A",2K,1%,R0402,6752.20,4998.62,90.000,NO
R1412,"Q_RES_0402LF-2K,1%,1/16W,CHIP,A",2K,1%,R0402,6332.20,4828.62,0.000,YES
R1413,"Q_RES_0402LF-2K,1%,1/16W,CHIP,A",2K,1%,R0402,6482.20,4828.62,180.000,NO
R1414,"Q_RES_0402LF-2K,1%,1/16W,CHIP,A",2K,1%,R0402,6482.20,4828.62,0.000,YES
R1415,"Q_RES_0402LF-2K,1%,1/16W,EMPTYA",2K,1%,R0402,7182.20,3923.62,270.000,NO
R1416,"Q_RES_0402LF-2K,1%,1/16W,EMPTYA",2K,1%,R0402,7419.90,4126.92,0.000,YES
R1417,"Q_RES_0402LF-2K,1%,1/16W,CHIP,A",2K,1%,R0402,7052.20,5128.62,90.000,NO
R1418,"Q_RES_0402LF-2K,1%,1/16W,CHIP,A",2K,1%,R0402,7112.20,5128.62,90.000,NO
R1419,"Q_RES_0402LF-2K,1%,1/16W,CHIP,A",2K,1%,R0402,7613.40,4648.62,180.000,YES
R1420,"Q_RES_0402LF-2K,1%,1/16W,CHIP,A",2K,1%,R0402,7613.40,4648.62,0.000,NO
R1421,"Q_RES_0402LF-2K,1%,1/16W,CHIP,A",2K,1%,R0402,7763.40,4698.62,0.000,NO
R1423,"Q_RES_0402LF-33.2,1%,1/16W,CHIA",33.2,1%,R0402,12532.42,1384.68,225.000,YES
R1434,"Q_RES_0402LF-10K,1%,1/16W,CHIPA",10K,1%,R0402,7613.40,4698.62,0.000,NO
R1435,"Q_RES_0402LF-10K,1%,1/16W,CHIPA",10K,1%,R0402,7622.20,4082.12,180.000,YES
R1437,"Q_RES_0402LF-10K,1%,1/16W,CHIPA",10K,1%,R0402,7622.20,4232.12,180.000,YES
R1440,"Q_RES_0402LF-10K,1%,1/16W,EMPTA",10K,1%,R0402,6332.20,4310.62,0.000,YES
R1442,"Q_RES_0402LF-33.2,1%,1/16W,CHIA",33.2,1%,R0402,12438.82,987.85,0.000,NO
R1443,"Q_RES_0402LF-33.2,1%,1/16W,CHIA",33.2,1%,R0402,4457.20,4007.62,90.000,NO
R1444,"Q_RES_0402LF-33.2,1%,1/16W,CHIA",33.2,1%,R0402,6852.20,4998.62,270.000,NO
R1445,"Q_RES_0402LF-2K,1%,1/16W,CHIP,A",2K,1%,R0402,17020.67,6974.65,90.000,YES
R1446,"Q_RES_0402LF-33.2,1%,1/16W,CHIA",33.2,1%,R0402,6802.20,5128.62,270.000,NO
R1447,"Q_RES_0402LF-33.2,1%,1/16W,CHIA",33.2,1%,R0402,6952.20,5128.62,270.000,NO
R1448,"Q_RES_0402LF-33.2,1%,1/16W,CHIA",33.2,1%,R0402,7052.20,5263.62,270.000,NO
R1449,"Q_RES_0402LF-10K,1%,1/16W,CHIPA",10K,1%,R0402,12185.93,1649.62,180.000,NO
R1450,"Q_RES_0402LF-10K,1%,1/16W,CHIPA",10K,1%,R0402,12185.93,1194.62,180.000,NO
R1451,"Q_RES_0402LF-2K,1%,1/16W,CHIP,A",2K,1%,R0402,12185.93,1579.62,180.000,NO
R1452,"Q_RES_0402LF-2K,1%,1/16W,CHIP,A",2K,1%,R0402,12244.94,1139.82,180.000,NO
R1453,"Q_RES_0402LF-2K,1%,1/16W,CHIP,A",2K,1%,R0402,12343.91,1066.09,180.000,NO
R1454,"Q_RES_0402LF-2K,1%,1/16W,CHIP,A",2K,1%,R0402,12301.11,1294.09,180.000,NO
R1455,"Q_RES_0402LF-49.9,1%,1/16W,CHIA",49.9,1%,R0402,12687.54,885.72,0.000,NO
R1456,"Q_RES_0402LF-49.9,1%,1/16W,CHIA",49.9,1%,R0402,12185.93,1854.62,0.000,NO
R1457,"Q_RES_0402LF-10K,1%,1/16W,CHIPA",10K,1%,R0402,13328.86,1277.07,90.000,YES
R1458,"Q_RES_0402LF-10K,1%,1/16W,CHIPA",10K,1%,R0402,13505.92,1247.18,180.000,YES
R1459,"Q_RES_0402LF-10K,1%,1/16W,CHIPA",10K,1%,R0402,12917.04,1047.31,90.000,YES
R1460,"Q_RES_0402LF-2.2K,5%,1/16W,EMPA",2.2K,5%,R0402,6859.68,541.82,270.000,YES
R1461,"Q_RES_0402LF-0,5%,1/16W,CHIP,CA",0,5%,R0402,12876.41,1135.55,270.000,YES
R1462,"Q_RES_0402LF-1K,1%,1/16W,CHIP,A",1K,1%,R0402,9888.79,4219.61,0.000,YES
R1463,"Q_RES_0402LF-0,5%,1/16W,CHIP,CA",0,5%,R0402,13351.20,2105.19,90.000,YES
R1464,"Q_RES_0402LF-0,5%,1/16W,CHIP,CA",0,5%,R0402,13919.37,2237.54,0.000,YES
R1465,"Q_RES_0402LF-10K,1%,1/16W,EMPTA",10K,1%,R0402,7763.40,4548.62,180.000,NO
R1467,"Q_RES_0402LF-4.7K,1%,1/16W,EMPA",4.7K,1%,R0402,6332.20,4578.62,0.000,NO
R1469,"Q_RES_0402LF-33.2,1%,1/16W,CHIA",33.2,1%,R0402,7763.40,4648.62,0.000,NO
R1470,"Q_RES_0402LF-33.2,1%,1/16W,CHIA",33.2,1%,R0402,7913.40,4648.62,0.000,NO
R1471,"Q_RES_0402LF-4.75K,1%,1/16W,CHA",4.75K,1%,R0402,10010.59,3418.29,0.000,YES
R1472,"Q_RES_0402LF-33.2,1%,1/16W,CHIA",33.2,1%,R0402,15185.68,2311.16,180.000,NO
R1473,"Q_RES_0402LF-1K,1%,1/16W,CHIP,A",1K,1%,R0402,7512.20,5128.62,270.000,YES
R1474,"Q_RES_0402LF-1K,1%,1/16W,CHIP,A",1K,1%,R0402,7622.20,4132.12,180.000,YES
R1475,"Q_RES_0402LF-1K,1%,1/16W,EMPTYA",1K,1%,R0402,12605.93,2435.62,0.000,NO
R1476,"Q_RES_0402LF-1K,1%,1/16W,CHIP,A",1K,1%,R0402,12495.93,2414.62,180.000,NO
R1477,"Q_RES_0402LF-1K,1%,1/16W,EMPTYA",1K,1%,R0402,12605.93,2386.62,0.000,NO
R1478,"Q_RES_0402LF-10K,1%,1/16W,CHIPA",10K,1%,R0402,12495.93,2374.62,180.000,NO
R1479,"Q_RES_0402LF-10,1%,1/16W,CHIP,A",10,1%,R0402,13229.06,987.03,270.000,NO
R1483,"Q_RES_0402LF-10K,1%,1/16W,EMPTA",10K,1%,R0402,9842.54,4143.96,90.000,YES
R1484,"Q_RES_0402LF-1K,1%,1/16W,EMPTYA",1K,1%,R0402,9800.92,4143.96,270.000,YES
R1485,"Q_RES_0402LF-200,1%,1/16W,EMPTA",200,1%,R0402,12715.93,2294.62,180.000,YES
R1486,"Q_RES_0402LF-200,1%,1/16W,EMPTA",200,1%,R0402,12406.20,2215.62,180.000,YES
R1487,"Q_RES_0402LF-100,1%,1/16W,CHIPA",100,1%,R0402,12819.13,808.99,270.000,NO
R1492,"Q_RES_0402LF-10K,1%,1/16W,CHIPA",10K,1%,R0402,7622.20,4232.12,0.000,NO
R1493,"Q_RES_0402LF-1K,1%,1/16W,CHIP,A",1K,1%,R0402,5001.60,6156.12,180.000,NO
R1494,"Q_RES_0402LF-1K,1%,1/16W,EMPTYA",1K,1%,R0402,7622.20,4182.12,0.000,NO
R1495,"Q_RES_0402LF-10K,1%,1/16W,CHIPA",10K,1%,R0402,5170.00,6157.42,180.000,NO
R1496,"Q_RES_0402LF-10K,1%,1/16W,CHIPA",10K,1%,R0402,12495.93,2196.62,0.000,NO
R1497,"Q_RES_0402LF-12K,1%,1/16W,EMPTA",12K,1%,R0402,12405.93,2174.62,180.000,NO
R1498,"Q_RES_0402LF-1K,1%,1/16W,EMPTYA",1K,1%,R0402,12306.23,1566.72,180.000,YES
R1499,"Q_RES_0402LF-1K,1%,1/16W,CHIP,A",1K,1%,R0402,12306.23,1526.12,0.000,YES
R1500,"Q_RES_0402LF-4.75K,1%,1/16W,CHA",4.75K,1%,R0402,9949.56,4259.02,270.000,YES
R1502,"Q_RES_0402LF-4.75K,1%,1/16W,CHA",4.75K,1%,R0402,9887.59,3417.99,0.000,YES
R1504,"Q_RES_0402LF-33.2,1%,1/16W,CHIA",33.2,1%,R0402,17795.75,152.22,270.000,YES
R1505,"Q_RES_0402LF-33.2,1%,1/16W,CHIA",33.2,1%,R0402,17744.35,152.42,270.000,YES
R1514,"Q_RES_0402LF-33.2,1%,1/16W,CHIA",33.2,1%,R0402,15483.88,1277.81,180.000,NO
R1520,"Q_RES_0402LF-33.2,1%,1/16W,CHIA",33.2,1%,R0402,3490.38,1428.69,180.000,NO
R1525,"Q_RES_0402LF-0,5%,1/16W,CHIP,CA",0,5%,R0402,9566.97,3994.01,180.000,YES
R1526,"Q_RES_0402LF-33.2,1%,1/16W,CHIA",33.2,1%,R0402,9566.97,4036.56,180.000,YES
R1527,"Q_RES_0402LF-1K,1%,1/16W,CHIP,A",1K,1%,R0402,10356.88,3915.37,270.000,YES
R1541,"Q_RES_0402LF-100K,1%,1/16W,CHIA",100K,1%,R0402,7763.40,4748.62,0.000,YES
R1543,"Q_RES_0402LF-0,5%,1/16W,CHIP,CA",0,5%,R0402,9105.84,4936.11,180.000,YES
R1545,"Q_RES_0402LF-2K,1%,1/16W,CHIP,A",2K,1%,R0402,12343.90,1026.08,180.000,NO
R1546,"Q_RES_0402LF-2K,1%,1/16W,CHIP,A",2K,1%,R0402,12185.93,1409.62,0.000,NO
R1547,"Q_RES_0402LF-0,5%,1/16W,CHIP,CA",0,5%,R0402,6482.20,4263.62,180.000,NO
R1551,"Q_RES_0402LF-4.7K,1%,1/16W,EMPA",4.7K,1%,R0402,6482.20,4578.62,0.000,NO
R1554,"Q_RES_0402LF-10K,1%,1/16W,CHIPA",10K,1%,R0402,13425.25,1479.32,270.000,YES
R1558,"Q_RES_0402LF-10K,1%,1/16W,EMPTA",10K,1%,R0402,7622.20,4282.12,0.000,NO
R1571,"Q_RES_0402LF-100K,1%,1/16W,CHIA",100K,1%,R0402,17793.19,3051.80,90.000,YES
R1581,"Q_RES_0402LF-2K,1%,1/16W,CHIP,A",2K,1%,R0402,12300.93,1634.62,180.000,NO
R1582,"Q_RES_0402LF-2K,1%,1/16W,CHIP,A",2K,1%,R0402,12300.93,1411.10,180.000,NO
R1583,"Q_RES_0402LF-10K,1%,1/16W,CHIPA",10K,1%,R0402,12300.93,1569.62,180.000,NO
R1592,"Q_RES_0402LF-10K,1%,1/16W,CHIPA",10K,1%,R0402,18373.05,1926.78,180.000,NO
R1593,"Q_RES_0402LF-4.7K,1%,1/16W,CHIA",4.7K,1%,R0402,15437.79,1227.78,270.000,NO
R1594,"Q_RES_0402LF-33.2,1%,1/16W,CHIA",33.2,1%,R0402,18444.55,1767.22,0.000,NO
R1595,"Q_RES_0402LF-33.2,1%,1/16W,CHIA",33.2,1%,R0402,15476.97,1227.78,90.000,NO
R1600,"Q_RES_0402LF-33.2,1%,1/16W,CHIA",33.2,1%,R0402,12185.93,1329.62,180.000,NO
R1601,"Q_RES_0402LF-10K,1%,1/16W,CHIPA",10K,1%,R0402,12300.93,1342.62,180.000,NO
R1605,"Q_RES_0402LF-1K,1%,1/16W,CHIP,A",1K,1%,R0402,6477.20,1848.62,180.000,NO
R1606,"Q_RES_0402LF-33.2,1%,1/16W,CHIA",33.2,1%,R0402,6482.20,4313.62,0.000,NO
R1607,"Q_RES_0402LF-0,5%,1/16W,EMPTY,A",0,5%,R0402,6548.95,5195.94,270.000,NO
R1640,"Q_RES_0402LF-0,5%,1/16W,CHIP,CA",0,5%,R0402,6618.65,5100.54,90.000,NO
R1641,"Q_RES_0402LF-100K,1%,1/16W,CHIA",100K,1%,R0402,6590.39,5195.91,90.000,NO
R1642,"Q_RES_0402LF-10K,1%,1/16W,CHIPA",10K,1%,R0402,6508.45,5266.80,270.000,NO
R1643,"Q_RES_0402LF-100K,1%,1/16W,CHIA",100K,1%,R0402,6468.15,5138.84,270.000,NO
R1648,"Q_RES_0402LF-0,5%,1/16W,EMPTY,A",0,5%,R0402,15397.20,5858.62,270.000,NO
R1650,"Q_RES_0402LF-0,5%,1/16W,CHIP,CA",0,5%,R0402,10129.42,2965.70,90.000,YES
R1652,"Q_RES_0402LF-0,5%,1/16W,CHIP,CA",0,5%,R0402,17094.86,7124.87,270.000,YES
R1654,"Q_RES_0402LF-1K,1%,1/16W,CHIP,A",1K,1%,R0402,6507.94,5196.07,270.000,NO
R1655,"Q_RES_0402LF-10K,1%,1/16W,CHIPA",10K,1%,R0402,17071.60,2057.00,270.000,YES
R1656,"Q_RES_0402LF-33.2,1%,1/16W,CHIA",33.2,1%,R0402,12300.93,1449.62,0.000,YES
R1657,"Q_RES_0402LF-33.2,1%,1/16W,CHIA",33.2,1%,R0402,12300.93,1409.62,0.000,YES
R1659,"Q_RES_0402LF-10K,1%,1/16W,CHIPA",10K,1%,R0402,12652.33,1558.06,45.000,YES
R1660,"Q_RES_0402LF-10K,1%,1/16W,EMPTA",10K,1%,R0402,6482.20,4388.62,0.000,YES
R1661,"Q_RES_0402LF-33.2,1%,1/16W,CHIA",33.2,1%,R0402,1411.03,4818.13,90.000,NO
R1662,"Q_RES_0402LF-33.2,1%,1/16W,CHIA",33.2,1%,R0402,1241.70,4818.13,90.000,NO
R1671,"Q_RES_0402LF-0,5%,1/16W,CHIP,CA",0,5%,R0402,17118.32,637.33,270.000,NO
R1673,"Q_RES_0402LF-10K,1%,1/16W,CHIPA",10K,1%,R0402,8827.15,1831.69,0.000,NO
R1675,"Q_RES_0402LF-2.49K,1%,1/16W,CHA",2.49K,1%,R0402,12802.91,2441.14,270.000,YES
R1676,"Q_RES_0402LF-1K,1%,1/16W,EMPTYA",1K,1%,R0402,12841.20,2431.42,270.000,YES
R1680,"Q_RES_0402LF-0,5%,1/16W,CHIP,CA",0,5%,R0402,9882.19,4143.96,90.000,YES
R1681,"Q_RES_0402LF-10K,1%,1/16W,CHIPA",10K,1%,R0402,6182.20,4478.62,180.000,YES
R1688,"Q_RES_0402LF-100K,1%,1/16W,CHIA",100K,1%,R0402,8257.70,5150.82,0.000,NO
R1689,"Q_RES_0402LF-6.19K,1%,1/16W,CHA",6.19K,1%,R0402,8257.70,5190.82,180.000,NO
R1690,"Q_RES_0402LF-10K,1%,1/16W,CHIPA",10K,1%,R0402,8257.70,5230.82,0.000,NO
R1691,"Q_RES_0402LF-10K,1%,1/16W,EMPTA",10K,1%,R0402,8586.20,5071.62,180.000,NO
R1692,"Q_RES_0402LF-100K,1%,1/16W,CHIA",100K,1%,R0402,8586.20,4990.62,0.000,NO
R1693,"Q_RES_0402LF-33.2,1%,1/16W,CHIA",33.2,1%,R0402,8257.70,5060.82,180.000,NO
R1694,"Q_RES_0402LF-10K,1%,1/16W,CHIPA",10K,1%,R0402,12673.22,1051.64,90.000,NO
R1695,"Q_RES_0402LF-0,5%,1/16W,EMPTY,A",0,5%,R0402,8257.70,5020.82,0.000,NO
R1700,"Q_RES_0402LF-200K,1%,1/16W,CHIA",200K,1%,R0402,6292.20,2303.62,180.000,NO
R1702,"Q_RES_0402LF-4.7K,5%,1/16W,CHIA",4.7K,5%,R0402,5832.20,2213.62,0.000,NO
R1703,"Q_RES_0402LF-4.7K,5%,1/16W,CHIA",4.7K,5%,R0402,5832.20,2253.62,0.000,NO
R1706,"Q_RES_0402LF-10K,1%,1/16W,EMPTA",10K,1%,R0402,16619.45,1959.35,180.000,NO
R1710,"Q_RES_0402LF-49.9,1%,1/16W,CHIA",49.9,1%,R0402,7763.40,4888.62,0.000,NO
R1712,"Q_RES_0402LF-4.7K,5%,1/16W,EMPA",4.7K,5%,R0402,5577.20,14513.62,270.000,NO
R1713,"Q_RES_0402LF-4.7K,5%,1/16W,EMPA",4.7K,5%,R0402,5520.00,14513.62,270.000,NO
R1714,"Q_RES_0402LF-0,5%,1/16W,CHIP,CA",0,5%,R0402,7122.98,16073.02,90.000,YES
R1717,"Q_RES_0402LF-49.9,1%,1/16W,CHIA",49.9,1%,R0402,17293.79,4868.69,180.000,NO
R1718,"Q_RES_0402LF-49.9,1%,1/16W,CHIA",49.9,1%,R0402,791.90,6525.64,0.000,NO
R1719,"Q_RES_0402LF-33.2,1%,1/16W,CHIA",33.2,1%,R0402,17930.69,3902.52,0.000,NO
R1720,"Q_RES_0402LF-0,5%,1/16W,EMPTY,A",0,5%,R0402,13240.93,2494.62,270.000,NO
R1721,"Q_RES_0402LF-0,5%,1/16W,CHIP,CA",0,5%,R0402,12885.70,1346.52,45.000,NO
R1724,"Q_RES_0402LF-0,5%,1/16W,CHIP,CA",0,5%,R0402,9817.89,3624.60,90.000,NO
R1735,"Q_RES_0402LF-100,1%,1/16W,CHIPA",100,1%,R0402,17293.79,4908.69,180.000,NO
R1736,"Q_RES_0402LF-33.2,1%,1/16W,CHIA",33.2,1%,R0402,12680.33,1527.36,45.000,YES
R1741,"Q_RES_0402LF-1K,1%,1/16W,CHIP,A",1K,1%,R0402,7452.20,5128.62,270.000,YES
R1742,"Q_RES_0402LF-10K,1%,1/16W,EMPTA",10K,1%,R0402,7452.20,5263.62,90.000,NO
R1744,"Q_RES_0402LF-0,5%,1/16W,CHIP,CA",0,5%,R0402,12581.95,1278.37,270.000,YES
R1745,"Q_RES_0402LF-0,5%,1/16W,EMPTY,A",0,5%,R0402,8257.70,5270.82,180.000,NO
R1747,"Q_RES_0805LF-0,5%,1/8W,CHIP,CSA",0,5%,R0805,12688.47,624.22,0.000,NO
R1748,"Q_RES_0402LF-0,5%,1/16W,CHIP,CA",0,5%,R0402,13197.21,740.05,270.000,NO
R1749,"Q_RES_0402LF-10K,1%,1/16W,EMPTA",10K,1%,R0402,13137.88,638.00,90.000,NO
R1750,"Q_RES_0402LF-1K,1%,1/16W,CHIP,A",1K,1%,R0402,13178.31,638.00,270.000,NO
R1751,"Q_RES_0402LF-33.2,1%,1/16W,CHIA",33.2,1%,R0402,6330.00,4068.62,0.000,NO
R1752,"Q_RES_0402LF-33.2,1%,1/16W,CHIA",33.2,1%,R0402,6220.00,898.62,90.000,NO
R1753,"Q_RES_0402LF-33.2,1%,1/16W,CHIA",33.2,1%,R0402,6482.20,4628.62,0.000,NO
R1754,"Q_RES_0402LF-33.2,1%,1/16W,CHIA",33.2,1%,R0402,6345.00,3928.62,0.000,NO
R1755,"Q_RES_0402LF-33.2,1%,1/16W,CHIA",33.2,1%,R0402,6480.00,4068.62,0.000,NO
R1756,"Q_RES_0402LF-33.2,1%,1/16W,CHIA",33.2,1%,R0402,6480.00,4023.62,0.000,NO
R1757,"Q_RES_0402LF-33.2,1%,1/16W,CHIA",33.2,1%,R0402,6182.20,4628.62,180.000,YES
R1758,"Q_RES_0402LF-33.2,1%,1/16W,CHIA",33.2,1%,R0402,6475.00,3928.62,0.000,NO
R1763,"Q_RES_0402LF-10K,1%,1/16W,EMPTA",10K,1%,R0402,6825.88,888.37,90.000,YES
R1764,"Q_RES_0402LF-1K,1%,1/16W,EMPTYA",1K,1%,R0402,6865.88,888.37,270.000,YES
R1765,"Q_RES_0805LF-0,5%,1/8W,EMPTY,CA",0,5%,R0805,12688.47,540.22,180.000,NO
R1785,"Q_RES_0402LF-4.7K,1%,1/16W,CHIA",4.7K,1%,R0402,1738.96,4213.83,0.000,NO
R1791,"Q_RES_0402LF-9.09K,1%,1/16W,CHA",9.09K,1%,R0402,1738.96,4308.83,0.000,NO
R1792,"Q_RES_0402LF-0,5%,1/16W,EMPTY,A",0,5%,R0402,898.01,4465.19,180.000,NO
R1793,"Q_RES_0402LF-0,5%,1/16W,EMPTY,A",0,5%,R0402,1491.74,4818.13,270.000,NO
R1798,"Q_RES_0402LF-0,5%,1/16W,CHIP,CA",0,5%,R0402,5547.20,368.62,270.000,YES
R1799,"Q_RES_0402LF-7.87K,1%,1/16W,CHA",7.87K,1%,R0402,1833.96,4433.83,180.000,NO
R1800,"Q_RES_0402LF-1.21K,1%,1/16W,CHA",1.21K,1%,R0402,1738.96,4433.83,0.000,NO
R1801,"Q_RES_0402LF-0,5%,1/16W,CHIP,CA",0,5%,R0402,7490.20,745.62,180.000,YES
R1809,"Q_RES_0402LF-20K,1%,1/16W,CHIPA",20K,1%,R0402,12687.54,967.68,0.000,NO
R1810,"Q_RES_0402LF-1K,1%,1/16W,EMPTYA",1K,1%,R0402,12687.54,927.24,180.000,NO
R1811,"Q_RES_0402LF-33.2,1%,1/16W,CHIA",33.2,1%,R0402,7763.40,4598.62,180.000,NO
R1812,"Q_RES_0402LF-33.2,1%,1/16W,CHIA",33.2,1%,R0402,7613.40,4548.62,180.000,NO
R1813,"Q_RES_0402LF-10K,1%,1/16W,EMPTA",10K,1%,R0402,4908.36,3053.98,0.000,NO
R1814,"Q_RES_0402LF-1K,1%,1/16W,EMPTYA",1K,1%,R0402,4908.36,3093.98,180.000,NO
R1815,"Q_RES_0402LF-0,5%,1/16W,CHIP,CA",0,5%,R0402,5631.00,541.82,90.000,YES
R1816,"Q_RES_0402LF-0,5%,1/16W,CHIP,CA",0,5%,R0402,5715.80,541.82,90.000,YES
R1820,"Q_RES_0402LF-10K,1%,1/16W,CHIPA",10K,1%,R0402,12495.93,2053.62,0.000,NO
R1821,"Q_RES_0402LF-0,5%,1/16W,CHIP,CA",0,5%,R0402,11454.67,5905.22,270.000,YES
R1822,"Q_RES_0402LF-10K,1%,1/16W,CHIPA",10K,1%,R0402,4383.18,5427.33,0.000,NO
R1823,"Q_RES_0402LF-1K,1%,1/16W,CHIP,A",1K,1%,R0402,7622.20,4132.12,180.000,NO
R1824,"Q_RES_0402LF-10K,1%,1/16W,CHIPA",10K,1%,R0402,18117.50,1798.97,0.000,NO
R1827,"Q_RES_0402LF-33.2,1%,1/16W,CHIA",33.2,1%,R0402,13702.52,811.11,0.000,NO
R1828,"Q_RES_0402LF-10K,1%,1/16W,CHIPA",10K,1%,R0402,13663.69,880.70,90.000,NO
R1831,"Q_RES_0402LF-0,5%,1/16W,EMPTY,A",0,5%,R0402,14981.84,3656.98,90.000,NO
R1832,"Q_RES_0402LF-0,5%,1/16W,EMPTY,A",0,5%,R0402,14567.77,4225.71,90.000,NO
R1833,"Q_RES_0402LF-0,5%,1/16W,EMPTY,A",0,5%,R0402,7452.20,4998.62,90.000,NO
R1837,"Q_RES_4P_12-0.001,1%,3W,SMLF,CA",,,R2512_4P_H41,844.30,13224.61,270.000,NO
R1838,"Q_RES_4P_12-0.001,1%,3W,SMLF,CA",,,R2512_4P_H41,17690.97,13207.11,270.000,NO
R1839,"Q_RES_0402LF-0,5%,1/16W,EMPTY,A",0,5%,R0402,8004.98,4000.26,270.000,NO
R1840,"Q_RES_0402LF-0,5%,1/16W,EMPTY,A",0,5%,R0402,8004.98,4146.26,270.000,NO
R1841,"Q_RES_0402LF-10K,1%,1/16W,CHIPA",10K,1%,R0402,7897.20,4268.62,90.000,NO
R1843,"Q_RES_0402LF-33.2,1%,1/16W,CHIA",33.2,1%,R0402,7772.20,4032.12,0.000,NO
R1844,"Q_RES_0402LF-33.2,1%,1/16W,CHIA",33.2,1%,R0402,7772.20,4082.12,0.000,NO
R1853,"Q_RES_0402LF-0,5%,1/16W,CHIP,CA",0,5%,R0402,6482.20,4213.62,0.000,YES
R1854,"Q_RES_0402LF-10K,1%,1/16W,CHIPA",10K,1%,R0402,7472.45,1378.64,180.000,NO
R1856,"Q_RES_0402LF-100,1%,1/16W,CHIPA",100,1%,R0402,7472.35,1420.50,0.000,NO
R1857,"Q_RES_0402LF-10K,1%,1/16W,CHIPA",10K,1%,R0402,7763.03,1537.28,0.000,NO
R1868,"Q_RES_0402LF-10,1%,1/16W,CHIP,A",10,1%,R0402,13149.06,1021.89,270.000,NO
R1869,"Q_RES_0402LF-10,1%,1/16W,CHIP,A",10,1%,R0402,13109.06,1021.89,270.000,NO
R1870,"Q_RES_0402LF-10,1%,1/16W,CHIP,A",10,1%,R0402,13189.06,1021.83,270.000,NO
R1871,"Q_RES_0402LF-10,1%,1/16W,CHIP,A",10,1%,R0402,12957.67,937.16,270.000,NO
R1872,"Q_RES_0402LF-10,1%,1/16W,CHIP,A",10,1%,R0402,12984.07,1064.67,270.000,NO
R1895,"Q_RES_0402LF-100,1%,1/16W,CHIPA",100,1%,R0402,17131.73,327.44,270.000,YES
R1896,"Q_RES_0402LF-100,1%,1/16W,CHIPA",100,1%,R0402,17030.00,948.62,270.000,YES
R1897,"Q_RES_0402LF-100,1%,1/16W,CHIPA",100,1%,R0402,17080.00,948.62,270.000,YES
R1898,"Q_RES_0402LF-100,1%,1/16W,CHIPA",100,1%,R0402,16990.00,948.62,270.000,YES
R1905,"Q_RES_0402LF-1K,1%,1/16W,CHIP,A",1K,1%,R0402,17862.99,4254.32,0.000,NO
R1906,"Q_RES_0402LF-1K,1%,1/16W,CHIP,A",1K,1%,R0402,17862.99,4104.32,0.000,NO
R1907,"Q_RES_0402LF-1K,1%,1/16W,CHIP,A",1K,1%,R0402,17862.99,4189.32,0.000,NO
R1908,"Q_RES_0402LF-1K,1%,1/16W,CHIP,A",1K,1%,R0402,17862.99,4039.32,0.000,NO
R1919,"Q_RES_0402LF-33.2,1%,1/16W,CHIA",33.2,1%,R0402,6482.20,4578.62,180.000,YES
R1921,"Q_RES_0402LF-33.2,1%,1/16W,CHIA",33.2,1%,R0402,17715.51,4701.93,180.000,NO
R1929,"Q_RES_0402LF-10K,1%,1/16W,CHIPA",10K,1%,R0402,17118.32,772.21,270.000,NO
R1930,"Q_RES_0402LF-10K,1%,1/16W,CHIPA",10K,1%,R0402,17917.06,515.40,90.000,YES
R1932,"Q_RES_0402LF-33.2,1%,1/16W,CHIA",33.2,1%,R0402,7122.20,12971.62,180.000,YES
R1933,"Q_RES_0402LF-33.2,1%,1/16W,CHIA",33.2,1%,R0402,7122.20,13011.62,180.000,YES
R1934,"Q_RES_0402LF-33.2,1%,1/16W,CHIA",33.2,1%,R0402,7032.20,12971.62,0.000,YES
R1935,"Q_RES_0402LF-33.2,1%,1/16W,CHIA",33.2,1%,R0402,7032.20,13011.62,0.000,YES
R1944,"Q_RES_0402LF-0,5%,1/16W,CHIP,CA",0,5%,R0402,12320.10,1924.82,180.000,YES
R1950,"Q_RES_0402LF-0,5%,1/16W,CHIP,CA",0,5%,R0402,8257.70,5110.82,180.000,NO
R1955,"Q_RES_0402LF-10K,1%,1/16W,CHIPA",10K,1%,R0402,12185.79,1729.45,180.000,NO
R1958,"Q_RES_0402LF-10K,1%,1/16W,CHIPA",10K,1%,R0402,9678.00,4020.17,180.000,YES
R1959,"Q_RES_0402LF-0,5%,1/16W,CHIP,CA",0,5%,R0402,15820.17,9092.45,90.000,YES
R1960,"Q_RES_0402LF-0,5%,1/16W,CHIP,CA",0,5%,R0402,12842.73,1903.87,0.000,YES
R1961,"Q_RES_0402LF-10K,1%,1/16W,CHIPA",10K,1%,R0402,13229.06,1057.33,270.000,NO
R1962,"Q_RES_0402LF-20K,1%,1/16W,EMPTA",20K,1%,R0402,13575.62,1282.85,180.000,YES
R1995,"Q_RES_0402LF-33.2,1%,1/16W,CHIA",33.2,1%,R0402,12645.93,1424.62,45.000,YES
R1996,"Q_RES_0402LF-33.2,1%,1/16W,CHIA",33.2,1%,R0402,12763.45,1011.30,90.000,YES
R2071,"Q_RES_0402LF-0,5%,1/16W,EMPTY,A",0,5%,R0402,6192.20,4263.62,180.000,NO
R2113,"Q_RES_0402LF-33.2,1%,1/16W,CHIA",33.2,1%,R0402,5607.20,1613.62,0.000,NO
R2114,"Q_RES_0402LF-0,5%,1/16W,CHIP,CA",0,5%,R0402,6285.64,2492.02,0.000,NO
R2121,"Q_RES_0402LF-4.7K,5%,1/16W,CHIA",4.7K,5%,R0402,5512.20,1613.62,180.000,NO
R2125,"Q_RES_0402LF-4.7K,5%,1/16W,CHIA",4.7K,5%,R0402,6411.34,2492.02,180.000,NO
R2132,"Q_RES_0402LF-0,5%,1/16W,EMPTY,A",0,5%,R0402,13097.90,638.00,270.000,NO
R2133,"Q_RES_0402LF-1K,1%,1/16W,CHIP,A",1K,1%,R0402,17132.80,1703.26,180.000,NO
R2134,"Q_RES_0402LF-10K,1%,1/16W,CHIPA",10K,1%,R0402,17132.17,1749.70,0.000,NO
R2155,"Q_RES_0402LF-0,5%,1/16W,CHIP,CA",0,5%,R0402,7613.40,4798.62,0.000,NO
R2204,"Q_RES_0402LF-2.2K,5%,1/16W,EMPA",2.2K,5%,R0402,6182.50,346.52,180.000,YES
R2205,"Q_RES_0402LF-2.2K,5%,1/16W,EMPA",2.2K,5%,R0402,6490.47,351.10,270.000,YES
R2208,"Q_RES_0402LF-0,5%,1/16W,CHIP,CA",0,5%,R0402,6391.45,2982.97,0.000,NO
R2209,"Q_RES_0402LF-0,5%,1/16W,CHIP,CA",0,5%,R0402,6391.45,3022.47,0.000,NO
R2210,"Q_RES_0402LF-0,5%,1/16W,CHIP,CA",0,5%,R0402,6391.45,3109.62,0.000,NO
R2211,"Q_RES_0402LF-0,5%,1/16W,CHIP,CA",0,5%,R0402,6391.45,3155.87,0.000,NO
R2212,"Q_RES_0402LF-2.2K,5%,1/16W,EMPA",2.2K,5%,R0402,5972.20,898.62,270.000,YES
R2213,"Q_RES_0402LF-2.2K,5%,1/16W,EMPA",2.2K,5%,R0402,5922.20,898.62,270.000,YES
R2219,"Q_RES_0402LF-26.7K,1%,1/16W,CHA",26.7K,1%,R0402,8289.78,3890.12,0.000,NO
R2221,"Q_RES_0402LF-26.7K,1%,1/16W,CHA",26.7K,1%,R0402,8664.86,3864.76,180.000,NO
R2222,"Q_RES_0402LF-1K,1%,1/16W,CHIP,A",1K,1%,R0402,8664.86,3824.15,0.000,NO
R2227,"Q_RES_0402LF-1K,1%,1/16W,CHIP,A",1K,1%,R0402,8290.00,3844.00,0.000,NO
R2230,"Q_RES_0402LF-10K,1%,1/16W,CHIPA",10K,1%,R0402,8664.86,4025.81,180.000,NO
R2232,"Q_RES_0402LF-10K,1%,1/16W,EMPTA",10K,1%,R0402,11772.45,2021.74,0.000,NO
R2233,"Q_RES_0402LF-10K,1%,1/16W,CHIPA",10K,1%,R0402,8289.78,3972.76,0.000,NO
R2234,"Q_RES_0402LF-10K,1%,1/16W,EMPTA",10K,1%,R0402,12591.50,3015.16,270.000,NO
R2235,"Q_RES_0402LF-1K,1%,1/16W,CHIP,A",1K,1%,R0402,12631.50,3015.16,90.000,NO
R2236,"Q_RES_0402LF-100K,1%,1/16W,EMPA",100K,1%,R0402,8665.38,4142.76,180.000,NO
R2238,"Q_RES_0402LF-4.99K,1%,1/16W,EMA",4.99K,1%,R0402,8665.38,4188.36,0.000,NO
R2240,"Q_RES_0402LF-10K,1%,1/16W,EMPTA",10K,1%,R0402,11772.45,1981.74,0.000,NO
R2241,"Q_RES_0402LF-1K,1%,1/16W,CHIP,A",1K,1%,R0402,11772.45,1941.74,180.000,NO
R2242,"Q_RES_0402LF-10K,1%,1/16W,EMPTA",10K,1%,R0402,12551.50,3015.16,270.000,NO
R2243,"Q_RES_0402LF-1K,1%,1/16W,CHIP,A",1K,1%,R0402,12511.50,3015.16,90.000,NO
R2244,"Q_RES_0402LF-10K,1%,1/16W,CHIPA",10K,1%,R0402,7613.40,4698.62,180.000,YES
R2252,"Q_RES_0402LF-100K,1%,1/16W,EMPA",100K,1%,R0402,11989.75,2406.72,180.000,NO
R2253,"Q_RES_0402LF-4.75K,1%,1/16W,CHA",4.75K,1%,R0402,11989.75,2365.92,0.000,NO
R2255,"Q_RES_0402LF-0,5%,1/16W,CHIP,CA",0,5%,R0402,11989.75,2446.92,180.000,NO
R2256,"Q_RES_0402LF-0,5%,1/16W,EMPTY,A",0,5%,R0402,7366.01,764.48,270.000,YES
R2257,"Q_RES_0402LF-0,5%,1/16W,EMPTY,A",0,5%,R0402,7325.01,764.48,270.000,YES
R2268,"Q_RES_0402LF-0,5%,1/16W,CHIP,CA",0,5%,R0402,4468.28,5374.83,0.000,NO
R2282,"Q_RES_0402LF-10K,1%,1/16W,CHIPA",10K,1%,R0402,5560.64,2532.02,0.000,NO
R2287,"Q_RES_0402LF-10K,1%,1/16W,CHIPA",10K,1%,R0402,8827.25,1874.49,0.000,NO
R2296,"Q_RES_0402LF-1K,1%,1/16W,CHIP,A",1K,1%,R0402,9299.25,2016.12,0.000,YES
R2304,"Q_RES_0402LF-10K,1%,1/16W,CHIPA",10K,1%,R0402,5380.64,2694.72,180.000,NO
R2308,"Q_RES_0402LF-10K,1%,1/16W,EMPTA",10K,1%,R0402,6088.95,2766.30,90.000,NO
R2309,"Q_RES_0402LF-1K,1%,1/16W,CHIP,A",1K,1%,R0402,6047.25,2766.30,270.000,NO
R2310,"Q_RES_0402LF-10K,1%,1/16W,EMPTA",10K,1%,R0402,6140.95,2766.30,90.000,NO
R2311,"Q_RES_0402LF-1K,1%,1/16W,CHIP,A",1K,1%,R0402,6181.15,2766.30,270.000,NO
R2312,"Q_RES_0402LF-10K,1%,1/16W,CHIPA",10K,1%,R0402,5865.45,2966.57,0.000,NO
R2313,"Q_RES_0402LF-0,5%,1/16W,CHIP,CA",0,5%,R0402,6391.45,2902.67,180.000,NO
R2315,"Q_RES_0402LF-10K,1%,1/16W,CHIPA",10K,1%,R0402,6391.45,2943.27,180.000,NO
R2316,"Q_RES_0402LF-0,5%,1/16W,CHIP,CA",0,5%,R0402,18167.14,15042.41,0.000,NO
R2317,"Q_RES_0402LF-10K,1%,1/16W,CHIPA",10K,1%,R0402,9449.15,1849.12,180.000,NO
R2322,"Q_RES_0402LF-49.9,1%,1/16W,EMPA",49.9,1%,R0402,17023.20,5379.72,90.000,NO
R2330,"Q_RES_0402LF-0,5%,1/16W,EMPTY,A",0,5%,R0402,8665.38,4068.12,0.000,NO
R2332,"Q_RES_0402LF-2K,1%,1/16W,CHIP,A",2K,1%,R0402,14594.31,13973.95,90.000,YES
R2338,"Q_RES_0402LF-10K,1%,1/16W,EMPTA",10K,1%,R0402,17100.57,6974.65,270.000,YES
R2339,"Q_RES_0402LF-22,5%,1/16W,CHIP,A",22,5%,R0402,8242.20,4268.62,90.000,NO
R2342,"Q_RES_0402LF-10K,1%,1/16W,CHIPA",10K,1%,R0402,13641.62,1282.85,180.000,YES
R2343,"Q_RES_0402LF-10K,1%,1/16W,EMPTA",10K,1%,R0402,6014.30,4586.88,0.000,NO
R2344,"Q_RES_0402LF-4.7K,5%,1/16W,CHIA",4.7K,5%,R0402,6012.20,4823.62,0.000,NO
R2345,"Q_RES_0402LF-49.9,1%,1/16W,EMPA",49.9,1%,R0402,1556.18,5110.95,180.000,YES
R2346,"Q_RES_0402LF-4.7K,5%,1/16W,CHIA",4.7K,5%,R0402,6482.20,4528.62,0.000,NO
R2347,"Q_RES_0402LF-0,5%,1/16W,CHIP,CA",0,5%,R0402,7772.20,4182.12,0.000,YES
R2348,"Q_RES_0402LF-0,5%,1/16W,CHIP,CA",0,5%,R0402,13641.62,1241.23,180.000,YES
R2350,"Q_RES_0402LF-0,5%,1/16W,CHIP,CA",0,5%,R0402,5560.64,2572.02,0.000,NO
R2354,"Q_RES_0402LF-100,1%,1/16W,EMPTA",100,1%,R0402,1543.08,5192.81,180.000,NO
R2355,"Q_RES_0402LF-4.7K,5%,1/16W,EMPA",4.7K,5%,R0402,5680.89,3108.47,180.000,NO
R2356,"Q_RES_0402LF-10K,1%,1/16W,CHIPA",10K,1%,R0402,18113.22,15104.37,180.000,YES
R2357,"Q_RES_0402LF-10K,1%,1/16W,CHIPA",10K,1%,R0402,10137.20,3093.62,90.000,YES
R2358,"Q_RES_0402LF-0,5%,1/16W,CHIP,CA",0,5%,R0402,15104.37,3153.25,90.000,YES
R2359,"Q_RES_0402LF-10K,1%,1/16W,CHIPA",10K,1%,R0402,15182.58,2889.56,180.000,NO
R2360,"Q_RES_0402LF-0,5%,1/16W,CHIP,CA",0,5%,R0402,15182.58,2849.56,0.000,NO
R2362,"Q_RES_0402LF-33.2,1%,1/16W,CHIA",33.2,1%,R0402,15820.17,8945.83,90.000,YES
R2363,"Q_RES_0402LF-10,1%,1/16W,CHIP,A",10,1%,R0402,13087.92,928.01,270.000,NO
R2365,"Q_RES_0402LF-1K,1%,1/16W,CHIP,A",1K,1%,R0402,13810.66,14210.03,270.000,NO
R2366,"Q_RES_0402LF-0,5%,1/16W,CHIP,CA",0,5%,R0402,13770.75,14209.81,270.000,NO
R2367,"Q_RES_0402LF-10K,1%,1/16W,EMPTA",10K,1%,R0402,4794.23,14023.64,180.000,YES
R2368,"Q_RES_0402LF-150,1%,1/16W,CHIPA",150,1%,R0402,13810.40,14077.27,0.000,NO
R2369,"Q_RES_0402LF-0,5%,1/16W,CHIP,CA",0,5%,R0402,13810.45,14042.07,0.000,NO
R2370,"Q_RES_0402LF-0,5%,1/16W,CHIP,CA",0,5%,R0402,13810.45,14006.84,0.000,NO
R2371,"Q_RES_0402LF-33.2,1%,1/16W,CHIA",33.2,1%,R0402,5520.00,14583.62,90.000,NO
R2372,"Q_RES_0402LF-33.2,1%,1/16W,CHIA",33.2,1%,R0402,13857.20,14318.62,270.000,NO
R2373,"Q_RES_0402LF-1K,1%,1/16W,CHIP,A",1K,1%,R0402,13829.45,14137.92,180.000,YES
R2374,"Q_RES_0402LF-2K,1%,1/16W,CHIP,A",2K,1%,R0402,4809.36,13944.47,0.000,YES
R2375,"Q_RES_0402LF-1K,1%,1/16W,CHIP,A",1K,1%,R0402,13724.66,14130.19,0.000,NO
R2376,"Q_RES_0402LF-0,5%,1/16W,CHIP,CA",0,5%,R0402,13716.26,14173.74,0.000,NO
R2377,"Q_RES_0402LF-1K,1%,1/16W,CHIP,A",1K,1%,R0402,13710.50,14127.91,180.000,YES
R2379,"Q_RES_0402LF-0,5%,1/16W,CHIP,CA",0,5%,R0402,13710.50,14164.91,180.000,YES
R2380,"Q_RES_0402LF-0,5%,1/16W,CHIP,CA",0,5%,R0402,4698.16,13966.06,180.000,NO
R2381,"Q_RES_0402LF-49.9,1%,1/16W,CHIA",49.9,1%,R0402,13716.16,14074.58,180.000,NO
R2382,"Q_RES_0402LF-49.9,1%,1/16W,EMPA",49.9,1%,R0402,13716.73,13990.53,180.000,NO
R2383,"Q_RES_0402LF-1K,1%,1/16W,CHIP,A",1K,1%,R0402,16952.76,5215.07,0.000,YES
R2384,"Q_RES_0402LF-10K,1%,1/16W,EMPTA",10K,1%,R0402,732.81,6946.11,90.000,YES
R2385,"Q_RES_0402LF-2K,1%,1/16W,CHIP,A",2K,1%,R0402,771.21,6945.81,270.000,YES
R2386,"Q_RES_0402LF-100,1%,1/16W,EMPTA",100,1%,R0402,17039.60,5455.03,270.000,NO
R2387,"Q_RES_0402LF-0,5%,1/16W,CHIP,CA",0,5%,R0402,958.76,6922.03,90.000,YES
R2388,"Q_RES_0402LF-0,5%,1/16W,CHIP,CA",0,5%,R0402,16952.76,5415.07,180.000,NO
R2389,"Q_RES_0402LF-0,5%,1/16W,CHIP,CA",0,5%,R0402,16952.76,5455.07,180.000,NO
R2390,"Q_RES_0402LF-0,5%,1/16W,CHIP,CA",0,5%,R0402,16952.76,5181.07,180.000,NO
R2391,"Q_RES_0402LF-0,5%,1/16W,CHIP,CA",0,5%,R0402,16952.76,5131.07,180.000,NO
R2392,"Q_RES_0402LF-1K,1%,1/16W,CHIP,A",1K,1%,R0402,16562.29,5446.22,0.000,NO
R2393,"Q_RES_0402LF-1K,1%,1/16W,CHIP,A",1K,1%,R0402,16952.76,5335.07,0.000,YES
R2394,"Q_RES_0402LF-0,5%,1/16W,CHIP,CA",0,5%,R0402,16952.76,5535.27,180.000,NO
R2396,"Q_RES_0402LF-1K,1%,1/16W,CHIP,A",1K,1%,R0402,16952.76,5415.07,0.000,YES
R2397,"Q_RES_0402LF-0,5%,1/16W,CHIP,CA",0,5%,R0402,16952.76,5455.07,0.000,YES
R2398,"Q_RES_0402LF-1K,1%,1/16W,EMPTYA",1K,1%,R0402,17060.35,5316.13,180.000,NO
R2399,"Q_RES_0402LF-150,1%,1/16W,CHIPA",150,1%,R0402,17214.29,4868.69,180.000,NO
R2400,"Q_RES_0402LF-0,5%,1/16W,CHIP,CA",0,5%,R0402,17214.29,4908.69,180.000,NO
R2401,"Q_RES_0402LF-0,5%,1/16W,CHIP,CA",0,5%,R0402,17214.29,4948.69,180.000,NO
R2402,"Q_RES_0402LF-0,5%,1/16W,CHIP,CA",0,5%,R0402,17139.77,4668.04,90.000,NO
R2403,"Q_RES_0402LF-0,5%,1/16W,CHIP,CA",0,5%,R0402,17089.77,4668.04,90.000,NO
R2404,"Q_RES_0402LF-1K,1%,1/16W,CHIP,A",1K,1%,R0402,17293.79,4806.69,180.000,NO
R2405,"Q_RES_0402LF-0,5%,1/16W,CHIP,CA",0,5%,R0402,17214.29,4788.69,0.000,NO
R2406,"Q_RES_0402LF-10K,1%,1/16W,EMPTA",10K,1%,R0402,14557.34,13973.95,270.000,YES
R2407,"Q_RES_0402LF-10K,1%,1/16W,CHIPA",10K,1%,R0402,14556.07,14003.85,0.000,NO
R2408,"Q_RES_0402LF-0,5%,1/16W,CHIP,CA",0,5%,R0402,14434.56,13962.69,180.000,NO
R2409,"Q_RES_0402LF-10K,1%,1/16W,CHIPA",10K,1%,R0402,17136.06,7124.37,90.000,YES
R2410,"Q_RES_0402LF-33.2,1%,1/16W,CHIA",33.2,1%,R0402,5722.20,2213.62,180.000,NO
R2411,"Q_RES_0402LF-33.2,1%,1/16W,CHIA",33.2,1%,R0402,5722.20,2253.62,180.000,NO
R2412,"Q_RES_0402LF-0,5%,1/16W,CHIP,CA",0,5%,R0402,12630.40,1051.22,270.000,NO
R2413,"Q_RES_0402LF-0,5%,1/16W,CHIP,CA",0,5%,R0402,6200.97,541.82,90.000,YES
R2414,"Q_RES_0402LF-0,5%,1/16W,CHIP,CA",0,5%,R0402,6109.70,541.92,90.000,YES
R2415,"Q_RES_0402LF-0,5%,1/16W,CHIP,CA",0,5%,R0402,6063.30,541.82,90.000,YES
R2416,"Q_RES_0402LF-0,5%,1/16W,CHIP,CA",0,5%,R0402,6023.50,541.82,90.000,YES
R2417,"Q_RES_0402LF-33.2,1%,1/16W,CHIA",33.2,1%,R0402,5984.05,541.82,90.000,YES
R2418,"Q_RES_0402LF-33.2,1%,1/16W,CHIA",33.2,1%,R0402,5940.97,541.82,90.000,YES
R2419,"Q_RES_0402LF-33.2,1%,1/16W,CHIA",33.2,1%,R0402,7159.90,736.62,90.000,YES
R2420,"Q_RES_0402LF-33.2,1%,1/16W,CHIA",33.2,1%,R0402,7120.00,736.62,90.000,YES
R2421,"Q_RES_0402LF-33.2,1%,1/16W,CHIA",33.2,1%,R0402,7118.67,542.22,90.000,YES
R2422,"Q_RES_0402LF-33.2,1%,1/16W,CHIA",33.2,1%,R0402,7075.97,541.82,90.000,YES
R2423,"Q_RES_0402LF-33.2,1%,1/16W,CHIA",33.2,1%,R0402,6985.97,541.82,90.000,YES
R2424,"Q_RES_0402LF-33.2,1%,1/16W,CHIA",33.2,1%,R0402,6944.00,541.82,90.000,YES
R2425,"Q_RES_0402LF-33.2,1%,1/16W,CHIA",33.2,1%,R0402,6819.80,541.82,90.000,YES
R2426,"Q_RES_0402LF-100,1%,1/16W,EMPTA",100,1%,R0402,8827.25,1920.55,180.000,NO
R2449,"Q_RES_0402LF-33.2,1%,1/16W,CHIA",33.2,1%,R0402,1452.13,4818.13,90.000,NO
R2450,"Q_RES_0402LF-33.2,1%,1/16W,CHIA",33.2,1%,R0402,1200.60,4818.13,90.000,NO
R2451,"Q_RES_0402LF-10K,1%,1/16W,EMPTA",10K,1%,R0402,13040.34,685.62,180.000,NO
R2452,"Q_RES_0402LF-0,5%,1/16W,CHIP,CA",0,5%,R0402,13040.34,645.72,0.000,NO
R2453,"Q_RES_0402LF-33.2,1%,1/16W,CHIA",33.2,1%,R0402,1353.17,4818.13,270.000,NO
R2454,"Q_RES_0402LF-33.2,1%,1/16W,CHIA",33.2,1%,R0402,1303.17,4818.13,270.000,NO
R2455,"Q_RES_0402LF-33.2,1%,1/16W,CHIA",33.2,1%,R0402,3979.18,14275.69,0.000,NO
R2456,"Q_RES_0402LF-33.2,1%,1/16W,CHIA",33.2,1%,R0402,3979.18,14325.71,0.000,NO
R2457,"Q_RES_0402LF-100K,1%,1/16W,CHIA",100K,1%,R0402,5880.64,2522.02,0.000,NO
R2473,"Q_RES_0402LF-49.9,1%,1/16W,CHIA",49.9,1%,R0402,18246.69,3839.52,0.000,NO
R2474,"Q_RES_0402LF-0,5%,1/16W,EMPTY,A",0,5%,R0402,18246.69,3795.52,0.000,NO
R2476,"Q_RES_0402LF-200K,1%,1/16W,EMPA",200K,1%,R0402,6387.20,2303.62,0.000,NO
R2477,"Q_RES_0402LF-33.2,1%,1/16W,CHIA",33.2,1%,R0402,14588.18,7259.88,90.000,YES
R2478,"Q_RES_0402LF-33.2,1%,1/16W,CHIA",33.2,1%,R0402,14450.18,7259.88,90.000,YES
R2479,"Q_RES_0402LF-33.2,1%,1/16W,CHIA",33.2,1%,R0402,498.68,7268.74,0.000,YES
R2480,"Q_RES_0402LF-33.2,1%,1/16W,CHIA",33.2,1%,R0402,498.68,7223.74,0.000,YES
R2481,"Q_RES_0402LF-4.75K,1%,1/16W,EMA",4.75K,1%,R0402,9678.56,3981.38,180.000,YES
R2486,"Q_RES_0402LF-10K,1%,1/16W,CHIPA",10K,1%,R0402,6347.20,5263.62,180.000,NO
R2487,"Q_RES_0402LF-4.7K,1%,1/16W,EMPA",4.7K,1%,R0402,12057.61,571.30,0.000,NO
R2488,"Q_RES_0402LF-4.7K,1%,1/16W,CHIA",4.7K,1%,R0402,18444.60,1721.87,180.000,NO
R2489,"Q_RES_0402LF-33.2,1%,1/16W,CHIA",33.2,1%,R0402,12057.61,610.60,180.000,NO
R2490,"Q_RES_0402LF-1K,1%,1/16W,CHIP,A",1K,1%,R0402,12306.81,12482.90,90.000,YES
R2491,"Q_RES_0402LF-1K,1%,1/16W,CHIP,A",1K,1%,R0402,11184.07,12534.49,180.000,YES
R2492,"Q_RES_0402LF-1K,1%,1/16W,CHIP,A",1K,1%,R0402,17058.03,12484.37,90.000,YES
R2493,"Q_RES_0402LF-1K,1%,1/16W,CHIP,A",1K,1%,R0402,17952.89,12530.19,180.000,YES
R2494,"Q_RES_0402LF-1K,1%,1/16W,CHIP,A",1K,1%,R0402,2558.67,12515.64,180.000,YES
R2495,"Q_RES_0402LF-1K,1%,1/16W,CHIP,A",1K,1%,R0402,1422.40,12579.52,180.000,YES
R2496,"Q_RES_0402LF-1K,1%,1/16W,CHIP,A",1K,1%,R0402,7305.32,12496.25,180.000,YES
R2497,"Q_RES_0402LF-1K,1%,1/16W,CHIP,A",1K,1%,R0402,8497.67,12482.90,90.000,YES
R2498,"Q_RES_0402LF-33.2,1%,1/16W,CHIA",33.2,1%,R0402,12237.93,12383.86,90.000,YES
R2499,"Q_RES_0402LF-33.2,1%,1/16W,CHIA",33.2,1%,R0402,11353.39,12356.96,90.000,YES
R2500,"Q_RES_0402LF-33.2,1%,1/16W,CHIA",33.2,1%,R0402,17050.29,12278.10,90.000,YES
R2501,"Q_RES_0402LF-33.2,1%,1/16W,CHIA",33.2,1%,R0402,17974.17,12393.90,90.000,YES
R2502,"Q_RES_0402LF-33.2,1%,1/16W,CHIA",33.2,1%,R0402,2746.93,12534.86,90.000,YES
R2503,"Q_RES_0402LF-33.2,1%,1/16W,CHIA",33.2,1%,R0402,1591.97,12356.96,90.000,YES
R2504,"Q_RES_0402LF-33.2,1%,1/16W,CHIA",33.2,1%,R0402,7310.69,12322.16,90.000,YES
R2505,"Q_RES_0402LF-33.2,1%,1/16W,CHIA",33.2,1%,R0402,8406.51,12383.86,90.000,YES
R2506,"Q_RES_0402LF-1K,1%,1/16W,CHIP,A",1K,1%,R0402,4815.00,2953.62,90.000,NO
R2507,"Q_RES_0402LF-1K,1%,1/16W,CHIP,A",1K,1%,R0402,5070.00,2888.62,0.000,NO
R2508,"Q_RES_0402LF-10K,1%,1/16W,EMPTA",10K,1%,R0402,14662.20,1698.62,0.000,YES
R2509,"Q_RES_0402LF-1K,1%,1/16W,EMPTYA",1K,1%,R0402,14547.20,1698.62,180.000,YES
R2510,"Q_RES_0402LF-10K,1%,1/16W,EMPTA",10K,1%,R0402,14547.20,1453.62,0.000,YES
R2511,"Q_RES_0402LF-1K,1%,1/16W,EMPTYA",1K,1%,R0402,14662.20,1453.62,180.000,YES
R2512,"Q_RES_0402LF-49.9,1%,1/16W,CHIA",49.9,1%,R0402,14863.80,4319.72,0.000,NO
R2513,"Q_RES_0402LF-0,5%,1/16W,CHIP,CA",0,5%,R0402,14973.84,4152.88,90.000,NO
R2514,"Q_RES_0402LF-1K,1%,1/16W,EMPTYA",1K,1%,R0402,14457.77,3659.96,270.000,NO
R2520,"Q_RES_0402LF-0,5%,1/16W,CHIP,CA",0,5%,R0402,4067.18,14275.69,0.000,NO
R2521,"Q_RES_0402LF-0,5%,1/16W,CHIP,CA",0,5%,R0402,4067.18,14325.71,0.000,NO
R2522,"Q_RES_0402LF-1K,1%,1/16W,CHIP,A",1K,1%,R0402,4049.04,14184.92,180.000,YES
R2523,"Q_RES_0402LF-0,5%,1/16W,CHIP,CA",0,5%,R0402,4065.20,14136.62,180.000,YES
R2524,"Q_RES_0402LF-1K,1%,1/16W,CHIP,A",1K,1%,R0402,4553.80,14012.82,0.000,YES
R2525,"Q_RES_0402LF-1K,1%,1/16W,CHIP,A",1K,1%,R0402,3963.25,14136.19,0.000,NO
R2526,"Q_RES_0402LF-0,5%,1/16W,CHIP,CA",0,5%,R0402,7117.20,1618.62,0.000,NO
R2528,"Q_RES_0402LF-100K,1%,1/16W,CHIA",100K,1%,R0402,7834.50,5184.82,270.000,NO
R2529,"Q_RES_0402LF-0,5%,1/16W,CHIP,CA",0,5%,R0402,7875.20,5184.82,90.000,NO
R2530,"Q_RES_0402LF-4.7K,5%,1/16W,CHIA",4.7K,5%,R0402,8128.10,5183.82,90.000,NO
R2531,"Q_RES_0402LF-0,5%,1/16W,CHIP,CA",0,5%,R0402,8166.70,5039.22,90.000,NO
R2550,"Q_RES_0402LF-0,5%,1/16W,CHIP,CA",0,5%,R0402,4048.31,13970.38,0.000,NO
R2551,"Q_RES_0402LF-1K,1%,1/16W,CHIP,A",1K,1%,R0402,3949.09,14164.91,180.000,YES
R2552,"Q_RES_0402LF-0,5%,1/16W,CHIP,CA",0,5%,R0402,3949.09,14129.91,180.000,YES
R2553,"Q_RES_0402LF-100,1%,1/16W,CHIPA",100,1%,R0402,3949.09,14040.85,0.000,YES
R2554,"Q_RES_0402LF-49.9,1%,1/16W,CHIA",49.9,1%,R0402,3949.09,14076.05,0.000,YES
R2555,"Q_RES_0402LF-49.9,1%,1/16W,EMPA",49.9,1%,R0402,3969.32,13986.53,180.000,NO
R2556,"Q_RES_0402LF-1K,1%,1/16W,CHIP,A",1K,1%,R0402,1455.47,4936.40,0.000,YES
R2557,"Q_RES_0402LF-0,5%,1/16W,CHIP,CA",0,5%,R0402,894.61,6621.31,90.000,NO
R2558,"Q_RES_0402LF-0,5%,1/16W,CHIP,CA",0,5%,R0402,1455.47,5016.40,0.000,YES
R2559,"Q_RES_0402LF-150,1%,1/16W,CHIPA",150,1%,R0402,1454.97,5108.10,180.000,NO
R2560,"Q_RES_0402LF-0,5%,1/16W,CHIP,CA",0,5%,R0402,1454.97,5148.10,180.000,NO
R2561,"Q_RES_0402LF-0,5%,1/16W,CHIP,CA",0,5%,R0402,1454.97,5188.10,180.000,NO
R2562,"Q_RES_0402LF-0,5%,1/16W,CHIP,CA",0,5%,R0402,9050.80,5001.17,180.000,YES
R2563,"Q_RES_0402LF-0,5%,1/16W,CHIP,CA",0,5%,R0402,1300.06,4921.15,90.000,NO
R2565,"Q_RES_0402LF-0,5%,1/16W,CHIP,CA",0,5%,R0402,5055.18,5198.19,0.000,NO
R2566,"Q_RES_0402LF-0,5%,1/16W,CHIP,CA",0,5%,R0402,5055.18,5158.19,0.000,NO
R2568,"Q_RES_0402LF-1K,1%,1/16W,CHIP,A",1K,1%,R0402,1064.50,5179.25,0.000,NO
R2569,"Q_RES_0402LF-1K,1%,1/16W,CHIP,A",1K,1%,R0402,1455.47,5055.50,0.000,YES
R2570,"Q_RES_0402LF-0,5%,1/16W,CHIP,CA",0,5%,R0402,1454.97,5268.30,180.000,NO
R2571,"Q_RES_0402LF-1K,1%,1/16W,CHIP,A",1K,1%,R0402,1454.97,5149.80,0.000,YES
R2572,"Q_RES_0402LF-0,5%,1/16W,CHIP,CA",0,5%,R0402,1454.97,5188.10,0.000,YES
R2573,"Q_RES_0402LF-1K,1%,1/16W,EMPTYA",1K,1%,R0402,1524.70,5043.63,270.000,NO
R2574,"Q_RES_0402LF-0,5%,1/16W,CHIP,CA",0,5%,R0402,1454.62,5065.33,0.000,NO
R2575,"Q_RES_0402LF-1K,1%,1/16W,CHIP,A",1K,1%,R0402,885.40,6679.52,180.000,YES
R2576,"Q_RES_0402LF-0,5%,1/16W,CHIP,CA",0,5%,R0402,862.78,6631.41,180.000,YES
R2577,"Q_RES_0402LF-0,5%,1/16W,CHIP,CA",0,5%,R0402,862.78,6596.41,180.000,YES
R2578,"Q_RES_0402LF-150,1%,1/16W,CHIPA",150,1%,R0402,871.40,6525.64,0.000,NO
R2579,"Q_RES_0402LF-0,5%,1/16W,CHIP,CA",0,5%,R0402,871.40,6485.64,0.000,NO
R2580,"Q_RES_0402LF-0,5%,1/16W,CHIP,CA",0,5%,R0402,871.40,6445.64,0.000,NO
R2582,"Q_RES_0402LF-0,5%,1/16W,CHIP,CA",0,5%,R0402,905.08,6778.81,180.000,YES
R2583,"Q_RES_0402LF-10K,1%,1/16W,CHIPA",10K,1%,R0402,4794.66,14003.85,0.000,NO
R2584,"Q_RES_0402LF-10K,1%,1/16W,CHIPA",10K,1%,R0402,995.16,6922.23,270.000,YES
R2585,"Q_RES_0402LF-31.6K,1%,1/16W,CHA",31.6K,1%,R0402,7434.62,16687.45,270.000,NO
R2586,"Q_RES_0402LF-0,5%,1/16W,CHIP,CA",0,5%,R0402,7282.52,15694.93,180.000,NO
R2587,"Q_RES_0402LF-4.7K,1%,1/16W,CHIA",4.7K,1%,R0402,7561.12,15817.83,180.000,YES
R2588,"Q_RES_0402LF-22,1%,1/16W,CHIP,A",22,1%,R0402,7561.12,15871.83,0.000,NO
R2589,"Q_RES_0402LF-1K,1%,1/16W,CHIP,A",1K,1%,R0402,14303.00,14019.48,0.000,YES
R2590,"Q_RES_0402LF-100,1%,1/16W,CHIPA",100,1%,R0402,13716.16,14034.58,180.000,NO
R2591,"Q_RES_0402LF-0,5%,1/16W,CHIP,CA",0,5%,R0402,13829.45,14173.04,180.000,YES
R2593,"Q_RES_0402LF-100,1%,1/16W,CHIPA",100,1%,R0402,791.90,6445.64,0.000,NO
R2594,"Q_RES_0402LF-0,5%,1/16W,CHIP,CA",0,5%,R0402,16952.76,5295.07,0.000,YES
R2595,"Q_RES_0402LF-0,5%,1/16W,CHIP,CA",0,5%,R0402,16952.76,5255.07,0.000,YES
R2596,"Q_RES_0402LF-150,1%,1/16W,CHIPA",150,1%,R0402,16952.76,5375.07,180.000,NO
R2597,"Q_RES_0402LF-0,5%,1/16W,CHIP,CA",0,5%,R0402,16952.76,5335.07,0.000,NO
R2656,"Q_RES_0402LF-100,1%,1/16W,EMPTA",100,1%,R0402,1767.93,15809.74,90.000,NO
R2659,"Q_RES_0402LF-0,5%,1/16W,CHIP,CA",0,5%,R0402,4419.90,16457.77,90.000,NO
R2660,"Q_RES_0402LF-0,5%,1/16W,CHIP,CA",0,5%,R0402,4379.90,16457.77,90.000,NO
R2661,"Q_RES_0402LF-33.2,1%,1/16W,CHIA",33.2,1%,R0402,6716.30,3916.02,0.000,NO
R2662,"Q_RES_0402LF-33.2,1%,1/16W,CHIA",33.2,1%,R0402,6482.20,4113.62,180.000,NO
R2663,"Q_RES_0402LF-33.2,1%,1/16W,CHIA",33.2,1%,R0402,6482.20,4163.62,180.000,YES
R2664,"Q_RES_0402LF-33.2,1%,1/16W,CHIA",33.2,1%,R0402,6482.20,4313.62,180.000,YES
R2666,"Q_RES_0402LF-10K,1%,1/16W,CHIPA",10K,1%,R0402,13965.82,15760.97,180.000,NO
R2667,"Q_RES_0402LF-10K,1%,1/16W,CHIPA",10K,1%,R0402,6462.25,17041.94,270.000,NO
R2668,"Q_RES_0402LF-4.7K,5%,1/16W,EMPA",4.7K,5%,R0402,14084.08,15650.37,0.000,NO
R2669,"Q_RES_0402LF-10K,1%,1/16W,CHIPA",10K,1%,R0402,6477.25,16476.94,90.000,NO
R2670,"Q_RES_0402LF-4.7K,5%,1/16W,EMPA",4.7K,5%,R0402,14084.08,15700.37,0.000,NO
R2671,"Q_RES_0402LF-33.2,1%,1/16W,CHIA",33.2,1%,R0402,6502.25,17041.94,90.000,NO
R2672,"Q_RES_0402LF-33.2,1%,1/16W,CHIA",33.2,1%,R0402,6517.25,16476.94,270.000,NO
R2674,"Q_RES_0402LF-27.4,1%,1/16W,CHIA",27.4,1%,R0402,13964.08,15650.37,180.000,NO
R2675,"Q_RES_0402LF-33.2,1%,1/16W,CHIA",33.2,1%,R0402,13964.08,15700.37,180.000,NO
R2676,"Q_RES_0402LF-0,5%,1/16W,CHIP,CA",0,5%,R0402,14083.48,15761.97,0.000,NO
R2693,"Q_RES_0402LF-1K,1%,1/16W,EMPTYA",1K,1%,R0402,543.33,16173.34,90.000,NO
R2694,"Q_RES_0402LF-1K,1%,1/16W,CHIP,A",1K,1%,R0402,543.33,16083.34,270.000,NO
R2695,"Q_RES_0402LF-1K,1%,1/16W,EMPTYA",1K,1%,R0402,578.33,16678.34,270.000,NO
R2696,"Q_RES_0402LF-1K,1%,1/16W,CHIP,A",1K,1%,R0402,537.00,16762.00,90.000,NO
R2703,"Q_RES_0402LF-0,5%,1/16W,CHIP,CA",0,5%,R0402,5055.18,5118.19,0.000,NO
R2704,"Q_RES_0402LF-0,5%,1/16W,CHIP,CA",0,5%,R0402,5055.18,5078.19,0.000,NO
R2705,"Q_RES_0402LF-0,5%,1/16W,EMPTY,A",0,5%,R0402,6437.25,16956.94,0.000,NO
R2706,"Q_RES_0402LF-0,5%,1/16W,CHIP,CA",0,5%,R0402,14539.08,15600.37,0.000,NO
R2707,"Q_RES_0402LF-0,5%,1/16W,CHIP,CA",0,5%,R0402,6502.25,16971.94,270.000,NO
R2724,"Q_RES_0402LF-0,5%,1/16W,EMPTY,A",0,5%,R0402,6452.25,16531.94,0.000,NO
R2725,"Q_RES_0402LF-0,5%,1/16W,CHIP,CA",0,5%,R0402,14539.08,15650.37,0.000,NO
R2726,"Q_RES_0402LF-33.2,1%,1/16W,CHIA",33.2,1%,R0402,11996.79,12561.49,90.000,YES
R2727,"Q_RES_0402LF-33.2,1%,1/16W,CHIA",33.2,1%,R0402,12306.81,12561.78,90.000,YES
R2728,"Q_RES_0402LF-33.2,1%,1/16W,CHIA",33.2,1%,R0402,11429.21,12561.77,270.000,YES
R2729,"Q_RES_0402LF-33.2,1%,1/16W,CHIA",33.2,1%,R0402,10820.30,12558.52,90.000,YES
R2730,"Q_RES_0402LF-33.2,1%,1/16W,CHIA",33.2,1%,R0402,11119.04,12556.95,90.000,YES
R2731,"Q_RES_0402LF-33.2,1%,1/16W,CHIA",33.2,1%,R0402,10242.41,12569.44,180.000,YES
R2732,"Q_RES_0402LF-33.2,1%,1/16W,CHIA",33.2,1%,R0402,17050.13,12553.89,90.000,YES
R2733,"Q_RES_0402LF-33.2,1%,1/16W,CHIA",33.2,1%,R0402,16754.14,12555.44,90.000,YES
R2734,"Q_RES_0402LF-33.2,1%,1/16W,CHIA",33.2,1%,R0402,18109.54,12543.64,90.000,YES
R2735,"Q_RES_0402LF-33.2,1%,1/16W,CHIA",33.2,1%,R0402,17952.89,12568.19,180.000,YES
R2736,"Q_RES_0402LF-33.2,1%,1/16W,CHIA",33.2,1%,R0402,7020.62,12559.94,90.000,YES
R2738,"Q_RES_0402LF-33.2,1%,1/16W,CHIA",33.2,1%,R0402,902.45,16830.71,0.000,NO
R2786,"Q_RES_0402LF-0,5%,1/16W,CHIP,CA",0,5%,R0402,449.67,4152.85,90.000,NO
R2787,"Q_RES_0402LF-0,5%,1/16W,CHIP,CA",0,5%,R0402,503.39,4153.70,90.000,NO
R2788,"Q_RES_0402LF-0,5%,1/16W,EMPTY,A",0,5%,R0402,449.67,4184.35,270.000,NO
R2789,"Q_RES_0402LF-0,5%,1/16W,EMPTY,A",0,5%,R0402,503.39,4185.20,270.000,NO
R2790,"Q_RES_0402LF-0,5%,1/16W,EMPTY,A",0,5%,R0402,601.89,4154.95,90.000,NO
R2791,"Q_RES_0402LF-0,5%,1/16W,EMPTY,A",0,5%,R0402,655.33,4156.15,90.000,NO
R2792,"Q_RES_0402LF-0,5%,1/16W,CHIP,CA",0,5%,R0402,7613.40,4838.62,0.000,NO
R2796,"Q_RES_0402LF-33.2,1%,1/16W,CHIA",33.2,1%,R0402,7131.33,16804.00,180.000,NO
R2800,"Q_RES_0402LF-0,5%,1/16W,EMPTY,A",0,5%,R0402,7101.09,16678.41,0.000,YES
R2801,"Q_RES_0402LF-0,5%,1/16W,EMPTY,A",0,5%,R0402,7067.19,16418.51,180.000,YES
R2802,"Q_RES_0402LF-0,5%,1/16W,CHIP,CA",0,5%,R0402,9299.79,16653.62,90.000,YES
R2803,"Q_RES_0402LF-0,5%,1/16W,CHIP,CA",0,5%,R0402,9501.00,16653.00,90.000,YES
R2805,"Q_RES_0402LF-4.7K,5%,1/16W,EMPA",4.7K,5%,R0402,7100.96,16638.42,0.000,YES
R2807,"Q_RES_0402LF-4.7K,5%,1/16W,EMPA",4.7K,5%,R0402,7082.19,16363.51,270.000,YES
R2811,"Q_RES_0402LF-33.2,1%,1/16W,CHIA",33.2,1%,R0402,7050.83,16624.93,90.000,YES
R2812,"Q_RES_0402LF-33.2,1%,1/16W,CHIA",33.2,1%,R0402,7042.19,16363.51,90.000,YES
R2815,"Q_RES_0402LF-100K,1%,1/16W,EMPA",100K,1%,R0402,6671.20,16728.62,0.000,NO
R2820,"Q_RES_0402LF-4.7K,5%,1/16W,EMPA",4.7K,5%,R0402,6936.20,16788.62,180.000,NO
R2828,"Q_RES_0402LF-100K,1%,1/16W,CHIA",100K,1%,R0402,16700.98,15013.62,0.000,NO
R2829,"Q_RES_0402LF-100K,1%,1/16W,EMPA",100K,1%,R0402,16700.98,15053.62,180.000,NO
R2830,"Q_RES_0402LF-100K,1%,1/16W,CHIA",100K,1%,R0402,4679.13,16036.82,180.000,NO
R2831,"Q_RES_0402LF-100K,1%,1/16W,EMPA",100K,1%,R0402,4663.20,15977.29,270.000,NO
R2832,"Q_RES_0402LF-100K,1%,1/16W,CHIA",100K,1%,R0402,16700.98,15458.62,0.000,NO
R2833,"Q_RES_0402LF-100K,1%,1/16W,EMPA",100K,1%,R0402,16700.98,15418.62,180.000,NO
R2834,"Q_RES_0402LF-4.7K,5%,1/16W,CHIA",4.7K,5%,R0402,17007.48,15008.62,180.000,NO
R2835,"Q_RES_0402LF-4.7K,5%,1/16W,CHIA",4.7K,5%,R0402,4572.20,15879.95,90.000,NO
R2836,"Q_RES_0402LF-4.7K,5%,1/16W,CHIA",4.7K,5%,R0402,17007.48,15413.62,180.000,NO
R2837,"Q_RES_0402LF-100K,1%,1/16W,EMPA",100K,1%,R0402,16700.98,15208.62,0.000,NO
R2838,"Q_RES_0402LF-100K,1%,1/16W,CHIA",100K,1%,R0402,16700.98,15248.62,180.000,NO
R2841,"Q_RES_0402LF-4.7K,5%,1/16W,CHIA",4.7K,5%,R0402,17007.48,15203.62,180.000,NO
R2842,"Q_RES_0402LF-4.7K,5%,1/16W,CHIA",4.7K,5%,R0402,1255.58,16378.62,180.000,NO
R2843,"Q_RES_0402LF-4.7K,1%,1/16W,CHIA",4.7K,1%,R0402,1738.96,4253.83,0.000,NO
R2844,"Q_RES_0402LF-33.2,1%,1/16W,CHIA",33.2,1%,R0402,6482.20,4163.62,0.000,NO
R2845,"Q_RES_0402LF-33.2,1%,1/16W,CHIA",33.2,1%,R0402,6332.20,4163.62,180.000,NO
R2846,"Q_RES_0402LF-33.2,1%,1/16W,CHIA",33.2,1%,R0402,6332.20,4113.62,0.000,NO
R2847,"Q_RES_0402LF-33.2,1%,1/16W,CHIA",33.2,1%,R0402,6332.20,4313.62,0.000,NO
R2848,"Q_RES_0402LF-0,5%,1/16W,CHIP,CA",0,5%,R0402,703.33,16173.34,270.000,NO
R2893,"Q_RES_0402LF-0,5%,1/16W,EMPTY,A",0,5%,R0402,1581.18,17100.17,90.000,NO
R2894,"Q_RES_0402LF-0,5%,1/16W,EMPTY,A",0,5%,R0402,2007.20,17118.62,90.000,NO
R2897,"Q_RES_0402LF-33.2,1%,1/16W,CHIA",33.2,1%,R0402,1497.20,17163.62,180.000,NO
R2898,"Q_RES_0402LF-33.2,1%,1/16W,CHIA",33.2,1%,R0402,2066.18,17180.17,0.000,NO
R2899,"Q_RES_0402LF-0,5%,1/16W,CHIP,CA",0,5%,R0402,1567.20,17163.62,0.000,NO
R2900,"Q_RES_0402LF-2K,1%,1/16W,EMPTYA",2K,1%,R0402,1289.82,4045.71,0.000,NO
R2905,"Q_RES_0402LF-0,5%,1/16W,CHIP,CA",0,5%,R0402,6542.45,2903.71,0.000,NO
R2906,"Q_RES_0402LF-0,5%,1/16W,CHIP,CA",0,5%,R0402,9339.79,16653.27,90.000,YES
R2907,"Q_RES_0402LF-5.11K,1%,1/16W,CHA",5.11K,1%,R0402,1833.96,4213.83,180.000,NO
R2908,"Q_RES_0402LF-5.11K,1%,1/16W,CHA",5.11K,1%,R0402,1833.96,4253.83,180.000,NO
R2909,"Q_RES_0402LF-4.7K,5%,1/16W,CHIA",4.7K,5%,R0402,6671.20,16688.62,0.000,NO
R2910,"Q_RES_0402LF-100K,1%,1/16W,EMPA",100K,1%,R0402,902.20,16943.62,0.000,NO
R2911,"Q_RES_0402LF-4.7K,5%,1/16W,EMPA",4.7K,5%,R0402,6936.20,16628.62,180.000,NO
R2912,"Q_RES_0402LF-4.7K,5%,1/16W,EMPA",4.7K,5%,R0402,4739.30,16632.42,180.000,NO
R2914,"Q_RES_0402LF-4.7K,5%,1/16W,EMPA",4.7K,5%,R0402,1232.20,16963.62,180.000,NO
R2915,"Q_RES_0402LF-4.7K,5%,1/16W,CHIA",4.7K,5%,R0402,6671.20,16768.62,180.000,NO
R2916,"Q_RES_0402LF-4.7K,5%,1/16W,EMPA",4.7K,5%,R0402,6671.20,16648.62,180.000,NO
R2917,"Q_RES_0402LF-49.9,1%,1/16W,CHIA",49.9,1%,R0402,6936.20,16748.62,0.000,NO
R2918,"Q_RES_0402LF-4.7K,5%,1/16W,CHIA",4.7K,5%,R0402,902.20,16903.62,180.000,NO
R2919,"Q_RES_0402LF-4.7K,5%,1/16W,CHIA",4.7K,5%,R0402,16700.98,14933.62,0.000,NO
R2920,"Q_RES_0402LF-4.7K,5%,1/16W,CHIA",4.7K,5%,R0402,4679.13,16106.82,180.000,NO
R2921,"Q_RES_0402LF-10K,1%,1/16W,EMPTA",10K,1%,R0402,598.33,16083.34,90.000,NO
R2922,"Q_RES_0402LF-0,5%,1/16W,CHIP,CA",0,5%,R0402,598.33,16173.34,90.000,NO
R2923,"Q_RES_0402LF-4.7K,5%,1/16W,EMPA",4.7K,5%,R0402,503.33,16173.34,90.000,NO
R2924,"Q_RES_0402LF-49.9,1%,1/16W,CHIA",49.9,1%,R0402,6936.20,16668.62,0.000,NO
R2925,"Q_RES_0402LF-49.9,1%,1/16W,CHIA",49.9,1%,R0402,4739.30,16592.42,0.000,NO
R2926,"Q_RES_0402LF-4.7K,5%,1/16W,CHIA",4.7K,5%,R0402,6936.20,16828.62,0.000,NO
R2927,"Q_RES_0402LF-100K,1%,1/16W,CHIA",100K,1%,R0402,6936.20,16588.62,0.000,NO
R2932,"Q_RES_0402LF-4.7K,5%,1/16W,CHIA",4.7K,5%,R0402,1232.20,16923.62,0.000,NO
R2933,"Q_RES_0402LF-4.7K,5%,1/16W,CHIA",4.7K,5%,R0402,16700.98,15338.62,0.000,NO
R2934,"Q_RES_0402LF-4.7K,5%,1/16W,CHIA",4.7K,5%,R0402,16700.98,15168.62,0.000,NO
R2935,"Q_RES_0402LF-4.7K,5%,1/16W,CHIA",4.7K,5%,R0402,946.73,16303.62,0.000,NO
R2936,"Q_RES_0402LF-100K,1%,1/16W,EMPA",100K,1%,R0402,4738.60,16774.62,180.000,NO
R2937,"Q_RES_0402LF-4.7K,5%,1/16W,CHIA",4.7K,5%,R0402,4738.60,16734.62,0.000,NO
R2939,"Q_RES_0402LF-33.2,1%,1/16W,CHIA",33.2,1%,R0402,6482.20,4213.62,180.000,NO
R2940,"Q_RES_0402LF-4.7K,5%,1/16W,EMPA",4.7K,5%,R0402,7593.59,17250.95,270.000,NO
R2941,"Q_RES_0402LF-100K,1%,1/16W,CHIA",100K,1%,R0402,7633.59,17250.95,90.000,NO
R2944,"Q_RES_0402LF-33.2,1%,1/16W,CHIA",33.2,1%,R0402,7638.59,16905.95,270.000,NO
R2946,"Q_RES_0402LF-4.7K,5%,1/16W,EMPA",4.7K,5%,R0402,7598.59,16905.95,90.000,NO
R2948,"Q_RES_0402LF-4.7K,5%,1/16W,EMPA",4.7K,5%,R0402,7558.59,16905.95,270.000,NO
R2950,"Q_RES_0402LF-4.7K,5%,1/16W,EMPA",4.7K,5%,R0402,7203.33,16804.00,180.000,NO
R2966,"Q_RES_0402LF-1M,1%,1/16W,CHIP,A",1M,1%,R0402,12748.64,1087.12,90.000,NO
R2967,"Q_RES_0402LF-0,5%,1/16W,CHIP,CA",0,5%,R0402,4468.28,5134.83,180.000,NO
R2968,"Q_RES_0402LF-0,5%,1/16W,CHIP,CA",0,5%,R0402,4468.28,5174.83,180.000,NO
R2969,"Q_RES_0402LF-0,5%,1/16W,CHIP,CA",0,5%,R0402,4981.69,4716.96,270.000,NO
R2971,"Q_RES_0402LF-0,5%,1/16W,CHIP,CA",0,5%,R0402,12713.64,1966.22,180.000,YES
R2972,"Q_RES_0402LF-10K,1%,1/16W,CHIPA",10K,1%,R0402,11772.45,1861.74,0.000,NO
R2973,"Q_RES_0402LF-1K,1%,1/16W,EMPTYA",1K,1%,R0402,11772.45,1901.74,180.000,NO
R2974,"Q_RES_0402LF-10K,1%,1/16W,CHIPA",10K,1%,R0402,12711.50,3015.16,270.000,NO
R2975,"Q_RES_0402LF-1K,1%,1/16W,EMPTYA",1K,1%,R0402,12671.50,3015.16,90.000,NO
R2976,"Q_RES_0402LF-10K,1%,1/16W,EMPTA",10K,1%,R0402,11772.45,2141.74,0.000,NO
R2977,"Q_RES_0402LF-1K,1%,1/16W,CHIP,A",1K,1%,R0402,11772.45,2101.74,180.000,NO
R2978,"Q_RES_0402LF-1K,1%,1/16W,CHIP,A",1K,1%,R0402,11772.45,2061.74,180.000,NO
R2979,"Q_RES_0402LF-10K,1%,1/16W,EMPTA",10K,1%,R0402,11772.45,2181.74,0.000,NO
R2980,"Q_RES_0402LF-1K,1%,1/16W,CHIP,A",1K,1%,R0402,11772.45,2221.74,180.000,NO
R2982,"Q_RES_0402LF-0,5%,1/16W,CHIP,CA",0,5%,R0402,533.33,16678.34,270.000,NO
R2983,"Q_RES_0402LF-0,5%,1/16W,CHIP,CA",0,5%,R0402,493.33,16678.34,270.000,NO
R2984,"Q_RES_0402LF-10K,1%,1/16W,CHIPA",10K,1%,R0402,5175.86,5059.69,180.000,NO
R2985,"Q_RES_0402LF-10K,1%,1/16W,CHIPA",10K,1%,R0402,5175.86,5004.69,180.000,NO
R2986,"Q_RES_0402LF-0,5%,1/16W,EMPTY,A",0,5%,R0402,1750.67,17315.92,270.000,NO
R2987,"Q_RES_0402LF-0,5%,1/16W,EMPTY,A",0,5%,R0402,1345.57,17296.82,270.000,NO
R2990,"Q_RES_0402LF-33.2,1%,1/16W,CHIA",33.2,1%,R0402,1835.67,17235.92,0.000,NO
R2991,"Q_RES_0402LF-33.2,1%,1/16W,CHIA",33.2,1%,R0402,1290.57,17231.82,180.000,NO
R2992,"Q_RES_0402LF-0,5%,1/16W,CHIP,CA",0,5%,R0402,1765.67,17235.92,180.000,NO
R2994,"Q_RES_0402LF-0,5%,1/16W,CHIP,CA",0,5%,R0402,5972.20,898.62,90.000,NO
R2995,"Q_RES_0402LF-33.2,1%,1/16W,CHIA",33.2,1%,R0402,292.20,2243.62,0.000,NO
R2996,"Q_RES_0402LF-33.2,1%,1/16W,CHIA",33.2,1%,R0402,292.20,2163.62,0.000,NO
R2999,"Q_RES_0402LF-2.2K,5%,1/16W,EMPA",2.2K,5%,R0402,2006.25,17330.22,0.000,NO
R3004,"Q_RES_0402LF-2.2K,5%,1/16W,EMPA",2.2K,5%,R0402,1209.10,17250.47,270.000,NO
R3005,"Q_RES_0402LF-18K,1%,1/16W,CHIPA",18K,1%,R0402,1833.96,4308.83,180.000,NO
R3023,"Q_RES_0402LF-0,5%,1/16W,CHIP,CA",0,5%,R0402,6082.25,7590.30,270.000,YES
R3024,"Q_RES_0402LF-240,1%,1/16W,EMPTA",240,1%,R0402,3789.02,7508.08,270.000,YES
R3025,"Q_RES_0402LF-1K,1%,1/16W,EMPTYA",1K,1%,R0402,3547.20,2258.62,180.000,NO
R3026,"Q_RES_0402LF-1K,1%,1/16W,CHIP,A",1K,1%,R0402,4297.20,2148.62,0.000,NO
R3027,"Q_RES_0402LF-1K,1%,1/16W,CHIP,A",1K,1%,R0402,3802.20,2213.62,180.000,NO
R3028,"Q_RES_0402LF-100K,1%,1/16W,EMPA",100K,1%,R0402,4640.20,15764.37,90.000,NO
R3029,"Q_RES_0402LF-4.7K,5%,1/16W,CHIA",4.7K,5%,R0402,4595.20,15509.37,90.000,NO
R3030,"Q_RES_0402LF-4.7K,5%,1/16W,CHIA",4.7K,5%,R0402,4520.20,15764.37,270.000,NO
R3032,"Q_RES_0402LF-100K,1%,1/16W,EMPA",100K,1%,R0402,4500.20,15664.37,90.000,NO
R3033,"Q_RES_0402LF-0,5%,1/16W,CHIP,CA",0,5%,R0402,14678.40,16296.02,270.000,NO
R3034,"Q_RES_0402LF-4.7K,5%,1/16W,CHIA",4.7K,5%,R0402,4520.20,15474.37,180.000,NO
R3035,"Q_RES_0402LF-4.7K,5%,1/16W,CHIA",4.7K,5%,R0402,4420.20,15664.37,270.000,NO
R3036,"Q_RES_0402LF-33.2,1%,1/16W,CHIA",33.2,1%,R0402,14516.30,15862.62,0.000,NO
R3037,"Q_RES_0402LF-1K,1%,1/16W,EMPTYA",1K,1%,R0402,17618.51,4658.93,0.000,NO
R3038,"Q_RES_0402LF-5.11K,1%,1/16W,CHA",5.11K,1%,R0402,12515.85,1201.07,180.000,YES
R3039,"Q_RES_0402LF-1K,1%,1/16W,CHIP,A",1K,1%,R0402,16280.33,1216.27,0.000,NO
R3040,"Q_RES_0402LF-1K,1%,1/16W,CHIP,A",1K,1%,R0402,12405.93,1974.62,0.000,NO
R3041,"Q_RES_0402LF-10K,1%,1/16W,CHIPA",10K,1%,R0402,12495.93,2015.62,0.000,NO
R3042,"Q_RES_0402LF-10K,1%,1/16W,EMPTA",10K,1%,R0402,12605.44,2295.22,270.000,YES
R3043,"Q_RES_0402LF-33.2,1%,1/16W,CHIA",33.2,1%,R0402,6332.20,4213.62,0.000,NO
R3045,"Q_RES_0402LF-0,5%,1/16W,CHIP,CA",0,5%,R0402,7622.20,4082.12,180.000,NO
R3046,"Q_RES_0402LF-0,5%,1/16W,CHIP,CA",0,5%,R0402,7622.20,3982.12,180.000,NO
R3047,"Q_RES_0402LF-0,5%,1/16W,CHIP,CA",0,5%,R0402,6802.20,5263.62,270.000,NO
R3048,"Q_RES_0402LF-0,5%,1/16W,CHIP,CA",0,5%,R0402,6752.20,5263.62,270.000,NO
R3049,"Q_RES_0402LF-0,5%,1/16W,CHIP,CA",0,5%,R0402,7613.40,4598.62,180.000,NO
R3050,"Q_RES_0402LF-33.2,1%,1/16W,CHIA",33.2,1%,R0402,377.20,2083.62,0.000,NO
R3051,"Q_RES_0402LF-0,5%,1/16W,CHIP,CA",0,5%,R0402,1095.15,2165.96,0.000,NO
R3052,"Q_RES_0402LF-33.2,1%,1/16W,CHIA",33.2,1%,R0402,380.00,2008.62,0.000,NO
R3053,"Q_RES_0402LF-33.2,1%,1/16W,CHIA",33.2,1%,R0402,380.00,1928.62,0.000,NO
R3054,"Q_RES_0402LF-33.2,1%,1/16W,CHIA",33.2,1%,R0402,1105.75,1863.62,0.000,NO
R3055,"Q_RES_0402LF-1K,1%,1/16W,CHIP,A",1K,1%,R0402,14497.77,3659.96,90.000,NO
R3056,"Q_RES_0402LF-33.2,1%,1/16W,CHIA",33.2,1%,R0402,14895.64,3656.98,270.000,NO
R3057,"Q_RES_0402LF-33.2,1%,1/16W,CHIA",33.2,1%,R0402,5725.00,368.62,270.000,YES
R3058,"Q_RES_0402LF-33.2,1%,1/16W,CHIA",33.2,1%,R0402,377.20,2403.62,0.000,NO
R3059,"Q_RES_0402LF-33.2,1%,1/16W,CHIA",33.2,1%,R0402,377.20,2323.62,0.000,NO
R3060,"Q_RES_0402LF-33.2,1%,1/16W,CHIA",33.2,1%,R0402,377.20,2243.42,0.000,NO
R3061,"Q_RES_0402LF-33.2,1%,1/16W,CHIA",33.2,1%,R0402,377.20,2163.62,0.000,NO
R3062,"Q_RES_0402LF-2K,1%,1/16W,EMPTYA",2K,1%,R0402,7121.00,841.12,270.000,YES
R3063,"Q_RES_0402LF-33.2,1%,1/16W,CHIA",33.2,1%,R0402,14226.80,15864.00,90.000,NO
R3064,"Q_RES_0402LF-0,5%,1/16W,EMPTY,A",0,5%,R0402,12166.56,2455.73,90.000,NO
R3065,"Q_RES_0402LF-33.2,1%,1/16W,CHIA",33.2,1%,R0402,981.55,1692.63,180.000,NO
R3066,"Q_RES_0402LF-0,5%,1/16W,CHIP,CA",0,5%,R0402,902.97,16678.80,270.000,NO
R3067,"Q_RES_0402LF-0,5%,1/16W,CHIP,CA",0,5%,R0402,858.33,16678.34,270.000,NO
R3068,"Q_RES_0402LF-130,1%,1/16W,CHIPA",130,1%,R0402,3673.06,2567.86,270.000,NO
R3069,"Q_RES_0402LF-130,1%,1/16W,CHIPA",130,1%,R0402,3546.72,2566.68,270.000,NO
R3070,"Q_RES_0402LF-130,1%,1/16W,CHIPA",130,1%,R0402,3296.48,2561.77,270.000,NO
R3071,"Q_RES_0402LF-130,1%,1/16W,CHIPA",130,1%,R0402,4297.02,2947.38,270.000,NO
R3072,"Q_RES_0402LF-130,1%,1/16W,CHIPA",130,1%,R0402,4172.18,2952.49,270.000,NO
R3073,"Q_RES_0402LF-130,1%,1/16W,CHIPA",130,1%,R0402,3920.83,2949.29,270.000,NO
R3074,"Q_RES_0402LF-130,1%,1/16W,CHIPA",130,1%,R0402,4042.15,2951.15,270.000,NO
R3075,"Q_RES_0402LF-130,1%,1/16W,CHIPA",130,1%,R0402,3664.98,2942.39,270.000,NO
R3078,"Q_RES_0402LF-130,1%,1/16W,CHIPA",130,1%,R0402,3791.12,2943.61,270.000,NO
R3079,"Q_RES_0402LF-130,1%,1/16W,CHIPA",130,1%,R0402,2917.59,2562.31,270.000,NO
R3080,"Q_RES_0402LF-130,1%,1/16W,CHIPA",130,1%,R0402,3046.51,2562.31,270.000,NO
R3081,"Q_RES_0402LF-130,1%,1/16W,CHIPA",130,1%,R0402,2864.81,2562.31,270.000,NO
R3082,"Q_RES_0402LF-130,1%,1/16W,CHIPA",130,1%,R0402,2810.77,2562.31,270.000,NO
R3083,"Q_RES_0402LF-130,1%,1/16W,CHIPA",130,1%,R0402,2718.21,2562.31,270.000,NO
R3084,"Q_RES_0402LF-130,1%,1/16W,CHIPA",130,1%,R0402,2764.91,2562.31,270.000,NO
R3085,"Q_RES_0402LF-130,1%,1/16W,CHIPA",130,1%,R0402,2677.59,2562.31,270.000,NO
R3086,"Q_RES_0402LF-130,1%,1/16W,CHIPA",130,1%,R0402,3290.02,2948.88,270.000,NO
R3087,"Q_RES_0402LF-130,1%,1/16W,CHIPA",130,1%,R0402,3067.36,2948.88,270.000,NO
R3088,"Q_RES_0402LF-130,1%,1/16W,CHIPA",130,1%,R0402,2892.74,2948.88,270.000,NO
R3089,"Q_RES_0402LF-130,1%,1/16W,CHIPA",130,1%,R0402,2981.84,2948.88,270.000,NO
R3090,"Q_RES_0402LF-130,1%,1/16W,CHIPA",130,1%,R0402,4177.65,2567.80,270.000,NO
R3091,"Q_RES_0402LF-130,1%,1/16W,CHIPA",130,1%,R0402,3926.16,2564.61,270.000,NO
R3092,"Q_RES_0402LF-130,1%,1/16W,CHIPA",130,1%,R0402,2229.07,3202.56,90.000,NO
R3093,"Q_RES_0402LF-130,1%,1/16W,CHIPA",130,1%,R0402,3164.63,2948.88,270.000,NO
R3094,"Q_RES_0402LF-130,1%,1/16W,CHIPA",130,1%,R0402,3027.65,2948.88,270.000,NO
R3095,"Q_RES_0402LF-130,1%,1/16W,CHIPA",130,1%,R0402,2845.15,2948.88,270.000,NO
R3096,"Q_RES_0402LF-130,1%,1/16W,CHIPA",130,1%,R0402,2937.63,2948.88,270.000,NO
R3097,"Q_RES_0402LF-130,1%,1/16W,CHIPA",130,1%,R0402,4049.85,2563.90,270.000,NO
R3098,"Q_RES_0402LF-130,1%,1/16W,CHIPA",130,1%,R0402,3798.60,2564.71,270.000,NO
R3099,"Q_RES_0402LF-130,1%,1/16W,CHIPA",130,1%,R0402,4318.73,2567.80,270.000,NO
R3100,"Q_RES_0402LF-130,1%,1/16W,CHIPA",130,1%,R0402,3412.95,2942.14,270.000,NO
R3101,"Q_RES_0402LF-470,1%,1/16W,CHIPA",470,1%,R0402,4422.65,2949.14,270.000,NO
R3102,"Q_RES_0402LF-470,1%,1/16W,CHIPA",470,1%,R0402,3541.45,2945.66,270.000,NO
R3103,"Q_RES_0402LF-0,5%,1/16W,CHIP,CA",0,5%,R0402,1094.25,2321.28,180.000,NO
R3105,"Q_RES_0402LF-0,5%,1/16W,CHIP,CA",0,5%,R0402,6422.25,17041.94,270.000,NO
R3106,"Q_RES_0402LF-0,5%,1/16W,CHIP,CA",0,5%,R0402,6437.25,16476.94,90.000,NO
R3107,"Q_RES_0402LF-0,5%,1/16W,CHIP,CA",0,5%,R0402,1835.67,17330.92,180.000,NO
R3108,"Q_RES_0402LF-0,5%,1/16W,CHIP,CA",0,5%,R0402,1290.57,17311.82,0.000,NO
R3109,"Q_RES_0402LF-0,5%,1/16W,CHIP,CA",0,5%,R0402,1497.20,17083.62,0.000,NO
R3110,"Q_RES_0402LF-0,5%,1/16W,CHIP,CA",0,5%,R0402,2067.20,17098.62,180.000,NO
R3111,"Q_RES_0402LF-0,5%,1/16W,CHIP,CA",0,5%,R0402,6785.28,350.67,0.000,YES
R3112,"Q_RES_0402LF-33.2,1%,1/16W,CHIA",33.2,1%,R0402,6856.82,350.57,180.000,YES
R3113,"Q_RES_0402LF-33.2,1%,1/16W,CHIA",33.2,1%,R0402,6310.60,502.92,90.000,YES
R3114,"Q_RES_0402LF-33.2,1%,1/16W,CHIA",33.2,1%,R0402,6190.90,442.92,90.000,YES
R3117,"Q_RES_0402LF-510K,5%,1/16W,EMPA",510K,5%,R0402,17646.80,3075.42,90.000,YES
R3118,"Q_RES_0402LF-86.6K,1%,1/16W,EMA",86.6K,1%,R0402,17745.37,3020.44,90.000,YES
R3123,"Q_RES_0402LF-0,5%,1/16W,CHIP,CA",0,5%,R0402,6116.09,3224.20,90.000,NO
R3124,"Q_RES_0402LF-0,5%,1/16W,CHIP,CA",0,5%,R0402,6038.22,3223.70,90.000,NO
R3125,"Q_RES_0402LF-0,5%,1/16W,CHIP,CA",0,5%,R0402,6272.36,3224.51,90.000,NO
R3126,"Q_RES_0402LF-0,5%,1/16W,CHIP,CA",0,5%,R0402,6194.96,3224.70,90.000,NO
R3127,"Q_RES_0402LF-10K,1%,1/16W,CHIPA",10K,1%,R0402,6391.45,3065.47,180.000,NO
R3130,"Q_RES_0402LF-10K,1%,1/16W,CHIPA",10K,1%,R0402,5865.45,3115.71,0.000,NO
R3131,"Q_RES_0402LF-10K,1%,1/16W,CHIPA",10K,1%,R0402,5865.45,3040.52,0.000,NO
R3132,"Q_RES_0402LF-100K,1%,1/16W,CHIA",100K,1%,R0402,6332.23,4366.50,0.000,NO
R3133,"Q_RES_0402LF-1K,1%,1/16W,CHIP,A",1K,1%,R0402,811.40,3032.62,0.000,NO
R3134,"Q_RES_0402LF-1K,1%,1/16W,CHIP,A",1K,1%,R0402,811.40,2862.62,0.000,NO
R3135,"Q_RES_0402LF-1K,1%,1/16W,CHIP,A",1K,1%,R0402,811.40,2957.98,0.000,NO
R3136,"Q_RES_0402LF-1K,1%,1/16W,CHIP,A",1K,1%,R0402,811.40,2787.98,0.000,NO
R3142,"Q_RES_0402LF-0,5%,1/16W,CHIP,CA",0,5%,R0402,1125.12,2788.75,0.000,NO
R3143,"Q_RES_0402LF-0,5%,1/16W,CHIP,CA",0,5%,R0402,1125.12,3062.36,0.000,NO
R3144,"Q_RES_0402LF-0,5%,1/16W,CHIP,CA",0,5%,R0402,17891.63,709.87,0.000,NO
R3145,"Q_RES_0402LF-10K,1%,1/16W,CHIPA",10K,1%,R0402,1254.19,3062.36,180.000,NO
R3147,"Q_RES_0402LF-10K,1%,1/16W,CHIPA",10K,1%,R0402,1254.19,2788.75,180.000,NO
R3149,"Q_RES_0402LF-1K,1%,1/16W,EMPTYA",1K,1%,R0402,5284.00,4891.12,0.000,NO
R3150,"Q_RES_0402LF-1K,1%,1/16W,CHIP,A",1K,1%,R0402,5184.00,4891.12,180.000,NO
R3151,"Q_RES_0402LF-1K,1%,1/16W,EMPTYA",1K,1%,R0402,5284.00,4951.12,0.000,NO
R3152,"Q_RES_0402LF-1K,1%,1/16W,CHIP,A",1K,1%,R0402,5184.00,4951.12,180.000,NO
R3153,"Q_RES_0402LF-1K,1%,1/16W,EMPTYA",1K,1%,R0402,5790.70,4882.12,180.000,NO
R3154,"Q_RES_0402LF-1K,1%,1/16W,CHIP,A",1K,1%,R0402,5895.70,4882.12,0.000,NO
R3155,"Q_RES_0402LF-1K,1%,1/16W,CHIP,A",1K,1%,R0402,5170.20,4824.52,270.000,NO
R3156,"Q_RES_0402LF-33.2,1%,1/16W,CHIA",33.2,1%,R0402,5790.70,4932.12,180.000,NO
R3157,"Q_RES_0402LF-33.2,1%,1/16W,CHIA",33.2,1%,R0402,5790.70,4972.12,180.000,NO
R3158,"Q_RES_0402LF-33.2,1%,1/16W,CHIA",33.2,1%,R0402,5283.90,5002.22,180.000,NO
R3160,"Q_RES_0402LF-1K,1%,1/16W,EMPTYA",1K,1%,R0402,15340.00,1283.62,90.000,YES
R3162,"Q_RES_0402LF-4.7K,1%,1/16W,CHIA",4.7K,1%,R0402,2907.20,443.62,270.000,YES
R3163,"Q_RES_0402LF-4.7K,1%,1/16W,EMPA",4.7K,1%,R0402,2867.20,443.62,90.000,YES
R3164,"Q_RES_0402LF-10K,1%,1/16W,CHIPA",10K,1%,R0402,2437.20,758.62,180.000,NO
R3165,"Q_RES_0402LF-10K,1%,1/16W,CHIPA",10K,1%,R0402,2987.20,443.62,270.000,YES
R3166,"Q_RES_0402LF-4.7K,1%,1/16W,EMPA",4.7K,1%,R0402,2955.20,167.37,270.000,YES
R3167,"Q_RES_0402LF-4.7K,1%,1/16W,CHIA",4.7K,1%,R0402,2915.20,167.37,90.000,YES
R3168,"Q_RES_0402LF-0,5%,1/16W,CHIP,CA",0,5%,R0402,3027.20,443.62,90.000,YES
R3169,"Q_RES_0402LF-0,5%,1/16W,CHIP,CA",0,5%,R0402,2492.20,638.62,270.000,NO
R3170,"Q_RES_0402LF-0,5%,1/16W,CHIP,CA",0,5%,R0402,2452.20,638.62,270.000,NO
R3171,"Q_RES_0402LF-0,5%,1/16W,CHIP,CA",0,5%,R0402,2412.20,638.62,270.000,NO
R3172,"Q_RES_0402LF-0,5%,1/16W,CHIP,CA",0,5%,R0402,2372.20,638.62,270.000,NO
R3173,"Q_RES_0402LF-1K,1%,1/16W,CHIP,A",1K,1%,R0402,2947.20,443.62,90.000,YES
R3174,"Q_RES_0402LF-10K,1%,1/16W,CHIPA",10K,1%,R0402,6182.20,4628.62,180.000,NO
R3175,"Q_RES_0402LF-10K,1%,1/16W,CHIPA",10K,1%,R0402,6182.20,4678.62,0.000,YES
R3176,"Q_RES_0402LF-1K,1%,1/16W,CHIP,A",1K,1%,R0402,6482.20,4728.62,180.000,NO
R3177,"Q_RES_0402LF-0,5%,1/16W,CHIP,CA",0,5%,R0402,503.08,603.17,90.000,NO
R3178,"Q_RES_0402LF-0,5%,1/16W,CHIP,CA",0,5%,R0402,546.20,603.17,90.000,NO
R3180,"Q_RES_0402LF-100,1%,1/16W,CHIPA",100,1%,R0402,2380.63,327.53,270.000,YES
R3181,"Q_RES_0402LF-27.4,1%,1/16W,CHIA",27.4,1%,R0402,8566.29,644.93,270.000,NO
R3182,"Q_RES_0402LF-10K,1%,1/16W,CHIPA",10K,1%,R0402,11120.19,775.59,180.000,NO
R3183,"Q_RES_0402LF-10K,1%,1/16W,CHIPA",10K,1%,R0402,11120.19,728.03,180.000,NO
R3184,"Q_RES_0402LF-4.7K,1%,1/16W,CHIA",4.7K,1%,R0402,10806.89,785.53,0.000,NO
R3185,"Q_RES_0402LF-33.2,1%,1/16W,CHIA",33.2,1%,R0402,10806.89,836.98,180.000,NO
R3186,"Q_RES_0402LF-33.2,1%,1/16W,CHIA",33.2,1%,R0402,4191.97,1574.66,0.000,NO
R3187,"Q_RES_0402LF-33.2,1%,1/16W,CHIA",33.2,1%,R0402,4191.97,1614.66,0.000,NO
R3188,"Q_RES_0402LF-33.2,1%,1/16W,CHIA",33.2,1%,R0402,4191.97,1493.73,0.000,NO
R3189,"Q_RES_0402LF-33.2,1%,1/16W,CHIA",33.2,1%,R0402,4191.97,1534.77,0.000,NO
R3190,"Q_RES_0402LF-4.7K,1%,1/16W,CHIA",4.7K,1%,R0402,4581.39,1209.48,180.000,NO
R3191,"Q_RES_0402LF-33.2,1%,1/16W,CHIA",33.2,1%,R0402,4581.39,1159.48,0.000,NO
R3192,"Q_RES_0402LF-4.7K,1%,1/16W,EMPA",4.7K,1%,R0402,11056.72,600.28,180.000,NO
R3193,"Q_RES_0402LF-33.2,1%,1/16W,CHIA",33.2,1%,R0402,11056.32,555.05,0.000,NO
R3194,"Q_RES_0402LF-22,1%,1/16W,CHIP,A",22,1%,R0402,9207.47,4692.27,270.000,NO
R3195,"Q_RES_0402LF-22,1%,1/16W,CHIP,A",22,1%,R0402,9247.47,4692.27,270.000,NO
R3196,"Q_RES_0402LF-22,1%,1/16W,CHIP,A",22,1%,R0402,9337.47,4692.27,270.000,NO
R3197,"Q_RES_0402LF-22,1%,1/16W,CHIP,A",22,1%,R0402,9377.47,4692.27,270.000,NO
R3198,"Q_RES_0402LF-22,1%,1/16W,CHIP,A",22,1%,R0402,9417.47,4692.27,270.000,NO
R3199,"Q_RES_0402LF-22,1%,1/16W,CHIP,A",22,1%,R0402,9457.47,4692.27,270.000,NO
R3200,"Q_RES_0402LF-22,1%,1/16W,CHIP,A",22,1%,R0402,9568.20,4802.62,0.000,NO
R3201,"Q_RES_0402LF-22,1%,1/16W,CHIP,A",22,1%,R0402,9568.45,4842.71,0.000,NO
R3203,"Q_RES_0402LF-33.2,1%,1/16W,CHIA",33.2,1%,R0402,6332.20,4213.62,180.000,YES
R3205,"Q_RES_0402LF-49.9,1%,1/16W,CHIA",49.9,1%,R0402,6022.20,5068.62,180.000,NO
R3206,"Q_RES_0402LF-0,5%,1/16W,EMPTY,A",0,5%,R0402,6022.20,5108.62,180.000,NO
R3207,"Q_RES_0402LF-100K,1%,1/16W,CHIA",100K,1%,R0402,6022.20,5148.62,0.000,NO
R3208,"Q_RES_0402LF-100,1%,1/16W,CHIPA",100,1%,R0402,2508.59,620.96,90.000,YES
R3209,"Q_RES_0402LF-22,1%,1/16W,EMPTYA",22,1%,R0402,7993.99,3031.88,0.000,YES
R3210,"Q_RES_0402LF-22,1%,1/16W,EMPTYA",22,1%,R0402,7994.99,2954.88,0.000,YES
R3211,"Q_RES_0402LF-22,1%,1/16W,EMPTYA",22,1%,R0402,8512.31,3015.42,180.000,YES
R3212,"Q_RES_0402LF-22,1%,1/16W,EMPTYA",22,1%,R0402,8513.90,3088.52,180.000,YES
R3213,"Q_RES_0402LF-0,5%,1/16W,EMPTY,A",0,5%,R0402,7558.77,2733.99,0.000,YES
R3214,"Q_RES_0402LF-0,5%,1/16W,EMPTY,A",0,5%,R0402,8116.64,2768.20,180.000,YES
R3215,"Q_RES_0402LF-0,5%,1/16W,EMPTY,A",0,5%,R0402,8117.18,2843.11,180.000,YES
R3216,"Q_RES_0402LF-100,1%,1/16W,CHIPA",100,1%,R0402,2468.59,620.86,90.000,YES
R3217,"Q_RES_0402LF-100,1%,1/16W,CHIPA",100,1%,R0402,2437.20,718.62,0.000,NO
R3222,"Q_RES_0402LF-2K,1%,1/16W,CHIP,A",2K,1%,R0402,6156.35,3224.55,270.000,NO
R3223,"Q_RES_0402LF-2K,1%,1/16W,CHIP,A",2K,1%,R0402,6076.75,3223.99,270.000,NO
R3224,"Q_RES_0402LF-2K,1%,1/16W,CHIP,A",2K,1%,R0402,6311.46,3224.90,270.000,NO
R3225,"Q_RES_0402LF-2K,1%,1/16W,CHIP,A",2K,1%,R0402,6233.65,3224.75,270.000,NO
R3226,"Q_RES_0402LF-2.2K,5%,1/16W,EMPA",2.2K,5%,R0402,1423.20,17083.62,180.000,NO
R3227,"Q_RES_0402LF-2.2K,5%,1/16W,EMPA",2.2K,5%,R0402,2121.20,17082.62,270.000,NO
R3228,"Q_RES_0402LF-33.2,1%,1/16W,CHIA",33.2,1%,R0402,3777.40,1243.12,0.000,NO
R3229,"Q_RES_0402LF-33.2,1%,1/16W,CHIA",33.2,1%,R0402,3777.20,1284.52,0.000,NO
R3230,"Q_RES_0402LF-33.2,1%,1/16W,CHIA",33.2,1%,R0402,6332.20,4263.62,0.000,NO
R3231,"Q_RES_0402LF-33.2,1%,1/16W,CHIA",33.2,1%,R0402,17937.71,3678.66,0.000,NO
R3232,"Q_RES_0402LF-100K,1%,1/16W,CHIA",100K,1%,R0402,18250.51,3677.01,0.000,NO
R3233,"Q_RES_0402LF-0,5%,1/16W,CHIP,CA",0,5%,R0402,18250.51,3637.31,0.000,NO
R3234,"Q_RES_0402LF-33.2,1%,1/16W,CHIA",33.2,1%,R0402,6012.20,4163.62,180.000,NO
R3235,"Q_RES_0402LF-100K,1%,1/16W,CHIA",100K,1%,R0402,6032.20,4443.62,180.000,NO
R3236,"Q_RES_0402LF-0,5%,1/16W,CHIP,CA",0,5%,R0402,6032.20,4493.62,180.000,NO
R3237,"Q_RES_0402LF-0,5%,1/16W,CHIP,CA",0,5%,R0402,7538.35,3080.95,270.000,YES
R3238,"Q_RES_0402LF-33.2,1%,1/16W,CHIA",33.2,1%,R0402,7239.57,736.62,90.000,YES
R3239,"Q_RES_0402LF-33.2,1%,1/16W,CHIA",33.2,1%,R0402,7199.67,736.62,90.000,YES
R3240,"Q_RES_0402LF-2.2K,5%,1/16W,EMPA",2.2K,5%,R0402,17278.65,1770.72,180.000,NO
R3241,"Q_RES_0402LF-2.2K,5%,1/16W,EMPA",2.2K,5%,R0402,17278.65,1730.72,180.000,NO
R3242,"Q_RES_0402LF-2.2K,5%,1/16W,EMPA",2.2K,5%,R0402,4304.64,1240.15,0.000,NO
R3243,"Q_RES_0402LF-2.2K,5%,1/16W,EMPA",2.2K,5%,R0402,4304.64,1285.15,0.000,NO
R3244,"Q_RES_0402LF-0,5%,1/16W,CHIP,CA",0,5%,R0402,7993.90,3080.62,180.000,YES
R3249,"Q_RES_0402LF-10K,1%,1/16W,CHIPA",10K,1%,R0402,6332.20,4628.62,0.000,NO
R3254,"Q_RES_0402LF-0,5%,1/16W,EMPTY,A",0,5%,R0402,5170.20,848.62,90.000,NO
R3263,"Q_RES_0402LF-0,5%,1/16W,CHIP,CA",0,5%,R0402,17733.75,1699.03,0.000,NO
R3264,"Q_RES_0402LF-0,5%,1/16W,CHIP,CA",0,5%,R0402,3871.60,1328.22,180.000,NO
R3265,"Q_RES_0402LF-4.7K,1%,1/16W,EMPA",4.7K,1%,R0402,1087.74,15245.94,0.000,NO
R3266,"Q_RES_0402LF-4.7K,1%,1/16W,CHIA",4.7K,1%,R0402,607.74,15200.94,0.000,NO
R3267,"Q_RES_0402LF-68K,1%,1/16W,EMPTA",68K,1%,R0402,1087.74,15445.94,0.000,NO
R3268,"Q_RES_0402LF-68K,1%,1/16W,EMPTA",68K,1%,R0402,607.74,15560.94,180.000,NO
R3269,"Q_RES_0402LF-1K,1%,1/16W,EMPTYA",1K,1%,R0402,1087.74,15525.94,180.000,NO
R3270,"Q_RES_0402LF-1K,1%,1/16W,EMPTYA",1K,1%,R0402,1087.74,15485.94,0.000,NO
R3271,"Q_RES_0402LF-1K,1%,1/16W,EMPTYA",1K,1%,R0402,607.74,15600.94,0.000,NO
R3272,"Q_RES_0402LF-1K,1%,1/16W,EMPTYA",1K,1%,R0402,607.74,15520.94,180.000,NO
R3273,"Q_RES_0402LF-68K,1%,1/16W,EMPTA",68K,1%,R0402,607.74,15440.94,180.000,NO
R3274,"Q_RES_0402LF-68K,1%,1/16W,EMPTA",68K,1%,R0402,880.48,15729.61,90.000,NO
R3275,"Q_RES_0402LF-1K,1%,1/16W,EMPTYA",1K,1%,R0402,607.74,15400.94,0.000,NO
R3276,"Q_RES_0402LF-1K,1%,1/16W,EMPTYA",1K,1%,R0402,607.74,15480.94,180.000,NO
R3277,"Q_RES_0402LF-1K,1%,1/16W,EMPTYA",1K,1%,R0402,875.00,15630.94,270.000,NO
R3278,"Q_RES_0402LF-1K,1%,1/16W,CHIP,A",1K,1%,R0402,840.48,15729.61,90.000,NO
R3279,"Q_RES_0402LF-68K,1%,1/16W,EMPTA",68K,1%,R0402,1087.74,15645.94,0.000,NO
R3280,"Q_RES_0402LF-1K,1%,1/16W,EMPTYA",1K,1%,R0402,1087.74,15565.94,180.000,NO
R3281,"Q_RES_0402LF-1K,1%,1/16W,EMPTYA",1K,1%,R0402,1087.74,15605.94,0.000,NO
R3282,"Q_RES_0402LF-68K,1%,1/16W,EMPTA",68K,1%,R0402,962.51,15729.61,90.000,NO
R3283,"Q_RES_0402LF-1K,1%,1/16W,EMPTYA",1K,1%,R0402,915.00,15630.94,270.000,NO
R3284,"Q_RES_0402LF-1K,1%,1/16W,CHIP,A",1K,1%,R0402,922.51,15729.61,90.000,NO
R3285,"Q_RES_0402LF-68K,1%,1/16W,EMPTA",68K,1%,R0402,1087.74,15365.94,0.000,NO
R3286,"Q_RES_0402LF-1K,1%,1/16W,EMPTYA",1K,1%,R0402,1087.74,15326.94,180.000,NO
R3287,"Q_RES_0402LF-1K,1%,1/16W,EMPTYA",1K,1%,R0402,1087.74,15405.94,0.000,NO
R3288,"Q_RES_0402LF-68K,1%,1/16W,EMPTA",68K,1%,R0402,607.74,15281.94,180.000,NO
R3289,"Q_RES_0402LF-1K,1%,1/16W,EMPTYA",1K,1%,R0402,607.74,15360.94,0.000,NO
R3290,"Q_RES_0402LF-1K,1%,1/16W,EMPTYA",1K,1%,R0402,607.74,15320.94,180.000,NO
R3291,"Q_RES_0402LF-4.7K,1%,1/16W,EMPA",4.7K,1%,R0402,844.74,15215.94,270.000,NO
R3292,"Q_RES_0402LF-4.7K,1%,1/16W,CHIA",4.7K,1%,R0402,1087.74,15285.94,180.000,NO
R3293,"Q_RES_0402LF-4.7K,1%,1/16W,EMPA",4.7K,1%,R0402,607.74,15240.94,180.000,NO
R3294,"Q_RES_0402LF-0,5%,1/16W,CHIP,CA",0,5%,R0402,5607.20,1671.12,0.000,NO
R3295,"Q_RES_0402LF-4.7K,1%,1/16W,CHIA",4.7K,1%,R0402,5722.20,1671.12,0.000,NO
R3296,"Q_RES_0402LF-4.7K,1%,1/16W,CHIA",4.7K,1%,R0402,5512.20,1718.62,180.000,NO
R3297,"Q_RES_0402LF-10K,1%,1/16W,CHIPA",10K,1%,R0402,6032.20,1646.12,0.000,NO
R3298,"Q_RES_0402LF-10K,1%,1/16W,CHIPA",10K,1%,R0402,5512.20,1848.62,180.000,NO
R3301,"Q_RES_0402LF-33.2,1%,1/16W,CHIA",33.2,1%,R0402,6477.20,1618.62,0.000,NO
R3302,"Q_RES_0402LF-0,5%,1/16W,EMPTY,A",0,5%,R0402,5122.20,848.62,90.000,NO
R3303,"Q_RES_0402LF-0,5%,1/16W,CHIP,CA",0,5%,R0402,5808.50,1576.84,180.000,NO
R3304,"Q_RES_0402LF-0,5%,1/16W,CHIP,CA",0,5%,R0402,5938.20,1363.14,180.000,NO
R3305,"Q_RES_0402LF-0,5%,1/16W,CHIP,CA",0,5%,R0402,5938.20,1253.14,180.000,NO
R3306,"Q_RES_0402LF-0,5%,1/16W,CHIP,CA",0,5%,R0402,5539.70,1377.74,180.000,NO
R3307,"Q_RES_0402LF-0,5%,1/16W,CHIP,CA",0,5%,R0402,5539.70,1277.88,180.000,NO
R3308,"Q_RES_0402LF-0,5%,1/16W,CHIP,CA",0,5%,R0402,5539.70,1538.78,180.000,NO
R3315,"Q_RES_0402LF-49.9,1%,1/16W,CHIA",49.9,1%,R0402,4739.30,16512.42,0.000,NO
R3317,"Q_RES_0402LF-4.7K,5%,1/16W,EMPA",4.7K,5%,R0402,4739.30,16472.42,180.000,NO
R3318,"Q_RES_0402LF-100K,1%,1/16W,EMPA",100K,1%,R0402,856.38,15898.72,0.000,NO
R3320,"Q_RES_0402LF-4.7K,5%,1/16W,CHIA",4.7K,5%,R0402,1210.58,15893.52,180.000,NO
R3321,"Q_RES_0402LF-4.7K,5%,1/16W,CHIA",4.7K,5%,R0402,946.88,15818.52,0.000,NO
R3322,"Q_RES_0402LF-4.7K,1%,1/16W,CHIA",4.7K,1%,R0402,4573.21,1498.64,0.000,NO
R3324,"Q_RES_0402LF-33.2,1%,1/16W,CHIA",33.2,1%,R0402,6482.20,4678.62,0.000,NO
R3325,"Q_RES_0402LF-10K,1%,1/16W,CHIPA",10K,1%,R0402,13289.46,1327.80,90.000,YES
R3326,"Q_RES_0402LF-0,5%,1/16W,CHIP,CA",0,5%,R0402,4573.21,1548.64,0.000,NO
R3327,"Q_RES_0402LF-0,5%,1/16W,CHIP,CA",0,5%,R0402,4483.21,1498.64,0.000,NO
R3335,"Q_RES_0402LF-0,5%,1/16W,CHIP,CA",0,5%,R0402,9064.89,9928.34,180.000,NO
R3336,"Q_RES_0402LF-0,5%,1/16W,CHIP,CA",0,5%,R0402,9064.89,9889.34,180.000,NO
R3337,"Q_RES_0402LF-0,5%,1/16W,CHIP,CA",0,5%,R0402,9064.89,9751.34,180.000,NO
R3338,"Q_RES_0402LF-0,5%,1/16W,CHIP,CA",0,5%,R0402,9064.89,9712.34,180.000,NO
R3340,"Q_RES_0402LF-33.2,1%,1/16W,CHIA",33.2,1%,R0402,9718.50,3809.52,0.000,YES
R3341,"Q_RES_0402LF-33.2,1%,1/16W,CHIA",33.2,1%,R0402,9272.20,10083.62,270.000,NO
R3344,"Q_RES_0603LF-1,1%,1/10W,CHIP,CA",1,1%,R0603_H24,7192.20,3998.62,180.000,YES
R3345,"Q_RES_0603LF-1,1%,1/10W,CHIP,CA",1,1%,R0603_H24,7012.20,3998.62,180.000,YES
R3346,"Q_RES_0603LF-1,1%,1/10W,CHIP,CA",1,1%,R0603_H24,6647.20,3998.62,180.000,YES
R3347,"Q_RES_0603LF-1,1%,1/10W,CHIP,CA",1,1%,R0603_H24,7397.20,3998.62,0.000,YES
R3348,"Q_RES_0603LF-1,1%,1/10W,CHIP,CA",1,1%,R0603_H24,6862.20,4878.62,90.000,YES
R3349,"Q_RES_0603LF-1,1%,1/10W,CHIP,CA",1,1%,R0603_H24,6812.95,3998.62,180.000,YES
R3352,"Q_RES_0402LF-0,5%,1/16W,CHIP,CA",0,5%,R0402,4201.15,16368.42,180.000,NO
R3353,"Q_RES_0402LF-0,5%,1/16W,CHIP,CA",0,5%,R0402,4201.15,16328.42,180.000,NO
R3354,"Q_RES_0402LF-0,5%,1/16W,CHIP,CA",0,5%,R0402,4201.15,16286.92,180.000,NO
R3355,"Q_RES_0402LF-0,5%,1/16W,CHIP,CA",0,5%,R0402,4201.15,16246.92,180.000,NO
R3362,"Q_RES_0402LF-1K,1%,1/16W,CHIP,A",1K,1%,R0402,1813.68,15440.28,0.000,NO
R3381,"Q_RES_0402LF-1K,1%,1/16W,EMPTYA",1K,1%,R0402,1315.37,15358.55,180.000,NO
R3386,"Q_RES_0402LF-1K,1%,1/16W,CHIP,A",1K,1%,R0402,1178.35,15419.35,0.000,NO
R3390,"Q_RES_0402LF-49.9,1%,1/16W,CHIA",49.9,1%,R0402,6702.20,17243.62,0.000,NO
R3391,"Q_RES_0402LF-49.9,1%,1/16W,CHIA",49.9,1%,R0402,1232.20,16743.62,0.000,NO
R3392,"Q_RES_0402LF-49.9,1%,1/16W,CHIA",49.9,1%,R0402,6702.20,17163.62,0.000,NO
R3393,"Q_RES_0402LF-0,5%,1/16W,CHIP,CA",0,5%,R0402,4468.28,5214.83,180.000,NO
R3394,"Q_RES_0402LF-0,5%,1/16W,CHIP,CA",0,5%,R0402,4468.28,5254.83,180.000,NO
R3395,"Q_RES_0402LF-2.2K,5%,1/16W,CHIA",2.2K,5%,R0402,5175.86,5279.69,180.000,NO
R3396,"Q_RES_0402LF-2.2K,5%,1/16W,CHIA",2.2K,5%,R0402,5175.86,5224.69,180.000,NO
R3397,"Q_RES_0402LF-33.2,1%,1/16W,CHIA",33.2,1%,R0402,4009.21,15378.10,180.000,NO
R3428,"Q_RES_0402LF-100K,1%,1/16W,EMPA",100K,1%,R0402,947.63,16058.67,180.000,NO
R3429,"Q_RES_0402LF-100K,1%,1/16W,EMPA",100K,1%,R0402,6670.93,16555.57,0.000,NO
R3430,"Q_RES_0402LF-100K,1%,1/16W,EMPA",100K,1%,R0402,16701.73,15655.57,180.000,NO
R3431,"Q_RES_0402LF-100K,1%,1/16W,EMPA",100K,1%,R0402,6931.47,16326.67,0.000,NO
R3432,"Q_RES_0402LF-4.7K,5%,1/16W,CHIA",4.7K,5%,R0402,1258.38,16043.67,180.000,NO
R3433,"Q_RES_0402LF-4.7K,5%,1/16W,CHIA",4.7K,5%,R0402,6932.32,16488.43,0.000,NO
R3434,"Q_RES_0402LF-4.7K,5%,1/16W,CHIA",4.7K,5%,R0402,6670.72,16426.67,0.000,NO
R3435,"Q_RES_0402LF-4.7K,5%,1/16W,CHIA",4.7K,5%,R0402,17010.28,15640.57,180.000,NO
R3436,"Q_RES_0402LF-4.7K,5%,1/16W,CHIA",4.7K,5%,R0402,6932.22,16406.67,180.000,NO
R3437,"Q_RES_0402LF-4.7K,5%,1/16W,CHIA",4.7K,5%,R0402,16700.98,15575.57,0.000,NO
R3438,"Q_RES_0402LF-4.7K,5%,1/16W,CHIA",4.7K,5%,R0402,6670.18,16515.57,0.000,NO
R3439,"Q_RES_0402LF-4.7K,5%,1/16W,CHIA",4.7K,5%,R0402,946.88,15978.67,0.000,NO
R3440,"Q_RES_0402LF-0,5%,1/16W,EMPTY,A",0,5%,R0402,818.33,16851.34,90.000,NO
R3441,"Q_RES_0402LF-0,5%,1/16W,CHIP,CA",0,5%,R0402,778.33,16851.34,90.000,NO
R3442,"Q_RES_0402LF-0,5%,1/16W,CHIP,CA",0,5%,R0402,738.33,16852.34,90.000,NO
R3443,"Q_RES_0402LF-0,5%,1/16W,CHIP,CA",0,5%,R0402,698.33,16851.34,90.000,NO
R3448,"Q_RES_0402LF-4.7K,5%,1/16W,EMPA",4.7K,5%,R0402,6437.20,17223.62,0.000,NO
R3449,"Q_RES_0402LF-100K,1%,1/16W,CHIA",100K,1%,R0402,6437.20,17263.62,180.000,NO
R3451,"Q_RES_0402LF-4.7K,5%,1/16W,EMPA",4.7K,5%,R0402,6437.20,17183.62,0.000,NO
R3452,"Q_RES_0402LF-100K,1%,1/16W,CHIA",100K,1%,R0402,6437.20,17143.62,180.000,NO
R3453,"Q_RES_0402LF-100K,1%,1/16W,EMPA",100K,1%,R0402,6702.20,17283.62,180.000,NO
R3454,"Q_RES_0402LF-1K,1%,1/16W,CHIP,A",1K,1%,R0402,6702.20,17323.62,0.000,NO
R3455,"Q_RES_0402LF-10K,1%,1/16W,CHIPA",10K,1%,R0402,1232.20,16703.62,0.000,NO
R3456,"Q_RES_0402LF-100K,1%,1/16W,EMPA",100K,1%,R0402,6702.20,17123.62,180.000,NO
R3457,"Q_RES_0402LF-10K,1%,1/16W,CHIPA",10K,1%,R0402,6702.20,17083.62,0.000,NO
R3458,"Q_RES_0603LF-1,1%,1/10W,CHIP,CA",1,1%,R0603_H24,7072.20,4933.62,0.000,YES
R3459,"Q_RES_0402LF-4.7K,5%,1/16W,CHIA",4.7K,5%,R0402,4314.21,15478.10,180.000,NO
R3460,"Q_RES_0402LF-100K,1%,1/16W,EMPA",100K,1%,R0402,4314.21,15438.10,0.000,NO
R3461,"Q_RES_0402LF-54.9K,1%,1/16W,CHA",54.9K,1%,R0402,4009.21,15418.10,0.000,NO
R3462,"Q_RES_0402LF-100K,1%,1/16W,EMPA",100K,1%,R0402,4009.21,15458.10,180.000,NO
R3463,"Q_RES_0402LF-54.9K,1%,1/16W,CHA",54.9K,1%,R0402,6670.93,16595.57,180.000,NO
R3464,"Q_RES_0402LF-54.9K,1%,1/16W,CHA",54.9K,1%,R0402,16701.73,15615.57,0.000,NO
R3465,"Q_RES_0402LF-10K,1%,1/16W,CHIPA",10K,1%,R0402,6931.47,16366.67,180.000,NO
R3466,"Q_RES_0402LF-10K,1%,1/16W,CHIPA",10K,1%,R0402,1232.20,17083.62,0.000,NO
R3467,"Q_RES_0402LF-10K,1%,1/16W,CHIPA",10K,1%,R0402,1232.20,16883.62,0.000,NO
R3468,"Q_RES_0402LF-49.9,1%,1/16W,CHIA",49.9,1%,R0402,1232.20,17043.62,0.000,NO
R3469,"Q_RES_0402LF-49.9,1%,1/16W,CHIA",49.9,1%,R0402,1232.20,16783.62,0.000,NO
R3470,"Q_RES_0402LF-10K,1%,1/16W,EMPTA",10K,1%,R0402,16701.73,15813.21,0.000,NO
R3471,"Q_RES_0402LF-10K,1%,1/16W,CHIPA",10K,1%,R0402,16701.73,15853.21,180.000,NO
R3472,"Q_RES_0402LF-0,5%,1/16W,EMPTY,A",0,5%,R0402,17017.48,15838.21,180.000,NO
R3473,"Q_RES_0402LF-100K,1%,1/16W,EMPA",100K,1%,R0402,947.63,16238.21,180.000,NO
R3474,"Q_RES_0402LF-4.7K,5%,1/16W,CHIA",4.7K,5%,R0402,1265.58,16223.21,180.000,NO
R3475,"Q_RES_0402LF-4.7K,5%,1/16W,CHIA",4.7K,5%,R0402,1049.00,16104.00,90.000,NO
R3476,"Q_RES_0402LF-33.2,1%,1/16W,CHIA",33.2,1%,R0402,6332.20,4418.62,0.000,NO
R3477,"Q_RES_0402LF-33.2,1%,1/16W,CHIA",33.2,1%,R0402,6482.20,4418.62,0.000,NO
R3478,"Q_RES_0402LF-33.2,1%,1/16W,CHIA",33.2,1%,R0402,6182.20,4528.62,180.000,YES
R3479,"Q_RES_0402LF-33.2,1%,1/16W,CHIA",33.2,1%,R0402,6182.20,4428.62,180.000,YES
R3480,"Q_RES_0402LF-33.2,1%,1/16W,CHIA",33.2,1%,R0402,6182.20,4578.62,180.000,YES
R3481,"Q_RES_0402LF-33.2,1%,1/16W,CHIA",33.2,1%,R0402,6182.20,4428.62,0.000,NO
R3482,"Q_RES_0402LF-33.2,1%,1/16W,CHIA",33.2,1%,R0402,6182.20,4578.62,0.000,NO
R3483,"Q_RES_0402LF-33.2,1%,1/16W,CHIA",33.2,1%,R0402,6332.20,4528.62,0.000,NO
R3484,"Q_RES_0402LF-33.2,1%,1/16W,CHIA",33.2,1%,R0402,6332.20,4478.62,0.000,NO
R3485,"Q_RES_0402LF-33.2,1%,1/16W,CHIA",33.2,1%,R0402,6482.20,4478.62,0.000,NO
R3486,"Q_RES_0402LF-33.2,1%,1/16W,CHIA",33.2,1%,R0402,6482.20,4478.62,180.000,YES
R3487,"Q_RES_0402LF-10K,1%,1/16W,CHIPA",10K,1%,R0402,947.63,16198.21,0.000,NO
R3488,"Q_RES_0402LF-4.7K,5%,1/16W,CHIA",4.7K,5%,R0402,4314.21,15518.10,180.000,NO
R3489,"Q_RES_0402LF-100K,1%,1/16W,EMPA",100K,1%,R0402,4314.21,15558.10,0.000,NO
R3490,"Q_RES_0402LF-4.7K,5%,1/16W,CHIA",4.7K,5%,R0402,4285.45,15794.66,0.000,NO
R3491,"Q_RES_0402LF-100K,1%,1/16W,EMPA",100K,1%,R0402,4285.45,15834.66,180.000,NO
R3492,"Q_RES_0402LF-54.9K,1%,1/16W,CHA",54.9K,1%,R0402,4009.21,15568.10,0.000,NO
R3493,"Q_RES_0402LF-100K,1%,1/16W,EMPA",100K,1%,R0402,4009.21,15608.10,180.000,NO
R3494,"Q_RES_0402LF-54.9K,1%,1/16W,CHA",54.9K,1%,R0402,4373.83,15986.54,270.000,NO
R3495,"Q_RES_0402LF-100K,1%,1/16W,EMPA",100K,1%,R0402,4333.83,15986.54,90.000,NO
R3496,"Q_RES_0402LF-33.2,1%,1/16W,CHIA",33.2,1%,R0402,4009.21,15648.10,180.000,NO
R3497,"Q_RES_0402LF-33.2,1%,1/16W,CHIA",33.2,1%,R0402,4293.83,15986.54,90.000,NO
R3498,"Q_RES_0402LF-54.9K,1%,1/16W,CHA",54.9K,1%,R0402,947.63,16018.67,0.000,NO
R3499,"Q_RES_0402LF-0,5%,1/16W,CHIP,CA",0,5%,R0402,778.33,16678.34,270.000,NO
R3500,"Q_RES_0402LF-4.7K,5%,1/16W,CHIA",4.7K,5%,R0402,17733.75,1784.03,180.000,NO
R3501,"Q_RES_0402LF-4.7K,5%,1/16W,CHIA",4.7K,5%,R0402,17733.75,1739.03,180.000,NO
R3502,"Q_RES_0402LF-100K,1%,1/16W,EMPA",100K,1%,R0402,3745.09,16841.59,90.000,NO
R3503,"Q_RES_0402LF-4.7K,5%,1/16W,CHIA",4.7K,5%,R0402,3743.91,16524.51,90.000,NO
R3504,"Q_RES_0402LF-4.7K,5%,1/16W,CHIA",4.7K,5%,R0402,947.63,16158.21,0.000,NO
R3505,"Q_RES_0402LF-33.2,1%,1/16W,CHIA",33.2,1%,R0402,6482.20,4528.62,180.000,YES
R3506,"Q_RES_0402LF-4.7K,5%,1/16W,EMPA",4.7K,5%,R0402,4738.60,16814.62,180.000,NO
R3507,"Q_RES_0402LF-10K,1%,1/16W,CHIPA",10K,1%,R0402,4738.60,16854.62,0.000,NO
R3508,"Q_RES_0402LF-54.9K,1%,1/16W,CHA",54.9K,1%,R0402,4739.30,16672.42,0.000,NO
R3509,"Q_RES_0402LF-10K,1%,1/16W,CHIPA",10K,1%,R0402,4739.30,16432.42,0.000,NO
R3510,"Q_RES_0402LF-54.9K,1%,1/16W,CHA",54.9K,1%,R0402,4600.20,15764.37,270.000,NO
R3511,"Q_RES_0402LF-54.9K,1%,1/16W,CHA",54.9K,1%,R0402,946.88,15898.52,180.000,NO
R3512,"Q_RES_0402LF-100K,1%,1/16W,EMPA",100K,1%,R0402,946.73,16423.62,0.000,NO
R3513,"Q_RES_0402LF-54.9K,1%,1/16W,CHA",54.9K,1%,R0402,946.73,16383.62,180.000,NO
R3514,"Q_RES_0402LF-54.9K,1%,1/16W,CHA",54.9K,1%,R0402,4460.20,15664.37,270.000,NO
R3515,"Q_RES_0402LF-49.9,1%,1/16W,CHIA",49.9,1%,R0402,1232.20,17003.62,0.000,NO
R3516,"Q_RES_0402LF-0,5%,1/16W,CHIP,CA",0,5%,R0402,818.33,16678.34,270.000,NO
R3517,"Q_RES_0402LF-0,5%,1/16W,CHIP,CA",0,5%,R0402,698.33,16678.34,270.000,NO
R3518,"Q_RES_0402LF-0,5%,1/16W,CHIP,CA",0,5%,R0402,738.33,16678.34,270.000,NO
R3519,"Q_RES_0402LF-4.7K,5%,1/16W,CHIA",4.7K,5%,R0402,3871.60,1243.22,0.000,NO
R3520,"Q_RES_0402LF-4.7K,5%,1/16W,CHIA",4.7K,5%,R0402,3870.75,1284.91,0.000,NO
R3521,"Q_RES_0402LF-54.9K,1%,1/16W,CHA",54.9K,1%,R0402,1835.67,17290.92,180.000,NO
R3522,"Q_RES_0402LF-54.9K,1%,1/16W,CHA",54.9K,1%,R0402,1290.57,17271.82,0.000,NO
R3523,"Q_RES_0402LF-54.9K,1%,1/16W,CHA",54.9K,1%,R0402,1497.20,17123.62,0.000,NO
R3524,"Q_RES_0402LF-54.9K,1%,1/16W,CHA",54.9K,1%,R0402,2066.18,17140.17,180.000,NO
R3525,"Q_RES_0402LF-54.9K,1%,1/16W,CHA",54.9K,1%,R0402,3785.09,16841.59,270.000,NO
R3526,"Q_RES_0402LF-0,5%,1/16W,CHIP,CA",0,5%,R0402,4468.28,5054.83,180.000,NO
R3527,"Q_RES_0402LF-0,5%,1/16W,CHIP,CA",0,5%,R0402,4468.28,5094.83,180.000,NO
R3529,"Q_RES_0402LF-10K,1%,1/16W,CHIPA",10K,1%,R0402,8297.20,1668.62,0.000,NO
R3530,"Q_RES_0402LF-4.7K,5%,1/16W,CHIA",4.7K,5%,R0402,8727.20,1713.62,180.000,NO
R3531,"Q_RES_0402LF-200K,1%,1/16W,EMPA",200K,1%,R0402,8297.20,1763.62,0.000,NO
R3532,"Q_RES_0402LF-4.7K,5%,1/16W,CHIA",4.7K,5%,R0402,8727.20,1768.62,180.000,NO
R3533,"Q_RES_0402LF-33.2,1%,1/16W,CHIA",33.2,1%,R0402,8807.20,1713.62,0.000,NO
R3534,"Q_RES_0402LF-33.2,1%,1/16W,CHIA",33.2,1%,R0402,8807.20,1768.62,0.000,NO
R3535,"Q_RES_0402LF-2.2K,5%,1/16W,CHIA",2.2K,5%,R0402,4383.18,4987.33,0.000,NO
R3536,"Q_RES_0402LF-2.2K,5%,1/16W,CHIA",2.2K,5%,R0402,4383.18,5042.33,0.000,NO
R3553,"Q_RES_0402LF-33.2,1%,1/16W,CHIA",33.2,1%,R0402,4213.37,626.65,0.000,NO
R3554,"Q_RES_0402LF-33.2,1%,1/16W,CHIA",33.2,1%,R0402,4213.37,674.65,0.000,NO
R3559,"Q_RES_0402LF-0,5%,1/16W,CHIP,CA",0,5%,R0402,2685.53,1472.03,180.000,NO
R3560,"Q_RES_0402LF-0,5%,1/16W,CHIP,CA",0,5%,R0402,5834.56,1943.78,180.000,NO
R3561,"Q_RES_0402LF-0,5%,1/16W,CHIP,CA",0,5%,R0402,8351.14,1191.98,270.000,NO
R3563,"Q_RES_0402LF-0,5%,1/16W,CHIP,CA",0,5%,R0402,17527.20,3724.52,0.000,NO
R3568,"Q_RES_0402LF-33.2,1%,1/16W,CHIA",33.2,1%,R0402,2853.00,1369.62,180.000,NO
R3569,"Q_RES_0402LF-33.2,1%,1/16W,CHIA",33.2,1%,R0402,2784.00,1369.62,0.000,NO
R3570,"Q_RES_0402LF-10,1%,1/16W,CHIP,A",10,1%,R0402,3037.11,1812.79,0.000,YES
R3571,"Q_RES_0402LF-10,1%,1/16W,CHIP,A",10,1%,R0402,3037.11,1772.79,0.000,YES
R3572,"Q_RES_0402LF-33.2,1%,1/16W,CHIA",33.2,1%,R0402,5997.20,1888.62,90.000,NO
R3573,"Q_RES_0402LF-33.2,1%,1/16W,CHIA",33.2,1%,R0402,5932.20,1888.62,90.000,NO
R3574,"Q_RES_0402LF-10,1%,1/16W,CHIP,A",10,1%,R0402,6270.36,2120.76,180.000,NO
R3575,"Q_RES_0402LF-10,1%,1/16W,CHIP,A",10,1%,R0402,6270.36,2080.76,180.000,NO
R3576,"Q_RES_0402LF-33.2,1%,1/16W,CHIA",33.2,1%,R0402,8407.20,1358.62,180.000,NO
R3577,"Q_RES_0402LF-33.2,1%,1/16W,CHIA",33.2,1%,R0402,8407.20,1293.62,180.000,NO
R3578,"Q_RES_0402LF-10,1%,1/16W,CHIP,A",10,1%,R0402,8005.20,1442.62,180.000,YES
R3579,"Q_RES_0402LF-10,1%,1/16W,CHIP,A",10,1%,R0402,8005.20,1392.62,180.000,YES
R3580,"Q_RES_0402LF-0,5%,1/16W,CHIP,CA",0,5%,R0402,5055.18,5278.19,0.000,NO
R3581,"Q_RES_0402LF-0,5%,1/16W,CHIP,CA",0,5%,R0402,5055.18,5238.19,0.000,NO
R3582,"Q_RES_0402LF-2.2K,5%,1/16W,CHIA",2.2K,5%,R0402,4383.18,5207.33,0.000,NO
R3583,"Q_RES_0402LF-2.2K,5%,1/16W,CHIA",2.2K,5%,R0402,4383.18,5262.33,0.000,NO
R3586,"Q_RES_0402LF-33.2,1%,1/16W,CHIA",33.2,1%,R0402,8499.10,1858.12,0.000,NO
R3587,"Q_RES_0402LF-33.2,1%,1/16W,CHIA",33.2,1%,R0402,17662.20,3774.52,180.000,NO
R3588,"Q_RES_0402LF-33.2,1%,1/16W,CHIA",33.2,1%,R0402,8442.20,1863.62,90.000,NO
R3589,"Q_RES_0402LF-33.2,1%,1/16W,CHIA",33.2,1%,R0402,8402.20,1863.62,90.000,NO
R3590,"Q_RES_0402LF-33.2,1%,1/16W,CHIA",33.2,1%,R0402,2922.00,1391.62,180.000,NO
R3591,"Q_RES_0402LF-33.2,1%,1/16W,CHIA",33.2,1%,R0402,2715.00,1369.62,0.000,NO
R3592,"Q_RES_0402LF-33.2,1%,1/16W,CHIA",33.2,1%,R0402,8502.20,1358.62,180.000,NO
R3593,"Q_RES_0402LF-33.2,1%,1/16W,CHIA",33.2,1%,R0402,8502.20,1293.62,180.000,NO
R3594,"Q_RES_0402LF-33.2,1%,1/16W,CHIA",33.2,1%,R0402,5997.20,1808.62,90.000,NO
R3595,"Q_RES_0402LF-33.2,1%,1/16W,CHIA",33.2,1%,R0402,5932.20,1808.62,90.000,NO
R3600,"Q_RES_0402LF-33.2,1%,1/16W,CHIA",33.2,1%,R0402,17527.20,3829.52,180.000,NO
R3601,"Q_RES_0402LF-33.2,1%,1/16W,CHIA",33.2,1%,R0402,17527.20,3774.52,180.000,NO
R3602,"Q_RES_0402LF-10,1%,1/16W,CHIP,A",10,1%,R0402,17032.94,3697.73,0.000,NO
R3603,"Q_RES_0402LF-10,1%,1/16W,CHIP,A",10,1%,R0402,17032.94,3737.73,0.000,NO
R3608,"Q_RES_0402LF-4.7K,1%,1/16W,CHIA",4.7K,1%,R0402,2685.53,1592.03,0.000,NO
R3609,"Q_RES_0402LF-4.7K,1%,1/16W,EMPA",4.7K,1%,R0402,2685.53,1552.03,0.000,NO
R3610,"Q_RES_0402LF-4.7K,1%,1/16W,EMPA",4.7K,1%,R0402,5834.56,2103.78,0.000,NO
R3611,"Q_RES_0402LF-4.7K,1%,1/16W,CHIA",4.7K,1%,R0402,5834.56,2023.78,0.000,NO
R3612,"Q_RES_0402LF-4.7K,1%,1/16W,EMPA",4.7K,1%,R0402,8191.14,1191.98,90.000,NO
R3613,"Q_RES_0402LF-4.7K,1%,1/16W,EMPA",4.7K,1%,R0402,8311.14,1191.98,90.000,NO
R3616,"Q_RES_0402LF-4.7K,1%,1/16W,CHIA",4.7K,1%,R0402,17664.27,3641.48,180.000,NO
R3617,"Q_RES_0402LF-4.7K,1%,1/16W,EMPA",4.7K,1%,R0402,17664.27,3681.48,180.000,NO
R3620,"Q_RES_0402LF-0,5%,1/16W,CHIP,CA",0,5%,R0402,2685.53,1512.03,180.000,NO
R3621,"Q_RES_0402LF-4.7K,1%,1/16W,EMPA",4.7K,1%,R0402,5834.56,1983.78,0.000,NO
R3622,"Q_RES_0402LF-4.7K,1%,1/16W,CHIA",4.7K,1%,R0402,8271.14,1191.98,90.000,NO
R3623,"Q_RES_0402LF-4.7K,1%,1/16W,CHIA",4.7K,1%,R0402,5834.56,2063.78,0.000,NO
R3624,"Q_RES_0402LF-4.7K,1%,1/16W,CHIA",4.7K,1%,R0402,8231.14,1191.98,90.000,NO
R3627,"Q_RES_0402LF-4.7K,1%,1/16W,CHIA",4.7K,1%,R0402,17525.87,3680.48,180.000,NO
R3628,"Q_RES_0402LF-4.7K,1%,1/16W,EMPA",4.7K,1%,R0402,17525.87,3640.48,180.000,NO
R3630,"Q_RES_0402LF-0,5%,1/16W,EMPTY,A",0,5%,R0402,2757.97,1255.43,270.000,NO
R3631,"Q_RES_0402LF-0,5%,1/16W,EMPTY,A",0,5%,R0402,2702.40,2407.82,270.000,NO
R3633,"Q_RES_2512LF-0.01,1%,1W,CHIP,CA",0.01,1%,R2512,3205.61,1802.59,270.000,YES
R3634,"Q_RES_2512LF-0.01,1%,1W,CHIP,CA",0.01,1%,R2512,6402.46,2097.16,90.000,NO
R3635,"Q_RES_2512LF-0.01,1%,1W,CHIP,CA",0.01,1%,R2512,7915.26,1378.97,90.000,NO
R3636,"Q_RES_0402LF-0,5%,1/16W,CHIP,CA",0,5%,R0402,9074.20,4675.62,270.000,YES
R3637,"Q_RES_0402LF-0,5%,1/16W,CHIP,CA",0,5%,R0402,9115.20,4675.62,270.000,YES
R3638,"Q_RES_0402LF-10K,1%,1/16W,CHIPA",10K,1%,R0402,10299.22,3641.69,90.000,NO
R3639,"Q_RES_0402LF-10K,1%,1/16W,CHIPA",10K,1%,R0402,10259.58,3641.64,90.000,NO
R3640,"Q_RES_0402LF-10K,1%,1/16W,CHIPA",10K,1%,R0402,10164.70,3632.22,180.000,NO
R3641,"Q_RES_0402LF-10K,1%,1/16W,CHIPA",10K,1%,R0402,10097.38,3633.56,0.000,NO
R3642,"Q_RES_0402LF-10K,1%,1/16W,CHIPA",10K,1%,R0402,10020.00,3808.62,180.000,YES
R3643,"Q_RES_0402LF-10K,1%,1/16W,CHIPA",10K,1%,R0402,10023.10,3633.52,180.000,NO
R3645,"Q_RES_2512LF-0.01,1%,1W,CHIP,CA",0.01,1%,R2512,16961.71,3865.16,180.000,NO
R3651,"Q_RES_0402LF-0,5%,1/16W,CHIP,CA",0,5%,R0402,601.89,4123.45,90.000,NO
R3652,"Q_RES_0402LF-0,5%,1/16W,CHIP,CA",0,5%,R0402,655.33,4124.65,90.000,NO
R3653,"Q_RES_0402LF-680,1%,1/16W,CHIPA",680,1%,R0402,344.85,4010.00,180.000,NO
R3654,"Q_RES_0402LF-33.2,1%,1/16W,CHIA",33.2,1%,R0402,390.08,3649.12,90.000,NO
R3655,"Q_RES_0402LF-0,5%,1/16W,CHIP,CA",0,5%,R0402,741.69,3831.92,270.000,YES
R3656,"Q_RES_0402LF-10K,1%,1/16W,EMPTA",10K,1%,R0402,833.74,3958.65,180.000,NO
R3657,"Q_RES_0402LF-10K,1%,1/16W,EMPTA",10K,1%,R0402,833.74,3913.91,180.000,NO
R3658,"Q_RES_0402LF-10K,1%,1/16W,EMPTA",10K,1%,R0402,634.29,3649.12,90.000,NO
R3659,"Q_RES_0402LF-10K,1%,1/16W,EMPTA",10K,1%,R0402,593.22,3649.12,90.000,NO
R3660,"Q_RES_0402LF-10K,1%,1/16W,CHIPA",10K,1%,R0402,511.14,3649.12,90.000,NO
R3661,"Q_RES_0402LF-47K,0.1%,1/16W,EMA",47K,0.1%,R0402,428.09,3649.12,90.000,NO
R3662,"Q_RES_0402LF-0,5%,1/16W,CHIP,CA",0,5%,R0402,676.81,3649.12,90.000,NO
R3663,"Q_RES_0402LF-10K,1%,1/16W,CHIPA",10K,1%,R0402,833.74,3822.19,180.000,NO
R3664,"Q_RES_0402LF-10K,1%,1/16W,EMPTA",10K,1%,R0402,833.91,3760.26,0.000,NO
R3665,"Q_RES_0402LF-100K,1%,1/16W,CHIA",100K,1%,R0402,833.74,3865.02,0.000,NO
R3666,"Q_RES_0402LF-0,5%,1/16W,CHIP,CA",0,5%,R0402,551.90,3649.12,270.000,NO
R3667,"Q_RES_0402LF-1K,1%,1/16W,EMPTYA",1K,1%,R0402,794.91,4203.19,0.000,NO
R3668,"Q_RES_0402LF-1K,1%,1/16W,CHIP,A",1K,1%,R0402,898.01,4203.19,180.000,NO
R3669,"Q_RES_0402LF-1K,1%,1/16W,EMPTYA",1K,1%,R0402,794.91,4243.19,0.000,NO
R3670,"Q_RES_0402LF-1K,1%,1/16W,CHIP,A",1K,1%,R0402,898.01,4243.19,180.000,NO
R3671,"Q_RES_0402LF-0,5%,1/16W,CHIP,CA",0,5%,R0402,898.01,4425.19,0.000,NO
R3672,"Q_RES_0402LF-0,5%,1/16W,CHIP,CA",0,5%,R0402,898.01,4385.19,0.000,NO
R3679,"Q_RES_0402LF-0,5%,1/16W,EMPTY,A",0,5%,R0402,1599.51,4433.19,0.000,NO
R3680,"Q_RES_0402LF-0,5%,1/16W,CHIP,CA",0,5%,R0402,1568.01,4433.19,180.000,NO
R3681,"Q_RES_0402LF-0,5%,1/16W,EMPTY,A",0,5%,R0402,1599.51,4213.83,0.000,NO
R3682,"Q_RES_0402LF-0,5%,1/16W,CHIP,CA",0,5%,R0402,1568.01,4213.83,180.000,NO
R3683,"Q_RES_0402LF-0,5%,1/16W,EMPTY,A",0,5%,R0402,1599.51,4253.83,0.000,NO
R3684,"Q_RES_0402LF-0,5%,1/16W,CHIP,CA",0,5%,R0402,1568.01,4253.83,180.000,NO
R3685,"Q_RES_0402LF-0,5%,1/16W,EMPTY,A",0,5%,R0402,1599.51,4308.83,0.000,NO
R3686,"Q_RES_0402LF-0,5%,1/16W,CHIP,CA",0,5%,R0402,1568.01,4308.83,180.000,NO
R3687,"Q_RES_0402LF-0,5%,1/16W,EMPTY,A",0,5%,R0402,1599.51,4173.83,0.000,NO
R3688,"Q_RES_0402LF-0,5%,1/16W,CHIP,CA",0,5%,R0402,1568.01,4173.83,180.000,NO
R3689,"Q_RES_0402LF-4.7K,1%,1/16W,EMPA",4.7K,1%,R0402,898.01,4283.19,180.000,NO
R3690,"Q_RES_0402LF-4.7K,1%,1/16W,EMPA",4.7K,1%,R0402,898.01,4505.19,180.000,NO
R3703,"Q_RES_0402LF-10K,1%,1/16W,EMPTA",10K,1%,R0402,2680.84,4396.05,180.000,NO
R3704,"Q_RES_0402LF-1K,1%,1/16W,CHIP,A",1K,1%,R0402,2680.54,4437.35,0.000,NO
R3705,"Q_RES_0402LF-10K,1%,1/16W,EMPTA",10K,1%,R0402,2031.24,4587.55,0.000,NO
R3706,"Q_RES_0402LF-10K,1%,1/16W,EMPTA",10K,1%,R0402,2031.24,4627.55,0.000,NO
R3707,"Q_RES_0402LF-1K,1%,1/16W,CHIP,A",1K,1%,R0402,2135.54,4572.22,180.000,NO
R3708,"Q_RES_0402LF-10K,1%,1/16W,EMPTA",10K,1%,R0402,2031.24,4682.55,0.000,NO
R3709,"Q_RES_0402LF-1K,1%,1/16W,CHIP,A",1K,1%,R0402,2135.54,4622.35,180.000,NO
R3710,"Q_RES_0402LF-0,5%,1/16W,CHIP,CA",0,5%,R0402,2135.54,4527.35,0.000,NO
R3711,"Q_RES_0402LF-33.2,1%,1/16W,CHIA",33.2,1%,R0402,2680.54,4477.35,180.000,NO
R3712,"Q_RES_0402LF-33.2,1%,1/16W,CHIA",33.2,1%,R0402,2680.54,4517.35,180.000,NO
R3713,"Q_RES_0402LF-0,5%,1/16W,CHIP,CA",0,5%,R0402,2135.54,4447.35,180.000,NO
R3714,"Q_RES_0402LF-0,5%,1/16W,CHIP,CA",0,5%,R0402,2135.54,4487.35,180.000,NO
R3715,"Q_RES_0402LF-0,5%,1/16W,CHIP,CA",0,5%,R0402,2135.54,4367.35,180.000,NO
R3716,"Q_RES_0402LF-0,5%,1/16W,CHIP,CA",0,5%,R0402,2135.54,4407.35,180.000,NO
R3717,"Q_RES_0402LF-0,5%,1/16W,CHIP,CA",0,5%,R0402,2135.54,4287.35,180.000,NO
R3718,"Q_RES_0402LF-0,5%,1/16W,CHIP,CA",0,5%,R0402,2135.54,4327.35,180.000,NO
R3719,"Q_RES_0402LF-0,5%,1/16W,CHIP,CA",0,5%,R0402,2135.54,4207.35,180.000,NO
R3720,"Q_RES_0402LF-0,5%,1/16W,CHIP,CA",0,5%,R0402,2135.54,4247.35,180.000,NO
R3721,"Q_RES_0402LF-0,5%,1/16W,CHIP,CA",0,5%,R0402,2680.54,4267.35,0.000,NO
R3722,"Q_RES_0402LF-0,5%,1/16W,CHIP,CA",0,5%,R0402,2680.54,4227.35,0.000,NO
R3723,"Q_RES_0402LF-2.2K,5%,1/16W,CHIA",2.2K,5%,R0402,2031.24,4477.55,0.000,NO
R3724,"Q_RES_0402LF-2.2K,5%,1/16W,CHIA",2.2K,5%,R0402,2031.24,4532.55,0.000,NO
R3725,"Q_RES_0402LF-2.2K,5%,1/16W,CHIA",2.2K,5%,R0402,2031.24,4367.55,0.000,NO
R3726,"Q_RES_0402LF-2.2K,5%,1/16W,CHIA",2.2K,5%,R0402,2031.24,4422.55,0.000,NO
R3727,"Q_RES_0402LF-2.2K,5%,1/16W,CHIA",2.2K,5%,R0402,2031.24,4257.55,0.000,NO
R3728,"Q_RES_0402LF-2.2K,5%,1/16W,CHIA",2.2K,5%,R0402,2031.24,4312.55,0.000,NO
R3729,"Q_RES_0402LF-2.2K,5%,1/16W,CHIA",2.2K,5%,R0402,2031.24,4147.55,0.000,NO
R3730,"Q_RES_0402LF-2.2K,5%,1/16W,CHIA",2.2K,5%,R0402,2031.24,4202.55,0.000,NO
R3731,"Q_RES_0402LF-2.2K,5%,1/16W,CHIA",2.2K,5%,R0402,2680.86,4310.39,0.000,NO
R3732,"Q_RES_0402LF-2.2K,5%,1/16W,CHIA",2.2K,5%,R0402,2680.36,4185.79,0.000,NO
R3751,"Q_RES_0402LF-0,5%,1/16W,CHIP,CA",0,5%,R0402,8417.20,2143.62,90.000,YES
R3752,"Q_RES_0402LF-0,5%,1/16W,CHIP,CA",0,5%,R0402,8334.45,2247.18,270.000,YES
R3754,"Q_RES_0402LF-33.2,1%,1/16W,CHIA",33.2,1%,R0402,8442.20,1993.62,90.000,NO
R3756,"Q_RES_0402LF-33.2,1%,1/16W,CHIA",33.2,1%,R0402,8402.20,1993.62,90.000,NO
R3758,"Q_RES_0402LF-10,1%,1/16W,CHIP,A",10,1%,R0402,8668.93,2277.63,180.000,NO
R3760,"Q_RES_0402LF-10,1%,1/16W,CHIP,A",10,1%,R0402,8668.93,2237.63,180.000,NO
R3763,"Q_RES_0402LF-4.7K,1%,1/16W,CHIA",4.7K,1%,R0402,8337.15,2265.68,270.000,NO
R3764,"Q_RES_0402LF-4.7K,1%,1/16W,EMPA",4.7K,1%,R0402,8442.20,2203.62,0.000,YES
R3767,"Q_RES_2512LF-0.01,1%,1W,CHIP,CA",0.01,1%,R2512,8821.83,2260.33,90.000,NO
R3770,"Q_RES_0402LF-0,5%,1/16W,CHIP,CA",0,5%,R0402,7553.59,17250.95,270.000,NO
R3771,"Q_RES_0402LF-10K,1%,1/16W,CHIPA",10K,1%,R0402,9299.25,1976.12,180.000,YES
R3772,"Q_RES_0402LF-0,5%,1/16W,CHIP,CA",0,5%,R0402,6285.64,2602.02,0.000,NO
R3773,"Q_RES_0402LF-4.7K,5%,1/16W,EMPA",4.7K,5%,R0402,6411.34,2602.02,180.000,NO
R3775,"Q_RES_0402LF-0,5%,1/16W,CHIP,CA",0,5%,R0402,5978.14,2575.32,0.000,NO
R3776,"Q_RES_0402LF-0,5%,1/16W,CHIP,CA",0,5%,R0402,5347.20,368.62,270.000,YES
R3777,"Q_RES_0402LF-0,5%,1/16W,CHIP,CA",0,5%,R0402,5297.20,368.62,270.000,YES
R3778,"Q_RES_0402LF-0,5%,1/16W,CHIP,CA",0,5%,R0402,5893.30,895.20,90.000,NO
R3779,"Q_RES_0402LF-0,5%,1/16W,CHIP,CA",0,5%,R0402,9448.35,1888.52,180.000,NO
R3783,"Q_RES_0402LF-100K,1%,1/16W,CHIA",100K,1%,R0402,16940.04,4014.85,180.000,NO
R3784,"Q_RES_0402LF-0,5%,1/16W,CHIP,CA",0,5%,R0402,18139.55,1445.20,270.000,NO
R3785,"Q_RES_0402LF-0,5%,1/16W,CHIP,CA",0,5%,R0402,16905.60,4286.12,90.000,YES
R3794,"Q_RES_0402LF-0,5%,1/16W,CHIP,CA",0,5%,R0402,16885.04,4030.60,270.000,NO
R3796,"Q_RES_0402LF-100K,1%,1/16W,CHIA",100K,1%,R0402,17013.84,4014.85,0.000,NO
R3797,"Q_RES_0402LF-100K,1%,1/16W,CHIA",100K,1%,R0402,17907.38,764.87,270.000,NO
R3799,"Q_RES_0402LF-100K,1%,1/16W,CHIA",100K,1%,R0402,17907.38,838.67,90.000,NO
R3807,"Q_RES_0402LF-0,5%,1/16W,CHIP,CA",0,5%,R0402,3181.58,2299.87,90.000,YES
R3816,"Q_RES_0402LF-100K,1%,1/16W,CHIA",100K,1%,R0402,3256.17,827.43,90.000,NO
R3825,"Q_RES_0402LF-100K,1%,1/16W,CHIA",100K,1%,R0402,3256.17,753.63,270.000,NO
R3826,"Q_RES_0402LF-100K,1%,1/16W,CHIA",100K,1%,R0402,3218.45,2050.49,0.000,YES
R3827,"Q_RES_0402LF-0,5%,1/16W,CHIP,CA",0,5%,R0402,2601.00,1554.62,90.000,NO
R3831,"Q_RES_0402LF-0,5%,1/16W,CHIP,CA",0,5%,R0402,3240.42,698.63,0.000,NO
R3832,"Q_RES_0402LF-0,5%,1/16W,CHIP,CA",0,5%,R0402,3163.45,2066.24,90.000,YES
R3833,"Q_RES_0402LF-100K,1%,1/16W,CHIA",100K,1%,R0402,3292.25,2050.49,180.000,YES
R3834,"Q_RES_0402LF-0,5%,1/16W,EMPTY,A",0,5%,R0402,17509.18,1266.67,270.000,NO
R3836,"Q_RES_0402LF-10K,1%,1/16W,EMPTA",10K,1%,R0402,6819.53,1158.68,0.000,NO
R3845,"Q_RES_0402LF-0,5%,1/16W,EMPTY,A",0,5%,R0402,16541.10,4302.02,270.000,NO
R3848,"Q_RES_0402LF-10K,1%,1/16W,EMPTA",10K,1%,R0402,2487.97,1117.43,0.000,NO
R3858,"Q_RES_0402LF-33.2,1%,1/16W,CHIA",33.2,1%,R0402,6780.50,541.82,90.000,YES
R3859,"Q_RES_0402LF-0,5%,1/16W,EMPTY,A",0,5%,R0402,1123.32,3880.71,0.000,NO
R3860,"Q_RES_0402LF-0,5%,1/16W,EMPTY,A",0,5%,R0402,1154.82,3880.71,180.000,NO
R3861,"Q_RES_0402LF-0,5%,1/16W,CHIP,CA",0,5%,R0402,1568.01,4353.83,0.000,NO
R3862,"Q_RES_0402LF-0,5%,1/16W,EMPTY,A",0,5%,R0402,1599.51,4353.83,180.000,NO
R3863,"Q_RES_0402LF-0,5%,1/16W,EMPTY,A",0,5%,R0402,1123.32,3920.71,0.000,NO
R3864,"Q_RES_0402LF-0,5%,1/16W,EMPTY,A",0,5%,R0402,1154.82,3920.71,180.000,NO
R3865,"Q_RES_0402LF-0,5%,1/16W,CHIP,CA",0,5%,R0402,1599.51,4393.97,180.000,NO
R3866,"Q_RES_0402LF-0,5%,1/16W,EMPTY,A",0,5%,R0402,1568.01,4393.97,0.000,NO
R3867,"Q_RES_0402LF-0,5%,1/16W,EMPTY,A",0,5%,R0402,2382.97,1255.43,270.000,NO
R3868,"Q_RES_0402LF-0,5%,1/16W,CHIP,CA",0,5%,R0402,2367.22,1271.18,180.000,NO
R3869,"Q_RES_0402LF-0,5%,1/16W,EMPTY,A",0,5%,R0402,17134.18,1266.67,270.000,NO
R3870,"Q_RES_0402LF-0,5%,1/16W,CHIP,CA",0,5%,R0402,17118.43,1282.42,180.000,NO
R3871,"Q_RES_0402LF-0,5%,1/16W,EMPTY,A",0,5%,R0402,17214.18,1266.67,90.000,NO
R3872,"Q_RES_0402LF-0,5%,1/16W,EMPTY,A",0,5%,R0402,17174.18,1266.67,90.000,NO
R3873,"Q_RES_0402LF-0,5%,1/16W,EMPTY,A",0,5%,R0402,2462.97,1255.43,90.000,NO
R3874,"Q_RES_0402LF-0,5%,1/16W,EMPTY,A",0,5%,R0402,2422.97,1255.43,90.000,NO
R3875,"Q_RES_0402LF-49.9,1%,1/16W,CHIA",49.9,1%,R0402,11795.63,12489.91,90.000,YES
R3876,"Q_RES_0402LF-49.9,1%,1/16W,CHIA",49.9,1%,R0402,12015.00,12486.59,45.000,YES
R3877,"Q_RES_0402LF-49.9,1%,1/16W,CHIA",49.9,1%,R0402,11334.61,12514.83,180.000,YES
R3878,"Q_RES_0402LF-49.9,1%,1/16W,CHIA",49.9,1%,R0402,11499.03,12488.34,90.000,YES
R3879,"Q_RES_0402LF-49.9,1%,1/16W,CHIA",49.9,1%,R0402,10676.41,12512.77,180.000,YES
R3880,"Q_RES_0402LF-49.9,1%,1/16W,CHIA",49.9,1%,R0402,10939.72,12514.09,180.000,YES
R3881,"Q_RES_0402LF-49.9,1%,1/16W,CHIA",49.9,1%,R0402,10082.35,12538.69,180.000,YES
R3882,"Q_RES_0402LF-49.9,1%,1/16W,CHIA",49.9,1%,R0402,10304.55,12515.03,180.000,YES
R3883,"Q_RES_0402LF-49.9,1%,1/16W,CHIA",49.9,1%,R0402,16315.45,12465.43,90.000,YES
R3884,"Q_RES_0402LF-49.9,1%,1/16W,CHIA",49.9,1%,R0402,16026.50,12490.20,90.000,YES
R3885,"Q_RES_0402LF-49.9,1%,1/16W,CHIA",49.9,1%,R0402,16905.18,12495.80,90.000,YES
R3886,"Q_RES_0402LF-49.9,1%,1/16W,CHIA",49.9,1%,R0402,16541.43,12521.85,90.000,YES
R3887,"Q_RES_0402LF-49.9,1%,1/16W,CHIA",49.9,1%,R0402,17496.90,12468.86,90.000,YES
R3888,"Q_RES_0402LF-49.9,1%,1/16W,CHIA",49.9,1%,R0402,17201.83,12513.74,90.000,YES
R3889,"Q_RES_0402LF-49.9,1%,1/16W,CHIA",49.9,1%,R0402,18163.60,12392.61,90.000,YES
R3890,"Q_RES_0402LF-49.9,1%,1/16W,CHIA",49.9,1%,R0402,17787.89,12486.45,90.000,YES
R3891,"Q_RES_0402LF-49.9,1%,1/16W,CHIA",49.9,1%,R0402,2104.19,12449.36,0.000,YES
R3892,"Q_RES_0402LF-49.9,1%,1/16W,CHIA",49.9,1%,R0402,2278.80,12422.83,0.000,YES
R3893,"Q_RES_0402LF-49.9,1%,1/16W,CHIA",49.9,1%,R0402,1338.73,12423.53,0.000,YES
R3894,"Q_RES_0402LF-49.9,1%,1/16W,CHIA",49.9,1%,R0402,1738.65,12418.26,90.000,YES
R3895,"Q_RES_0402LF-49.9,1%,1/16W,CHIA",49.9,1%,R0402,911.23,12455.35,90.000,YES
R3896,"Q_RES_0402LF-49.9,1%,1/16W,CHIA",49.9,1%,R0402,1211.99,12504.99,180.000,YES
R3897,"Q_RES_0402LF-49.9,1%,1/16W,CHIA",49.9,1%,R0402,320.99,12529.65,180.000,YES
R3898,"Q_RES_0402LF-49.9,1%,1/16W,CHIA",49.9,1%,R0402,617.75,12464.61,90.000,YES
R3899,"Q_RES_0402LF-49.9,1%,1/16W,CHIA",49.9,1%,R0402,6541.96,12464.27,90.000,YES
R3900,"Q_RES_0402LF-49.9,1%,1/16W,CHIA",49.9,1%,R0402,6247.92,12532.93,0.000,YES
R3901,"Q_RES_0402LF-49.9,1%,1/16W,CHIA",49.9,1%,R0402,7144.27,12490.75,90.000,YES
R3902,"Q_RES_0402LF-49.9,1%,1/16W,CHIA",49.9,1%,R0402,6847.05,12499.60,90.000,YES
R3903,"Q_RES_0402LF-49.9,1%,1/16W,CHIA",49.9,1%,R0402,7725.70,12475.12,90.000,YES
R3904,"Q_RES_0402LF-49.9,1%,1/16W,CHIA",49.9,1%,R0402,7440.22,12475.07,90.000,YES
R3905,"Q_RES_0402LF-49.9,1%,1/16W,CHIA",49.9,1%,R0402,8201.10,12451.12,90.000,YES
R3906,"Q_RES_0402LF-49.9,1%,1/16W,CHIA",49.9,1%,R0402,8031.16,12456.17,90.000,YES
R3907,"Q_RES_0402LF-33K,1%,1/16W,CHIPA",33K,1%,R0402,7466.55,16783.62,180.000,NO
R3909,"Q_RES_0402LF-33.2,1%,1/16W,CHIA",33.2,1%,R0402,7201.12,16057.33,90.000,YES
R3923,"Q_RES_0402LF-63.4K,1%,1/16W,CHA",63.4K,1%,R0402,7466.55,16743.62,0.000,NO
R3924,"Q_RES_0402LF-0,5%,1/16W,CHIP,CA",0,5%,R0402,7242.52,15939.13,180.000,YES
R3925,"Q_RES_0402LF-1K,1%,1/16W,CHIP,A",1K,1%,R0402,7196.12,16041.83,90.000,NO
R3933,"Q_RES_0402LF-16.9K,1%,1/16W,CHA",16.9K,1%,R0402,7060.72,16019.63,0.000,NO
R3934,"Q_RES_0402LF-22,1%,1/16W,CHIP,A",22,1%,R0402,7561.12,15791.83,0.000,NO
R3936,"Q_RES_0402LF-4.7K,1%,1/16W,CHIA",4.7K,1%,R0402,7561.12,15772.03,180.000,YES
R3938,"Q_RES_0402LF-10K,1%,1/16W,CHIPA",10K,1%,R0402,13538.50,1386.72,270.000,YES
R3939,"Q_RES_0402LF-0,5%,1/16W,EMPTY,A",0,5%,R0402,1646.86,3927.45,270.000,YES
R3940,"Q_RES_0402LF-0,5%,1/16W,EMPTY,A",0,5%,R0402,1646.86,3958.95,90.000,YES
R3941,"Q_RES_0402LF-0,5%,1/16W,CHIP,CA",0,5%,R0402,10100.55,2182.53,180.000,YES
R3942,"Q_RES_0402LF-0,5%,1/16W,EMPTY,A",0,5%,R0402,10132.05,2182.53,0.000,YES
R3943,"Q_RES_0402LF-0,5%,1/16W,EMPTY,A",0,5%,R0402,10165.90,1901.76,180.000,NO
R3946,"Q_RES_0402LF-0,5%,1/16W,EMPTY,A",0,5%,R0402,7811.60,2748.22,180.000,NO
R3948,"Q_RES_0402LF-10K,1%,1/16W,EMPTA",10K,1%,R0402,10013.95,2159.23,270.000,NO
R3955,"Q_RES_0402LF-0,5%,1/16W,EMPTY,A",0,5%,R0402,10151.95,2224.23,0.000,NO
R3956,"Q_RES_0402LF-0,5%,1/16W,EMPTY,A",0,5%,R0402,10151.95,2184.23,0.000,NO
R3958,"Q_RES_0402LF-0,5%,1/16W,CHIP,CA",0,5%,R0402,9854.45,1770.83,90.000,YES
R3959,"Q_RES_0402LF-0,5%,1/16W,CHIP,CA",0,5%,R0402,8615.65,2692.20,180.000,YES
R3972,"Q_RES_0402LF-0,5%,1/16W,CHIP,CA",0,5%,R0402,9855.00,1497.99,270.000,NO
R3973,"Q_RES_0402LF-0,5%,1/16W,CHIP,CA",0,5%,R0402,8849.28,2674.07,0.000,NO
R3974,"Q_RES_0402LF-0,5%,1/16W,EMPTY,A",0,5%,R0402,10151.95,2264.23,180.000,NO
R3975,"Q_RES_0402LF-0,5%,1/16W,CHIP,CA",0,5%,R0402,10167.70,2279.98,90.000,NO
R3976,"Q_RES_0402LF-100K,1%,1/16W,CHIA",100K,1%,R0402,10000.00,1482.99,180.000,NO
R3977,"Q_RES_0402LF-100K,1%,1/16W,CHIA",100K,1%,R0402,8865.03,2802.87,90.000,NO
R3978,"Q_RES_0402LF-100K,1%,1/16W,CHIA",100K,1%,R0402,9930.00,1482.99,180.000,NO
R3979,"Q_RES_0402LF-100K,1%,1/16W,CHIA",100K,1%,R0402,8865.03,2729.07,270.000,NO
R3996,"Q_RES_0402LF-0,5%,1/16W,CHIP,CA",0,5%,R0402,7762.89,1580.26,0.000,NO
R3997,"Q_RES_0402LF-0,5%,1/16W,CHIP,CA",0,5%,R0402,7251.33,1607.88,180.000,NO
R3998,"Q_RES_0402LF-0,5%,1/16W,EMPTY,A",0,5%,R0402,7089.53,1296.68,270.000,NO
R4013,"Q_RES_0402LF-100K,1%,1/16W,CHIA",100K,1%,R0402,7601.93,1022.28,90.000,NO
R4015,"Q_RES_0402LF-100K,1%,1/16W,CHIA",100K,1%,R0402,7601.93,948.48,270.000,NO
R4016,"Q_RES_0402LF-4.32K,1%,1/16W,CHA",4.32K,1%,R0402,4557.20,4007.62,270.000,NO
R4019,"Q_RES_0402LF-1K,1%,1/16W,CHIP,A",1K,1%,R0402,4517.20,4097.62,90.000,NO
R4021,"Q_RES_0402LF-33.2,1%,1/16W,CHIA",33.2,1%,R0402,4390.00,3808.62,0.000,YES
R4022,"Q_RES_0402LF-33.2,1%,1/16W,CHIA",33.2,1%,R0402,4505.00,3413.62,180.000,YES
R4023,"Q_RES_0402LF-33.2,1%,1/16W,CHIA",33.2,1%,R0402,4600.00,3413.62,180.000,YES
R4029,"Q_RES_0402LF-1K,1%,1/16W,CHIP,A",1K,1%,R0402,4627.20,4007.62,90.000,NO
R4036,"Q_RES_0402LF-4.32K,1%,1/16W,CHA",4.32K,1%,R0402,4515.20,4718.37,270.000,NO
R4037,"Q_RES_0402LF-4.32K,1%,1/16W,CHA",4.32K,1%,R0402,4881.69,4716.96,270.000,NO
R4038,"Q_RES_0402LF-4.32K,1%,1/16W,CHA",4.32K,1%,R0402,5593.00,4099.07,270.000,NO
R4039,"Q_RES_0402LF-1K,1%,1/16W,CHIP,A",1K,1%,R0402,4475.20,4808.37,90.000,NO
R4040,"Q_RES_0402LF-1K,1%,1/16W,CHIP,A",1K,1%,R0402,4841.69,4806.96,90.000,NO
R4041,"Q_RES_0402LF-1K,1%,1/16W,CHIP,A",1K,1%,R0402,5593.00,4187.57,90.000,NO
R4042,"Q_RES_0402LF-33.2,1%,1/16W,CHIA",33.2,1%,R0402,4440.20,4182.62,270.000,NO
R4043,"Q_RES_0402LF-33.2,1%,1/16W,CHIA",33.2,1%,R0402,4485.20,4182.62,270.000,NO
R4044,"Q_RES_0402LF-33.2,1%,1/16W,CHIA",33.2,1%,R0402,4530.20,4182.62,270.000,NO
R4045,"Q_RES_0402LF-33.2,1%,1/16W,CHIA",33.2,1%,R0402,4575.20,4182.62,270.000,NO
R4046,"Q_RES_0402LF-33.2,1%,1/16W,CHIA",33.2,1%,R0402,4805.20,4182.62,270.000,NO
R4047,"Q_RES_0402LF-33.2,1%,1/16W,CHIA",33.2,1%,R0402,4850.20,4182.62,270.000,NO
R4048,"Q_RES_0402LF-33.2,1%,1/16W,CHIA",33.2,1%,R0402,4895.20,4182.62,270.000,NO
R4049,"Q_RES_0402LF-33.2,1%,1/16W,CHIA",33.2,1%,R0402,4940.20,4182.62,270.000,NO
R4050,"Q_RES_0402LF-33.2,1%,1/16W,CHIA",33.2,1%,R0402,5473.30,3647.42,270.000,NO
R4051,"Q_RES_0402LF-33.2,1%,1/16W,CHIA",33.2,1%,R0402,5693.40,3647.02,270.000,NO
R4052,"Q_RES_0402LF-33.2,1%,1/16W,CHIA",33.2,1%,R0402,5734.60,3647.02,270.000,NO
R4053,"Q_RES_0402LF-1K,1%,1/16W,CHIP,A",1K,1%,R0402,4665.20,4718.37,90.000,NO
R4054,"Q_RES_0402LF-1K,1%,1/16W,CHIP,A",1K,1%,R0402,5031.69,4716.96,90.000,NO
R4055,"Q_RES_0402LF-1K,1%,1/16W,CHIP,A",1K,1%,R0402,5693.00,4099.07,90.000,NO
R4056,"Q_RES_0402LF-0,5%,1/16W,CHIP,CA",0,5%,R0402,7772.20,4232.12,0.000,YES
R4057,"Q_RES_0402LF-33.2,1%,1/16W,CHIA",33.2,1%,R0402,7351.73,5263.37,270.000,NO
R4059,"Q_RES_0402LF-0,5%,1/16W,CHIP,CA",0,5%,R0402,2599.33,1453.02,90.000,NO
R4060,"Q_RES_0402LF-0,5%,1/16W,CHIP,CA",0,5%,R0402,2320.20,1541.26,0.000,NO
R4061,"Q_RES_0402LF-0,5%,1/16W,CHIP,CA",0,5%,R0402,18194.61,1523.01,90.000,NO
R4062,"Q_RES_0402LF-0,5%,1/16W,CHIP,CA",0,5%,R0402,7764.20,1632.54,180.000,NO
R4063,"Q_RES_0402LF-0,5%,1/16W,CHIP,CA",0,5%,R0402,11527.20,1848.62,90.000,NO
R4064,"Q_RES_0402LF-0,5%,1/16W,CHIP,CA",0,5%,R0402,11567.20,1848.62,90.000,NO
R4065,"Q_RES_0402LF-10K,1%,1/16W,CHIPA",10K,1%,R0402,2357.00,1420.62,180.000,NO
R4066,"Q_RES_0402LF-4.7K,5%,1/16W,CHIA",4.7K,5%,R0402,2320.20,1590.71,180.000,NO
R4067,"Q_RES_0402LF-10K,1%,1/16W,CHIPA",10K,1%,R0402,2547.56,1583.02,90.000,NO
R4068,"Q_RES_0402LF-10K,1%,1/16W,CHIPA",10K,1%,R0402,18491.91,1648.75,270.000,NO
R4069,"Q_RES_0402LF-4.7K,5%,1/16W,CHIA",4.7K,5%,R0402,18012.99,1614.65,180.000,NO
R4070,"Q_RES_0402LF-10K,1%,1/16W,CHIPA",10K,1%,R0402,18241.87,1701.62,180.000,NO
R4071,"Q_RES_0402LF-10K,1%,1/16W,CHIPA",10K,1%,R0402,7497.00,1675.37,0.000,NO
R4072,"Q_RES_0402LF-10K,1%,1/16W,CHIPA",10K,1%,R0402,11590.20,2113.70,180.000,NO
R4073,"Q_RES_0402LF-4.7K,5%,1/16W,CHIA",4.7K,5%,R0402,11607.20,1848.62,270.000,NO
R4074,"Q_RES_0402LF-10K,1%,1/16W,CHIPA",10K,1%,R0402,11503.70,2112.31,0.000,NO
R4075,"Q_RES_0402LF-0,5%,1/16W,CHIP,CA",0,5%,R0402,9217.20,10083.62,270.000,NO
R4076,"Q_RES_0402LF-0,5%,1/16W,CHIP,CA",0,5%,R0402,9169.74,9661.87,90.000,NO
R4077,"Q_RES_0402LF-1,1%,1/16W,CHIP,CA",1,1%,R0402,9193.50,9810.32,270.000,YES
R4078,"Q_RES_0402LF-10K,1%,1/16W,EMPTA",10K,1%,R0402,9268.23,9661.52,90.000,NO
R4079,"Q_RES_0402LF-10K,1%,1/16W,CHIPA",10K,1%,R0402,9314.96,9661.87,270.000,NO
R4080,"Q_RES_0402LF-10K,1%,1/16W,CHIPA",10K,1%,R0402,9217.57,9661.87,90.000,NO
R4081,"Q_RES_0402LF-10K,1%,1/16W,CHIPA",10K,1%,R0402,9473.10,9974.22,180.000,NO
R4082,"Q_RES_0402LF-10K,1%,1/16W,EMPTA",10K,1%,R0402,9597.90,9974.96,0.000,NO
R4083,"Q_RES_0402LF-0,5%,1/16W,EMPTY,A",0,5%,R0402,8828.00,1957.20,180.000,NO
R4084,"Q_RES_0402LF-0,5%,1/16W,EMPTY,A",0,5%,R0402,8828.00,2011.50,180.000,NO
R4086,"Q_RES_0402LF-10K,1%,1/16W,CHIPA",10K,1%,R0402,7614.00,4934.52,180.000,NO
R4087,"Q_RES_0402LF-33.2,1%,1/16W,CHIA",33.2,1%,R0402,5762.00,542.22,90.000,YES
R4088,"Q_RES_0402LF-0,5%,1/16W,CHIP,CA",0,5%,R0402,5815.20,542.62,90.000,YES
R4089,"Q_RES_0402LF-33.2,1%,1/16W,CHIA",33.2,1%,R0402,6133.58,9398.77,0.000,YES
R4090,"Q_RES_0402LF-4.7K,1%,1/16W,CHIA",4.7K,1%,R0402,5834.50,1900.92,0.000,NO
R4091,"Q_RES_0402LF-4.7K,1%,1/16W,CHIA",4.7K,1%,R0402,8393.60,1190.82,90.000,NO
R4092,"Q_RES_0402LF-4.7K,1%,1/16W,CHIA",4.7K,1%,R0402,2685.50,1428.92,0.000,NO
R4093,"Q_RES_0402LF-4.7K,1%,1/16W,CHIA",4.7K,1%,R0402,8375.00,2246.52,90.000,YES
R4094,"Q_RES_0402LF-4.7K,1%,1/16W,CHIA",4.7K,1%,R0402,17662.20,3724.52,180.000,NO
R4095,"Q_RES_0402LF-10K,1%,1/16W,CHIPA",10K,1%,R0402,13032.20,1090.62,90.000,YES
R4096,"Q_RES_0402LF-10K,1%,1/16W,CHIPA",10K,1%,R0402,12879.13,892.19,270.000,NO
R4097,"Q_RES_0402LF-10K,1%,1/16W,CHIPA",10K,1%,R0402,13035.20,992.62,0.000,YES
R4098,"Q_RES_0402LF-10K,1%,1/16W,CHIPA",10K,1%,R0402,12918.23,892.69,270.000,NO
R4099,"Q_RES_0402LF-10K,1%,1/16W,CHIPA",10K,1%,R0402,12745.20,828.62,270.000,NO
R4100,"Q_RES_0402LF-10K,1%,1/16W,CHIPA",10K,1%,R0402,12300.93,1531.15,180.000,NO
R4101,"Q_RES_0402LF-10K,1%,1/16W,CHIPA",10K,1%,R0402,12185.97,1489.09,180.000,NO
R4102,"Q_RES_0402LF-10K,1%,1/16W,CHIPA",10K,1%,R0402,12185.97,1449.09,180.000,NO
R4103,"Q_RES_0402LF-10K,1%,1/16W,CHIPA",10K,1%,R0402,12277.20,2058.62,0.000,YES
R4104,"Q_RES_0402LF-10K,1%,1/16W,CHIPA",10K,1%,R0402,12277.20,2178.62,0.000,YES
R4105,"Q_RES_0402LF-10K,1%,1/16W,CHIPA",10K,1%,R0402,12277.20,2138.62,0.000,YES
R4106,"Q_RES_0402LF-10K,1%,1/16W,CHIPA",10K,1%,R0402,12277.20,2098.62,0.000,YES
R4107,"Q_RES_0402LF-10K,1%,1/16W,CHIPA",10K,1%,R0402,12405.93,2054.62,0.000,YES
R4108,"Q_RES_0402LF-10K,1%,1/16W,CHIPA",10K,1%,R0402,12405.93,2094.62,0.000,YES
R4109,"Q_RES_0402LF-10K,1%,1/16W,CHIPA",10K,1%,R0402,12405.93,2134.62,0.000,YES
R4110,"Q_RES_0402LF-10K,1%,1/16W,CHIPA",10K,1%,R0402,14547.20,1658.62,180.000,YES
R4111,"Q_RES_0402LF-10K,1%,1/16W,CHIPA",10K,1%,R0402,14547.20,1618.62,180.000,YES
R4112,"Q_RES_0402LF-10K,1%,1/16W,CHIPA",10K,1%,R0402,14547.20,1533.62,180.000,YES
R4113,"Q_RES_0402LF-10K,1%,1/16W,CHIPA",10K,1%,R0402,14547.20,1778.62,180.000,YES
R4114,"Q_RES_0402LF-10K,1%,1/16W,CHIPA",10K,1%,R0402,14547.20,1818.62,180.000,YES
R4115,"Q_RES_0402LF-10K,1%,1/16W,CHIPA",10K,1%,R0402,14547.20,1578.62,180.000,YES
R4116,"Q_RES_0402LF-10K,1%,1/16W,CHIPA",10K,1%,R0402,14547.20,1738.62,180.000,YES
R4117,"Q_RES_0402LF-10K,1%,1/16W,CHIPA",10K,1%,R0402,14547.20,1493.62,180.000,YES
R4118,"Q_RES_0402LF-10,1%,1/16W,CHIP,A",10,1%,R0402,13067.63,817.75,0.000,NO
R4119,"Q_RES_0402LF-54.9K,1%,1/16W,EMA",54.9K,1%,R0402,11925.00,16594.25,90.000,NO
R4120,"Q_RES_0402LF-100K,1%,1/16W,EMPA",100K,1%,R0402,11925.00,16500.25,270.000,NO
R4121,"Q_RES_0402LF-10K,1%,1/16W,CHIPA",10K,1%,R0402,11819.30,16591.15,90.000,NO
R4122,"Q_RES_0402LF-100K,1%,1/16W,EMPA",100K,1%,R0402,11819.30,16497.15,270.000,NO
R4123,"Q_RES_0402LF-54.9K,1%,1/16W,EMA",54.9K,1%,R0402,12139.10,17052.15,90.000,NO
R4124,"Q_RES_0402LF-100K,1%,1/16W,EMPA",100K,1%,R0402,12139.10,16958.15,270.000,NO
R4125,"Q_RES_0402LF-4.7K,5%,1/16W,CHIA",4.7K,5%,R0402,11961.46,16793.59,270.000,NO
R4126,"Q_RES_0402LF-4.7K,5%,1/16W,CHIA",4.7K,5%,R0402,11855.76,16790.49,270.000,NO
R4127,"Q_RES_0402LF-4.7K,5%,1/16W,CHIA",4.7K,5%,R0402,12175.56,17251.49,270.000,NO
R4128,"Q_RES_0402LF-4.7K,5%,1/16W,CHIA",4.7K,5%,R0402,11974.00,16594.25,90.000,NO
R4129,"Q_RES_0402LF-4.7K,5%,1/16W,CHIA",4.7K,5%,R0402,11868.30,16591.15,90.000,NO
R4130,"Q_RES_0402LF-4.7K,5%,1/16W,CHIA",4.7K,5%,R0402,12188.10,17052.15,90.000,NO
R4131,"Q_RES_0402LF-54.9K,1%,1/16W,EMA",54.9K,1%,R0402,11923.40,17049.05,90.000,NO
R4132,"Q_RES_0402LF-100K,1%,1/16W,EMPA",100K,1%,R0402,11923.40,16955.05,270.000,NO
R4133,"Q_RES_0402LF-54.9K,1%,1/16W,EMA",54.9K,1%,R0402,11709.30,16591.15,90.000,NO
R4134,"Q_RES_0402LF-100K,1%,1/16W,EMPA",100K,1%,R0402,11709.30,16497.15,270.000,NO
R4135,"Q_RES_0402LF-10K,1%,1/16W,CHIPA",10K,1%,R0402,12031.10,17049.50,90.000,NO
R4136,"Q_RES_0402LF-100K,1%,1/16W,EMPA",100K,1%,R0402,12031.10,16955.50,270.000,NO
R4137,"Q_RES_0402LF-4.7K,5%,1/16W,CHIA",4.7K,5%,R0402,11959.86,17248.39,270.000,NO
R4138,"Q_RES_0402LF-4.7K,5%,1/16W,CHIA",4.7K,5%,R0402,11745.76,16790.49,270.000,NO
R4139,"Q_RES_0402LF-4.7K,5%,1/16W,CHIA",4.7K,5%,R0402,12067.56,17248.84,270.000,NO
R4140,"Q_RES_0402LF-4.7K,5%,1/16W,CHIA",4.7K,5%,R0402,11972.40,17049.05,90.000,NO
R4141,"Q_RES_0402LF-4.7K,5%,1/16W,CHIA",4.7K,5%,R0402,11758.30,16591.15,90.000,NO
R4142,"Q_RES_0402LF-4.7K,5%,1/16W,CHIA",4.7K,5%,R0402,12080.10,17049.50,90.000,NO
R4143,"Q_RES_0402LF-33.2,1%,1/16W,CHIA",33.2,1%,R0402,8068.40,4548.62,180.000,NO
R4144,"Q_RES_0402LF-33.2,1%,1/16W,CHIA",33.2,1%,R0402,7913.40,4548.62,180.000,NO
R4145,"Q_RES_0402LF-33.2,1%,1/16W,CHIA",33.2,1%,R0402,7913.40,4448.62,180.000,NO
R4146,"Q_RES_0402LF-33.2,1%,1/16W,CHIA",33.2,1%,R0402,7913.40,4498.62,180.000,NO
R4147,"Q_RES_0402LF-33.2,1%,1/16W,CHIA",33.2,1%,R0402,8068.40,4498.62,180.000,NO
R4148,"Q_RES_0402LF-33.2,1%,1/16W,CHIA",33.2,1%,R0402,7913.40,4398.62,180.000,NO
R4149,"Q_RES_0402LF-33.2,1%,1/16W,CHIA",33.2,1%,R0402,6400.13,920.85,0.000,NO
R4150,"Q_RES_0402LF-33.2,1%,1/16W,CHIA",33.2,1%,R0402,6329.17,921.19,180.000,NO
R4151,"Q_RES_0402LF-33.2,1%,1/16W,CHIA",33.2,1%,R0402,6400.53,880.35,0.000,NO
R4152,"Q_RES_0402LF-33.2,1%,1/16W,CHIA",33.2,1%,R0402,6329.17,880.39,180.000,NO
R4153,"Q_RES_0402LF-10K,1%,1/16W,CHIPA",10K,1%,R0402,11599.30,16591.15,90.000,NO
R4154,"Q_RES_0402LF-100K,1%,1/16W,EMPA",100K,1%,R0402,11599.30,16497.15,270.000,NO
R4155,"Q_RES_0402LF-4.7K,5%,1/16W,CHIA",4.7K,5%,R0402,11635.76,16790.49,270.000,NO
R4156,"Q_RES_0402LF-4.7K,5%,1/16W,CHIA",4.7K,5%,R0402,11648.30,16591.15,90.000,NO
R4157,"Q_RES_0402LF-33.2,1%,1/16W,CHIA",33.2,1%,R0402,7913.40,4598.62,180.000,NO
R4158,"Q_RES_0402LF-54.9K,1%,1/16W,EMA",54.9K,1%,R0402,14188.33,15213.35,0.000,NO
R4159,"Q_RES_0402LF-100K,1%,1/16W,EMPA",100K,1%,R0402,14074.33,15213.35,180.000,NO
R4160,"Q_RES_0402LF-54.9K,1%,1/16W,EMA",54.9K,1%,R0402,14192.23,15483.75,0.000,NO
R4161,"Q_RES_0402LF-100K,1%,1/16W,EMPA",100K,1%,R0402,14078.23,15483.75,180.000,NO
R4162,"Q_RES_0402LF-54.9K,1%,1/16W,EMA",54.9K,1%,R0402,14190.73,15371.55,0.000,NO
R4163,"Q_RES_0402LF-100K,1%,1/16W,EMPA",100K,1%,R0402,14076.73,15371.55,180.000,NO
R4164,"Q_RES_0402LF-4.7K,5%,1/16W,CHIA",4.7K,5%,R0402,14532.67,15266.89,180.000,NO
R4165,"Q_RES_0402LF-4.7K,5%,1/16W,CHIA",4.7K,5%,R0402,14536.57,15537.29,180.000,NO
R4166,"Q_RES_0402LF-4.7K,5%,1/16W,CHIA",4.7K,5%,R0402,14535.07,15425.09,180.000,NO
R4167,"Q_RES_0402LF-4.7K,5%,1/16W,CHIA",4.7K,5%,R0402,14188.33,15164.35,0.000,NO
R4168,"Q_RES_0402LF-4.7K,5%,1/16W,CHIA",4.7K,5%,R0402,14192.23,15434.75,0.000,NO
R4169,"Q_RES_0402LF-4.7K,5%,1/16W,CHIA",4.7K,5%,R0402,14190.73,15322.55,0.000,NO
R4170,"Q_RES_0402LF-33.2,1%,1/16W,CHIA",33.2,1%,R0402,8208.40,4648.62,180.000,NO
R4171,"Q_RES_0402LF-33.2,1%,1/16W,CHIA",33.2,1%,R0402,8068.40,4648.62,180.000,NO
R4172,"Q_RES_0402LF-33.2,1%,1/16W,CHIA",33.2,1%,R0402,8068.40,4598.62,180.000,NO
R4173,"Q_RES_0402LF-100K,1%,1/16W,EMPA",100K,1%,R0402,14516.60,15903.02,180.000,NO
R4174,"Q_RES_0402LF-33.2,1%,1/16W,CHIA",33.2,1%,R0402,8068.40,4748.62,0.000,NO
R4175,"Q_RES_0402LF-33.2,1%,1/16W,CHIA",33.2,1%,R0402,8068.40,4698.62,0.000,NO
R4176,"Q_RES_0402LF-10K,1%,1/16W,CHIPA",10K,1%,R0402,6676.10,1119.12,270.000,NO
R4177,"Q_RES_0402LF-0,5%,1/16W,CHIP,CA",0,5%,R0402,6536.10,1204.12,0.000,NO
R4178,"Q_RES_0402LF-33.2,1%,1/16W,CHIA",33.2,1%,R0402,4142.20,16683.62,180.000,NO
R4179,"Q_RES_0402LF-33.2,1%,1/16W,CHIA",33.2,1%,R0402,11231.03,605.45,0.000,NO
R4180,"Q_RES_0402LF-33.2,1%,1/16W,CHIA",33.2,1%,R0402,14426.47,16696.29,0.000,NO
R4181,"Q_RES_0402LF-33.2,1%,1/16W,CHIA",33.2,1%,R0402,4142.20,16723.62,180.000,NO
R4182,"Q_RES_0402LF-33.2,1%,1/16W,CHIA",33.2,1%,R0402,11231.03,645.45,0.000,NO
R4183,"Q_RES_0402LF-33.2,1%,1/16W,CHIA",33.2,1%,R0402,14426.43,16739.55,0.000,NO
R4184,"Q_RES_0402LF-1K,1%,1/16W,EMPTYA",1K,1%,R0402,4874.43,558.95,180.000,NO
R4185,"Q_RES_0402LF-1K,1%,1/16W,CHIP,A",1K,1%,R0402,4736.83,559.35,0.000,NO
R4186,"Q_RES_0402LF-1K,1%,1/16W,EMPTYA",1K,1%,R0402,3785.47,16447.55,90.000,NO
R4187,"Q_RES_0402LF-1K,1%,1/16W,CHIP,A",1K,1%,R0402,3784.97,16328.95,270.000,NO
R4188,"Q_RES_0402LF-1K,1%,1/16W,EMPTYA",1K,1%,R0402,11698.91,571.11,180.000,NO
R4189,"Q_RES_0402LF-1K,1%,1/16W,CHIP,A",1K,1%,R0402,11839.91,571.11,0.000,NO
R4190,"Q_RES_0402LF-1K,1%,1/16W,EMPTYA",1K,1%,R0402,14541.67,16424.15,90.000,NO
R4191,"Q_RES_0402LF-1K,1%,1/16W,CHIP,A",1K,1%,R0402,14542.07,16295.65,270.000,NO
R4192,"Q_RES_0402LF-1K,1%,1/16W,EMPTYA",1K,1%,R0402,4872.83,612.05,180.000,NO
R4193,"Q_RES_0402LF-1K,1%,1/16W,CHIP,A",1K,1%,R0402,4737.27,611.29,0.000,NO
R4194,"Q_RES_0402LF-1K,1%,1/16W,EMPTYA",1K,1%,R0402,3851.23,16447.49,90.000,NO
R4195,"Q_RES_0402LF-1K,1%,1/16W,CHIP,A",1K,1%,R0402,3851.23,16329.59,270.000,NO
R4196,"Q_RES_0402LF-1K,1%,1/16W,EMPTYA",1K,1%,R0402,11698.71,613.11,180.000,NO
R4197,"Q_RES_0402LF-1K,1%,1/16W,CHIP,A",1K,1%,R0402,11840.71,613.11,0.000,NO
R4198,"Q_RES_0402LF-1K,1%,1/16W,EMPTYA",1K,1%,R0402,14591.27,16424.15,90.000,NO
R4199,"Q_RES_0402LF-1K,1%,1/16W,CHIP,A",1K,1%,R0402,14591.17,16295.45,270.000,NO
R4200,"Q_RES_0402LF-1K,1%,1/16W,EMPTYA",1K,1%,R0402,4871.73,665.65,180.000,NO
R4201,"Q_RES_0402LF-1K,1%,1/16W,CHIP,A",1K,1%,R0402,4737.53,665.75,0.000,NO
R4202,"Q_RES_0402LF-1K,1%,1/16W,EMPTYA",1K,1%,R0402,3915.63,16442.19,90.000,NO
R4203,"Q_RES_0402LF-1K,1%,1/16W,CHIP,A",1K,1%,R0402,3912.93,16329.79,270.000,NO
R4204,"Q_RES_0402LF-1K,1%,1/16W,EMPTYA",1K,1%,R0402,11698.71,658.11,180.000,NO
R4205,"Q_RES_0402LF-1K,1%,1/16W,CHIP,A",1K,1%,R0402,11839.71,658.11,0.000,NO
R4206,"Q_RES_0402LF-1K,1%,1/16W,EMPTYA",1K,1%,R0402,14637.67,16424.15,90.000,NO
R4207,"Q_RES_0402LF-1K,1%,1/16W,CHIP,A",1K,1%,R0402,14637.47,16295.45,270.000,NO
R4208,"Q_RES_0402LF-200K,1%,1/16W,EMPA",200K,1%,R0402,14485.07,16423.25,90.000,NO
R4209,"Q_RES_0402LF-200K,1%,1/16W,EMPA",200K,1%,R0402,14385.47,16423.35,90.000,NO
R4210,"Q_RES_0402LF-200K,1%,1/16W,EMPA",200K,1%,R0402,4114.32,16802.67,0.000,NO
R4211,"Q_RES_0402LF-200K,1%,1/16W,CHIA",200K,1%,R0402,14436.17,16423.15,90.000,NO
R4212,"Q_RES_0402LF-0,5%,1/16W,CHIP,CA",0,5%,R0402,14425.73,16539.69,270.000,NO
R4213,"Q_RES_0402LF-0,5%,1/16W,CHIP,CA",0,5%,R0402,4142.20,16763.62,180.000,NO
R4214,"Q_RES_0402LF-0,5%,1/16W,CHIP,CA",0,5%,R0402,11230.03,565.45,0.000,NO
R4215,"Q_RES_0402LF-0,5%,1/16W,CHIP,CA",0,5%,R0402,14427.33,16654.95,0.000,NO
R4216,"Q_RES_0402LF-0,5%,1/16W,CHIP,CA",0,5%,R0402,13823.47,13956.03,90.000,NO
R4259,"Q_RES_0402LF-33.2,1%,1/16W,CHIA",33.2,1%,R0402,6952.20,5263.62,270.000,NO
R4260,"Q_RES_0402LF-240,1%,1/16W,EMPTA",240,1%,R0402,3481.97,7057.79,180.000,NO
R4261,"Q_RES_0402LF-240,1%,1/16W,EMPTA",240,1%,R0402,3482.33,7099.95,0.000,NO
R4262,"Q_RES_0402LF-240,1%,1/16W,EMPTA",240,1%,R0402,12904.37,7509.65,90.000,NO
R4263,"Q_RES_0402LF-240,1%,1/16W,EMPTA",240,1%,R0402,12949.37,7509.65,270.000,NO
R4264,"Q_RES_0402LF-4.7K,5%,1/16W,CHIA",4.7K,5%,R0402,12050.81,16778.73,0.000,NO
R4265,"Q_RES_0402LF-4.7K,5%,1/16W,EMPA",4.7K,5%,R0402,12050.85,16817.67,180.000,NO
R4266,"Q_RES_0402LF-33.2,1%,1/16W,CHIA",33.2,1%,R0402,12123.35,16817.73,0.000,NO
R4267,"Q_RES_0402LF-33.2,1%,1/16W,CHIA",33.2,1%,R0402,6332.20,4578.62,0.000,YES
R4268,"Q_RES_0402LF-0,5%,1/16W,CHIP,CA",0,5%,R0402,12032.67,16544.85,90.000,NO
R4269,"Q_RES_0402LF-2.2K,5%,1/16W,EMPA",2.2K,5%,R0402,2770.00,4478.62,180.000,NO
R4270,"Q_RES_0402LF-2.2K,5%,1/16W,EMPA",2.2K,5%,R0402,2770.00,4518.62,180.000,NO
R4273,"Q_RES_0402LF-1K,1%,1/16W,EMPTYA",1K,1%,R0402,5073.20,1241.82,90.000,YES
R4274,"Q_RES_0402LF-1K,1%,1/16W,EMPTYA",1K,1%,R0402,5073.60,1446.92,90.000,YES
R4275,"Q_RES_0402LF-1K,1%,1/16W,EMPTYA",1K,1%,R0402,5378.40,991.72,180.000,NO
R4276,"Q_RES_0402LF-68K,1%,1/16W,CHIPA",68K,1%,R0402,5378.20,1033.52,0.000,NO
R4279,"Q_RES_0402LF-1K,1%,1/16W,EMPTYA",1K,1%,R0402,5073.10,729.92,270.000,YES
R4280,"Q_RES_0402LF-1K,1%,1/16W,EMPTYA",1K,1%,R0402,5073.10,826.62,90.000,YES
R4281,"Q_RES_0402LF-1K,1%,1/16W,EMPTYA",1K,1%,R0402,5379.00,1125.12,180.000,NO
R4282,"Q_RES_0402LF-68K,1%,1/16W,CHIPA",68K,1%,R0402,5378.90,1080.62,0.000,NO
R4284,"Q_RES_0402LF-1K,1%,1/16W,EMPTYA",1K,1%,R0402,5032.70,1241.32,90.000,YES
R4285,"Q_RES_0402LF-1K,1%,1/16W,EMPTYA",1K,1%,R0402,5032.90,1447.22,90.000,YES
R4287,"Q_RES_0402LF-1K,1%,1/16W,EMPTYA",1K,1%,R0402,5031.50,729.72,270.000,YES
R4288,"Q_RES_0402LF-1K,1%,1/16W,EMPTYA",1K,1%,R0402,5031.00,826.92,90.000,YES
R4289,"Q_RES_0402LF-4.7K,1%,1/16W,EMPA",4.7K,1%,R0402,4987.30,1241.22,90.000,YES
R4290,"Q_RES_0402LF-4.7K,1%,1/16W,EMPA",4.7K,1%,R0402,4986.30,1447.32,90.000,YES
R4291,"Q_RES_0402LF-4.7K,1%,1/16W,EMPA",4.7K,1%,R0402,4995.10,826.22,270.000,YES
R4292,"Q_RES_0402LF-4.7K,1%,1/16W,EMPA",4.7K,1%,R0402,4995.90,897.42,90.000,YES
R4293,"Q_RES_0402LF-100,1%,1/16W,CHIPA",100,1%,R0402,7087.20,3823.62,270.000,NO
R4294,"Q_RES_0402LF-100,1%,1/16W,CHIPA",100,1%,R0402,7914.20,3934.62,0.000,NO
R4295,"Q_RES_0402LF-100,1%,1/16W,CHIPA",100,1%,R0402,11727.42,7724.07,270.000,YES
R4296,"Q_RES_0402LF-100,1%,1/16W,CHIPA",100,1%,R0402,11798.42,7803.07,270.000,YES
R4297,"Q_RES_0402LF-100,1%,1/16W,CHIPA",100,1%,R0402,15820.00,7583.62,270.000,YES
R4298,"Q_RES_0402LF-100,1%,1/16W,CHIPA",100,1%,R0402,15840.00,7513.62,270.000,YES
R4299,"Q_RES_0402LF-100,1%,1/16W,CHIPA",100,1%,R0402,2484.42,7709.07,270.000,YES
R4300,"Q_RES_0402LF-100,1%,1/16W,CHIPA",100,1%,R0402,2573.42,7702.07,270.000,YES
R4301,"Q_RES_0402LF-100,1%,1/16W,CHIPA",100,1%,R0402,6643.42,7761.07,270.000,YES
R4302,"Q_RES_0402LF-100,1%,1/16W,CHIPA",100,1%,R0402,6719.42,7717.07,270.000,YES
R4303,"Q_RES_0402LF-22,1%,1/16W,CHIP,A",22,1%,R0402,12933.98,2894.07,90.000,NO
R4304,"Q_RES_0402LF-22,1%,1/16W,CHIP,A",22,1%,R0402,12973.42,2894.07,90.000,NO
R4305,"Q_RES_0402LF-0,5%,1/16W,CHIP,CA",0,5%,R0402,13035.42,2998.17,90.000,NO
R4306,"Q_RES_0402LF-0,5%,1/16W,CHIP,CA",0,5%,R0402,13075.42,2998.17,90.000,NO
R4388,"Q_RES_0402LF-150,1%,1/16W,CHIPA",150,1%,R0402,12423.98,7528.17,90.000,YES
R4389,"Q_RES_0402LF-150,1%,1/16W,CHIPA",150,1%,R0402,12491.22,7544.07,270.000,YES
R4390,"Q_RES_0402LF-150,1%,1/16W,CHIPA",150,1%,R0402,12599.98,7340.17,90.000,YES
R4391,"Q_RES_0402LF-150,1%,1/16W,CHIPA",150,1%,R0402,5691.52,4179.87,270.000,NO
R4392,"Q_RES_0402LF-33.2,1%,1/16W,CHIA",33.2,1%,R0402,5928.05,3633.54,0.000,NO
R4393,"Q_RES_0402LF-33.2,1%,1/16W,CHIA",33.2,1%,R0402,5646.98,3647.02,270.000,NO
R4394,"Q_RES_0402LF-33.2,1%,1/16W,CHIA",33.2,1%,R0402,5785.82,3646.57,270.000,NO
R4395,"Q_RES_0402LF-100,1%,1/16W,CHIPA",100,1%,R0402,4747.20,3648.62,270.000,NO
R4396,"Q_RES_0402LF-100,1%,1/16W,CHIPA",100,1%,R0402,4907.20,3648.62,270.000,NO
R4397,"Q_RES_0402LF-1.5K,1%,1/16W,CHIA",1.5K,1%,R0402,4817.20,3913.62,0.000,NO
R4398,"Q_RES_0402LF-1.5K,1%,1/16W,CHIA",1.5K,1%,R0402,4947.20,3913.62,0.000,NO
R4399,"Q_RES_0402LF-33.2,1%,1/16W,CHIA",33.2,1%,R0402,4867.20,3648.62,270.000,NO
R4400,"Q_RES_0402LF-33.2,1%,1/16W,CHIA",33.2,1%,R0402,4987.20,3648.62,270.000,NO
R4401,"Q_RES_0402LF-100,1%,1/16W,CHIPA",100,1%,R0402,5067.20,3648.62,270.000,NO
R4402,"Q_RES_0402LF-100,1%,1/16W,CHIPA",100,1%,R0402,5237.20,3648.62,270.000,NO
R4403,"Q_RES_0402LF-1.5K,1%,1/16W,CHIA",1.5K,1%,R0402,5040.40,3799.02,90.000,NO
R4404,"Q_RES_0402LF-1.5K,1%,1/16W,CHIA",1.5K,1%,R0402,5208.30,3823.82,90.000,NO
R4405,"Q_RES_0402LF-4.75K,1%,1/16W,CHA",4.75K,1%,R0402,5147.20,3648.62,90.000,NO
R4406,"Q_RES_0402LF-4.75K,1%,1/16W,CHA",4.75K,1%,R0402,5357.20,3648.62,90.000,NO
R4407,"Q_RES_0402LF-33.2,1%,1/16W,CHIA",33.2,1%,R0402,5187.20,3648.62,270.000,NO
R4408,"Q_RES_0402LF-33.2,1%,1/16W,CHIA",33.2,1%,R0402,5317.20,3648.62,270.000,NO
R4409,"Q_RES_0402LF-1.5K,1%,1/16W,CHIA",1.5K,1%,R0402,5097.20,4208.62,0.000,NO
R4410,"Q_RES_0402LF-1.5K,1%,1/16W,CHIA",1.5K,1%,R0402,5247.20,4208.62,0.000,NO
R4411,"Q_RES_0402LF-4.75K,1%,1/16W,CHA",4.75K,1%,R0402,5137.20,3943.62,90.000,NO
R4412,"Q_RES_0402LF-4.75K,1%,1/16W,CHA",4.75K,1%,R0402,5297.20,3943.62,90.000,NO
R4413,"Q_RES_0402LF-33.2,1%,1/16W,CHIA",33.2,1%,R0402,5177.20,3943.62,270.000,NO
R4414,"Q_RES_0402LF-33.2,1%,1/16W,CHIA",33.2,1%,R0402,5337.20,3943.62,270.000,NO
R4419,"Q_RES_0402LF-49.9,1%,1/16W,EMPA",49.9,1%,R0402,561.63,4155.03,90.000,NO
R4420,"Q_RES_0402LF-49.9,1%,1/16W,EMPA",49.9,1%,R0402,695.23,4155.03,90.000,NO
R4448,"Q_RES_0402LF-10K,1%,1/16W,EMPTA",10K,1%,R0402,6466.44,1406.99,180.000,NO
R4449,"Q_RES_0402LF-10K,1%,1/16W,EMPTA",10K,1%,R0402,6466.61,1345.06,0.000,NO
R4450,"Q_RES_0402LF-0,5%,1/16W,EMPTY,A",0,5%,R0402,6336.03,1646.96,90.000,YES
R4451,"Q_RES_0402LF-33.2,1%,1/16W,EMPA",33.2,1%,R0402,6022.78,1233.92,90.000,NO
R4452,"Q_RES_0402LF-10K,1%,1/16W,EMPTA",10K,1%,R0402,6143.84,1233.92,90.000,NO
R4453,"Q_RES_0402LF-47K,0.1%,1/16W,EMA",47K,0.1%,R0402,6101.04,1233.92,90.000,NO
R4454,"Q_RES_0402LF-0,5%,1/16W,EMPTY,A",0,5%,R0402,6127.36,1757.75,90.000,NO
R4455,"Q_RES_0402LF-0,5%,1/16W,EMPTY,A",0,5%,R0402,6183.52,1758.37,90.000,NO
R4456,"Q_RES_0402LF-10K,1%,1/16W,EMPTA",10K,1%,R0402,6466.44,1543.45,180.000,NO
R4457,"Q_RES_0402LF-10K,1%,1/16W,EMPTA",10K,1%,R0402,6466.44,1498.71,180.000,NO
R4458,"Q_RES_0402LF-10K,1%,1/16W,EMPTA",10K,1%,R0402,6266.99,1233.92,90.000,NO
R4459,"Q_RES_0402LF-10K,1%,1/16W,EMPTA",10K,1%,R0402,6225.92,1233.92,90.000,NO
R4460,"Q_RES_0402LF-0,5%,1/16W,CHIP,CA",0,5%,R0402,6127.40,1789.47,270.000,NO
R4461,"Q_RES_0402LF-0,5%,1/16W,CHIP,CA",0,5%,R0402,6183.52,1789.87,270.000,NO
R4462,"Q_RES_0402LF-0,5%,1/16W,EMPTY,A",0,5%,R0402,6309.51,1233.92,90.000,NO
R4463,"Q_RES_0402LF-680,1%,1/16W,EMPTA",680,1%,R0402,5977.55,1594.80,180.000,NO
R4464,"Q_RES_0402LF-100K,1%,1/16W,EMPA",100K,1%,R0402,6466.44,1449.82,0.000,NO
R4465,"Q_RES_0402LF-3.9K,5%,1/16W,EMPA",3.9K,5%,R0402,5689.05,1096.22,180.000,YES
R4466,"Q_RES_0402LF-0,5%,1/16W,EMPTY,A",0,5%,R0402,6184.60,1233.92,270.000,NO
R4467,"Q_RES_0402LF-0,5%,1/16W,CHIP,CA",0,5%,R0402,5454.50,903.27,90.000,YES
R4468,"Q_RES_0402LF-0,5%,1/16W,CHIP,CA",0,5%,R0402,5413.70,903.27,90.000,YES
R4471,"Q_RES_0402LF-0,5%,1/16W,EMPTY,A",0,5%,R0402,6255.96,1725.69,90.000,NO
R4472,"Q_RES_0402LF-0,5%,1/16W,EMPTY,A",0,5%,R0402,6310.25,1725.69,90.000,NO
R4473,"Q_RES_0402LF-0,5%,1/16W,CHIP,CA",0,5%,R0402,6255.96,1757.19,90.000,NO
R4474,"Q_RES_0402LF-0,5%,1/16W,CHIP,CA",0,5%,R0402,6310.25,1757.19,90.000,NO
R4475,"Q_RES_0603LF-1,1%,1/10W,CHIP,CA",1,1%,R0603_H24,4268.55,16469.93,180.000,YES
R4476,"Q_RES_0402LF-49.9,1%,1/16W,CHIA",49.9,1%,R0402,4679.60,16267.32,180.000,NO
R4477,"Q_RES_0402LF-33.2,1%,1/16W,CHIA",33.2,1%,R0402,4207.30,16472.16,180.000,NO
R4478,"Q_RES_0402LF-33.2,1%,1/16W,CHIA",33.2,1%,R0402,4207.10,16431.59,180.000,NO
R4479,"Q_RES_0402LF-33.2,1%,1/16W,CHIA",33.2,1%,R0402,4201.50,16204.02,180.000,NO
R4480,"Q_RES_0402LF-33.2,1%,1/16W,CHIA",33.2,1%,R0402,10332.68,5038.02,270.000,NO
R4481,"Q_RES_0402LF-33.2,1%,1/16W,CHIA",33.2,1%,R0402,4728.00,16349.47,180.000,NO
R4482,"Q_RES_0402LF-49.9,1%,1/16W,EMPA",49.9,1%,R0402,586.07,4217.46,180.000,NO
R4483,"Q_RES_0402LF-49.9,1%,1/16W,EMPA",49.9,1%,R0402,671.08,4217.46,0.000,NO
R4486,"Q_RES_0402LF-49.9,1%,1/16W,EMPA",49.9,1%,R0402,6113.35,1840.62,180.000,NO
R4487,"Q_RES_0402LF-49.9,1%,1/16W,EMPA",49.9,1%,R0402,6198.07,1840.22,0.000,NO
R4489,"Q_RES_0402LF-4.75K,1%,1/16W,CHA",4.75K,1%,R0402,4728.60,16310.03,180.000,NO
R4490,"Q_RES_0402LF-4.75K,1%,1/16W,EMA",4.75K,1%,R0402,4866.50,16310.38,0.000,NO
R4491,"Q_RES_0402LF-10K,1%,1/16W,CHIPA",10K,1%,R0402,4678.70,16227.35,180.000,NO
R4492,"Q_RES_0402LF-10K,1%,1/16W,CHIPA",10K,1%,R0402,4678.70,16186.26,0.000,NO
R4493,"Q_RES_0603LF-1,1%,1/10W,CHIP,CA",1,1%,R0603_H24,4268.65,16420.06,180.000,YES
R4494,"Q_RES_0402LF-10K,1%,1/16W,CHIPA",10K,1%,R0402,4515.80,16119.23,0.000,NO
R4495,"Q_RES_0402LF-33.2,1%,1/16W,CHIA",33.2,1%,R0402,9028.75,4644.12,270.000,YES
R4496,"Q_RES_0402LF-33.2,1%,1/16W,CHIA",33.2,1%,R0402,10292.78,5141.76,180.000,NO
R4497,"Q_RES_0402LF-33.2,1%,1/16W,CHIA",33.2,1%,R0402,10292.78,5236.28,180.000,NO
R4498,"Q_RES_0402LF-4.7K,5%,1/16W,CHIA",4.7K,5%,R0402,10197.69,5125.74,0.000,NO
R4499,"Q_RES_0402LF-4.7K,5%,1/16W,CHIA",4.7K,5%,R0402,10197.69,5177.28,0.000,NO
R4500,"Q_RES_0402LF-10K,1%,1/16W,EMPTA",10K,1%,R0402,10439.88,5021.61,0.000,NO
R4501,"Q_RES_0402LF-0,5%,1/16W,CHIP,CA",0,5%,R0402,9437.50,9816.52,270.000,NO
R4502,"Q_RES_0402LF-33.2,1%,1/16W,CHIA",33.2,1%,R0402,9399.70,5216.88,90.000,YES
R4503,"Q_RES_0402LF-0,5%,1/16W,CHIP,CA",0,5%,R0402,15905.00,1993.62,180.000,NO
R4504,"Q_RES_0402LF-0,5%,1/16W,CHIP,CA",0,5%,R0402,7035.00,768.62,270.000,YES
R4505,"Q_RES_0402LF-33.2,1%,1/16W,CHIA",33.2,1%,R0402,7075.00,768.62,270.000,YES
R4506,"Q_RES_0402LF-33.2,1%,1/16W,CHIA",33.2,1%,R0402,6390.00,528.62,90.000,YES
R4507,"Q_RES_0402LF-33.2,1%,1/16W,CHIA",33.2,1%,R0402,6350.00,528.62,90.000,YES
R4508,"Q_RES_0402LF-33.2,1%,1/16W,CHIA",33.2,1%,R0402,6385.00,813.62,270.000,NO
R4509,"Q_RES_0402LF-33.2,1%,1/16W,CHIA",33.2,1%,R0402,6345.00,813.62,270.000,NO
R4510,"Q_RES_0402LF-33.2,1%,1/16W,CHIA",33.2,1%,R0402,9321.65,5120.98,0.000,YES
R4511,"Q_RES_0402LF-0,5%,1/16W,CHIP,CA",0,5%,R0402,7081.10,841.12,270.000,YES
R4512,"Q_RES_0402LF-33.2,1%,1/16W,CHIA",33.2,1%,R0402,7280.00,798.62,90.000,YES
R4513,"Q_RES_0402LF-0,5%,1/16W,CHIP,CA",0,5%,R0402,7175.00,825.62,180.000,YES
R4514,"Q_RES_0402LF-4.7K,1%,1/16W,EMPA",4.7K,1%,R0402,4483.56,1457.10,180.000,NO
R4515,"Q_RES_0402LF-100K,1%,1/16W,CHIA",100K,1%,R0402,14725.65,16296.02,90.000,NO
R4516,"Q_RES_0402LF-10K,1%,1/16W,CHIPA",10K,1%,R0402,8939.81,5068.75,180.000,YES
R4517,"Q_RES_0402LF-10K,1%,1/16W,CHIPA",10K,1%,R0402,8980.87,4644.12,270.000,YES
R4518,"Q_RES_0402LF-10K,1%,1/16W,CHIPA",10K,1%,R0402,7613.57,4976.58,180.000,YES
R4519,"Q_RES_0402LF-10K,1%,1/16W,CHIPA",10K,1%,R0402,7613.45,5016.62,180.000,YES
R4520,"Q_RES_0402LF-10K,1%,1/16W,CHIPA",10K,1%,R0402,7613.50,4976.59,0.000,NO
R4521,"Q_RES_0402LF-10K,1%,1/16W,CHIPA",10K,1%,R0402,7763.08,4848.02,180.000,YES
R4530,"Q_RES_0402LF-33.2,1%,1/16W,CHIA",33.2,1%,R0402,7050.80,16110.22,0.000,NO
R4531,"Q_RES_0402LF-0,5%,1/16W,CHIP,CA",0,5%,R0402,7050.80,16071.02,0.000,NO
R4532,"Q_RES_0402LF-10K,1%,1/16W,EMPTA",10K,1%,R0402,17239.18,1128.67,0.000,NO
R4533,"Q_RES_0402LF-2K,1%,1/16W,EMPTYA",2K,1%,R0402,8088.43,4271.29,90.000,YES
R4534,"Q_RES_0402LF-0,5%,1/16W,CHIP,CA",0,5%,R0402,9050.80,5036.31,180.000,YES
R4535,"Q_RES_0402LF-10,1%,1/16W,CHIP,A",10,1%,R0402,6740.80,541.82,90.000,YES
R4536,"Q_RES_0402LF-10,1%,1/16W,CHIP,A",10,1%,R0402,6700.80,541.82,90.000,YES
R4537,"Q_RES_0402LF-0,5%,1/16W,CHIP,CA",0,5%,R0402,1071.70,15187.42,90.000,NO
R4540,"Q_RES_0402LF-33.2,1%,1/16W,CHIA",33.2,1%,R0402,10380.30,5141.82,180.000,NO
R4541,"Q_RES_0402LF-33.2,1%,1/16W,CHIA",33.2,1%,R0402,10376.10,5236.42,180.000,NO
R4543,"Q_RES_0402LF-4.7K,5%,1/16W,CHIA",4.7K,5%,R0402,3863.40,16227.22,180.000,NO
R4544,"Q_RES_0402LF-100K,1%,1/16W,EMPA",100K,1%,R0402,3863.50,16270.62,0.000,NO
R4545,"Q_RES_0402LF-4.7K,5%,1/16W,CHIA",4.7K,5%,R0402,3745.00,16444.22,270.000,NO
R4546,"Q_RES_0402LF-4.7K,5%,1/16W,EMPA",4.7K,5%,R0402,3878.10,16620.32,90.000,YES
R4547,"Q_RES_0402LF-100K,1%,1/16W,EMPA",100K,1%,R0402,14026.80,16017.72,90.000,NO
R4548,"Q_RES_0402LF-100K,1%,1/16W,CHIA",100K,1%,R0402,13987.00,16017.82,270.000,NO
R4549,"Q_RES_0402LF-4.7K,5%,1/16W,EMPA",4.7K,5%,R0402,14257.50,16128.12,180.000,NO
R4550,"Q_RES_0402LF-49.9,1%,1/16W,CHIA",49.9,1%,R0402,14257.10,16169.32,0.000,NO
R4551,"Q_RES_0402LF-54.9K,1%,1/16W,EMA",54.9K,1%,R0402,11204.32,16269.20,270.000,NO
R4552,"Q_RES_0402LF-100K,1%,1/16W,CHIA",100K,1%,R0402,11247.62,16269.10,90.000,NO
R4553,"Q_RES_0402LF-4.7K,5%,1/16W,CHIA",4.7K,5%,R0402,11506.82,16262.80,180.000,NO
R4554,"Q_RES_0402LF-4.7K,5%,1/16W,CHIA",4.7K,5%,R0402,11248.62,16192.50,90.000,NO
R4555,"Q_RES_0402LF-4.7K,5%,1/16W,EMPA",4.7K,5%,R0402,14257.70,16084.42,0.000,NO
R4556,"Q_RES_0402LF-33.2,1%,1/16W,CHIA",33.2,1%,R0402,3918.80,16619.92,90.000,YES
R4557,"Q_RES_0402LF-33.2,1%,1/16W,CHIA",33.2,1%,R0402,11158.02,16192.70,270.000,NO
R4558,"Q_RES_0402LF-33.2,1%,1/16W,CHIA",33.2,1%,R0402,13969.00,16095.22,180.000,NO
R4559,"Q_RES_0402LF-100K,1%,1/16W,CHIA",100K,1%,R0402,14040.00,16423.62,180.000,NO
R4560,"Q_RES_0402LF-4.7K,5%,1/16W,CHIA",4.7K,5%,R0402,14300.00,16373.62,180.000,NO
R4561,"Q_RES_0402LF-4.7K,5%,1/16W,CHIA",4.7K,5%,R0402,14040.00,16343.62,0.000,NO
R4562,"Q_RES_0402LF-100K,1%,1/16W,EMPA",100K,1%,R0402,14040.00,16383.62,0.000,NO
R4563,"Q_RES_0402LF-33.2,1%,1/16W,CHIA",33.2,1%,R0402,14040.00,16263.62,0.000,NO
R4564,"Q_RES_0402LF-10K,1%,1/16W,CHIPA",10K,1%,R0402,12363.60,2443.32,180.000,NO
R4565,"Q_RES_0402LF-10K,1%,1/16W,CHIPA",10K,1%,R0402,12363.60,2483.32,180.000,NO
R4567,"Q_RES_0402LF-5.11K,1%,1/16W,CHA",5.11K,1%,R0402,1599.00,4133.62,180.000,NO
R4568,"Q_RES_0402LF-4.7K,1%,1/16W,CHIA",4.7K,1%,R0402,1599.00,4093.62,0.000,NO
R4569,"Q_RES_0402LF-0,5%,1/16W,EMPTY,A",0,5%,R0402,13986.00,15213.62,180.000,NO
R4570,"Q_RES_0402LF-0,5%,1/16W,EMPTY,A",0,5%,R0402,13985.00,15371.62,180.000,NO
R4571,"Q_RES_0402LF-0,5%,1/16W,EMPTY,A",0,5%,R0402,13985.00,15483.62,180.000,NO
R4572,"Q_RES_0402LF-0,5%,1/16W,EMPTY,A",0,5%,R0402,12164.05,16887.00,0.000,NO
R4573,"Q_RES_0402LF-0,5%,1/16W,EMPTY,A",0,5%,R0402,11844.25,16426.00,0.000,NO
R4574,"Q_RES_0402LF-0,5%,1/16W,EMPTY,A",0,5%,R0402,11624.25,16426.00,0.000,NO
R4575,"Q_RES_0402LF-0,5%,1/16W,EMPTY,A",0,5%,R0402,11949.95,16429.10,0.000,NO
R4576,"Q_RES_0402LF-0,5%,1/16W,EMPTY,A",0,5%,R0402,11734.25,16426.00,0.000,NO
R4577,"Q_RES_0402LF-0,5%,1/16W,EMPTY,A",0,5%,R0402,11948.35,16883.90,0.000,NO
R4578,"Q_RES_0402LF-0,5%,1/16W,EMPTY,A",0,5%,R0402,12056.05,16884.35,0.000,NO
R4579,"Q_RES_0402LF-10K,1%,1/16W,EMPTA",10K,1%,R0402,7106.00,3682.62,90.000,NO
R4580,"Q_RES_0402LF-10K,1%,1/16W,EMPTA",10K,1%,R0402,6806.00,3682.62,90.000,NO
R4581,"Q_RES_0402LF-1K,1%,1/16W,CHIP,A",1K,1%,R0402,6806.00,3714.12,90.000,NO
R4582,"Q_RES_0402LF-10K,1%,1/16W,EMPTA",10K,1%,R0402,6906.00,3682.62,90.000,NO
R4583,"Q_RES_0402LF-1K,1%,1/16W,CHIP,A",1K,1%,R0402,6906.00,3714.12,90.000,NO
R4584,"Q_RES_0402LF-10K,1%,1/16W,EMPTA",10K,1%,R0402,7006.00,3682.62,90.000,NO
R4585,"Q_RES_0402LF-1K,1%,1/16W,CHIP,A",1K,1%,R0402,7006.00,3714.12,90.000,NO
R4586,"Q_RES_0402LF-10K,1%,1/16W,CHIPA",10K,1%,R0402,6956.00,3682.62,90.000,NO
R4588,"Q_RES_0402LF-1K,1%,1/16W,EMPTYA",1K,1%,R0402,6956.00,3714.12,90.000,NO
R4589,"Q_RES_0402LF-10K,1%,1/16W,CHIPA",10K,1%,R0402,7156.00,3682.62,90.000,NO
R4590,"Q_RES_0402LF-1K,1%,1/16W,EMPTYA",1K,1%,R0402,7156.00,3714.12,90.000,NO
R4591,"Q_RES_0402LF-10K,1%,1/16W,EMPTA",10K,1%,R0402,7056.00,3682.62,90.000,NO
R4592,"Q_RES_0402LF-1K,1%,1/16W,CHIP,A",1K,1%,R0402,7056.00,3714.12,90.000,NO
R4593,"Q_RES_0402LF-0,5%,1/16W,CHIP,CA",0,5%,R0402,13826.37,14154.95,180.000,NO
R4594,"Q_RES_0402LF-0,5%,1/16W,CHIP,CA",0,5%,R0402,1350.06,4921.15,90.000,NO
R4595,"Q_RES_0402LF-0,5%,1/16W,CHIP,CA",0,5%,R0402,905.08,6738.81,180.000,YES
R4596,"Q_RES_0402LF-1K,1%,1/16W,CHIP,A",1K,1%,R0402,7106.00,3714.12,90.000,NO
R4597,"Q_RES_0402LF-10K,1%,1/16W,EMPTA",10K,1%,R0402,6856.00,3682.62,90.000,NO
R4598,"Q_RES_0402LF-1K,1%,1/16W,CHIP,A",1K,1%,R0402,6856.00,3714.12,90.000,NO
R4599,"Q_RES_0402LF-0,5%,1/16W,CHIP,CA",0,5%,R0402,7530.89,4998.77,270.000,NO
R4600,"Q_RES_0402LF-0,5%,1/16W,CHIP,CA",0,5%,R0402,7491.79,4998.57,270.000,NO
R4601,"Q_RES_0402LF-0,5%,1/16W,CHIP,CA",0,5%,R0402,14725.67,643.55,180.000,NO
R4602,"Q_RES_0402LF-0,5%,1/16W,CHIP,CA",0,5%,R0402,3398.11,1246.77,90.000,NO
R4603,"Q_RES_0402LF-10K,1%,1/16W,CHIPA",10K,1%,R0402,1551.00,17190.82,270.000,YES
R4604,"Q_RES_0402LF-4.7K,5%,1/16W,CHIA",4.7K,5%,R0402,5805.00,5143.62,0.000,NO
R4605,"Q_RES_0402LF-4.7K,5%,1/16W,CHIA",4.7K,5%,R0402,5930.00,5248.62,0.000,NO
R4606,"Q_RES_0402LF-0,5%,1/16W,CHIP,CA",0,5%,R0402,7640.00,3653.62,90.000,NO
R4607,"Q_RES_0402LF-0,5%,1/16W,CHIP,CA",0,5%,R0402,7617.00,5134.62,90.000,NO
R4608,"Q_RES_0402LF-33.2,1%,1/16W,CHIA",33.2,1%,R0402,7899.00,4832.62,0.000,NO
R4609,"Q_RES_0402LF-33.2,1%,1/16W,CHIA",33.2,1%,R0402,7679.60,3654.82,90.000,NO
R4610,"Q_RES_0402LF-33.2,1%,1/16W,CHIA",33.2,1%,R0402,7760.00,3653.62,90.000,NO
R4611,"Q_RES_0402LF-33.2,1%,1/16W,CHIA",33.2,1%,R0402,7719.60,3654.82,90.000,NO
R4612,"Q_RES_0402LF-33.2,1%,1/16W,CHIA",33.2,1%,R0402,7828.00,5070.62,270.000,NO
R4613,"Q_RES_0402LF-0,5%,1/16W,EMPTY,A",0,5%,R0402,15340.00,1213.62,180.000,NO
R4614,"Q_RES_0402LF-33.2,1%,1/16W,CHIA",33.2,1%,R0402,15340.00,1253.62,180.000,NO
R4615,"Q_RES_0402LF-0,5%,1/16W,EMPTY,A",0,5%,R0402,3287.00,1403.62,90.000,NO
R4616,"Q_RES_0402LF-33.2,1%,1/16W,CHIA",33.2,1%,R0402,3327.00,1403.62,90.000,NO
R4617,"Q_RES_0402LF-33.2,1%,1/16W,CHIA",33.2,1%,R0402,3415.00,1618.62,0.000,NO
R4618,"Q_RES_0402LF-33.2,1%,1/16W,CHIA",33.2,1%,R0402,15170.00,1361.62,0.000,NO
R4620,"Q_RES_0402LF-4.7K,5%,1/16W,CHIA",4.7K,5%,R0402,8610.00,3783.62,180.000,NO
R4621,"Q_RES_0402LF-33.2,1%,1/16W,CHIA",33.2,1%,R0402,4608.00,3815.62,270.000,YES
R4622,"Q_RES_0402LF-2K,1%,1/16W,CHIP,A",2K,1%,R0402,902.30,16866.22,0.000,NO
R4623,"Q_RES_0402LF-1K,1%,1/16W,CHIP,A",1K,1%,R0402,4735.00,2363.62,90.000,NO
R4624,"Q_RES_0402LF-0,5%,1/16W,CHIP,CA",0,5%,R0402,4835.00,2363.62,270.000,NO
R4625,"Q_RES_0402LF-100,1%,1/16W,CHIPA",100,1%,R0402,6332.00,4826.62,0.000,NO
R4626,"Q_RES_0402LF-0,5%,1/16W,CHIP,CA",0,5%,R0402,5085.00,2233.62,180.000,NO
R4627,"Q_RES_0402LF-0,5%,1/16W,CHIP,CA",0,5%,R0402,5660.00,1028.62,180.000,NO
R4628,"Q_RES_0402LF-0,5%,1/16W,CHIP,CA",0,5%,R0402,5660.00,988.62,180.000,NO
R4629,"Q_RES_0402LF-0,5%,1/16W,CHIP,CA",0,5%,R0402,5901.00,583.62,270.000,YES
R4630,"Q_RES_0402LF-0,5%,1/16W,CHIP,CA",0,5%,R0402,4908.10,3135.82,0.000,NO
R4631,"Q_RES_0402LF-0,5%,1/16W,CHIP,CA",0,5%,R0402,5085.00,2098.62,0.000,NO
R4632,"Q_RES_0402LF-0,5%,1/16W,CHIP,CA",0,5%,R0402,4565.00,2133.62,180.000,NO
R4633,"Q_RES_0402LF-0,5%,1/16W,CHIP,CA",0,5%,R0402,4565.00,2223.62,180.000,NO
R4634,"Q_RES_0402LF-1K,1%,1/16W,EMPTYA",1K,1%,R0402,5040.00,2418.62,180.000,NO
R4635,"Q_RES_0402LF-10K,1%,1/16W,CHIPA",10K,1%,R0402,5040.00,2378.62,0.000,NO
R4636,"Q_RES_0402LF-200K,1%,1/16W,CHIA",200K,1%,R0402,5259.00,1127.00,270.000,YES
R4637,"Q_RES_0402LF-200K,1%,1/16W,CHIA",200K,1%,R0402,5259.00,1058.00,90.000,YES
R4638,"Q_RES_1206LF-243,1%,1/4W,CHIP,A",243,1%,R1206XN,6110.00,4975.00,270.000,NO
R4639,"Q_RES_1206LF-243,1%,1/4W,CHIP,A",243,1%,R1206XN,6190.00,4975.00,270.000,NO
R4640,"Q_RES_1206LF-243,1%,1/4W,CHIP,A",243,1%,R1206XN,6270.00,4975.00,270.000,NO
R4641,"Q_RES_1206LF-243,1%,1/4W,CHIP,A",243,1%,R1206XN,6350.00,4975.00,270.000,NO
R4642,"Q_RES_0402LF-1K,1%,1/16W,EMPTYA",1K,1%,R0402,1941.91,15529.40,180.000,NO
R4643,"Q_RES_0402LF-1K,1%,1/16W,EMPTYA",1K,1%,R0402,1942.83,15484.30,180.000,NO
R4644,"Q_RES_0402LF-1K,1%,1/16W,EMPTYA",1K,1%,R0402,1943.91,15396.78,180.000,NO
R4645,"Q_RES_0402LF-1K,1%,1/16W,EMPTYA",1K,1%,R0402,1944.50,15353.77,180.000,NO
R4646,"Q_RES_0402LF-1K,1%,1/16W,EMPTYA",1K,1%,R0402,1814.82,15354.62,0.000,NO
R4647,"Q_RES_0402LF-1K,1%,1/16W,CHIP,A",1K,1%,R0402,1814.48,15484.86,0.000,NO
R4648,"Q_RES_0402LF-1K,1%,1/16W,EMPTYA",1K,1%,R0402,1590.14,15754.09,270.000,NO
R4649,"Q_RES_0402LF-1K,1%,1/16W,EMPTYA",1K,1%,R0402,1545.80,15754.09,270.000,NO
R4650,"Q_RES_0402LF-1K,1%,1/16W,EMPTYA",1K,1%,R0402,1550.98,15646.65,90.000,NO
R4651,"Q_RES_0402LF-0,5%,1/16W,CHIP,CA",0,5%,R0402,1814.39,15578.74,0.000,NO
R4652,"Q_RES_0402LF-0,5%,1/16W,EMPTY,A",0,5%,R0402,10779.57,16639.50,0.000,NO
R4653,"Q_RES_0402LF-1K,1%,1/16W,CHIP,A",1K,1%,R0402,1814.39,15528.74,0.000,NO
R4654,"Q_RES_0402LF-1K,1%,1/16W,CHIP,A",1K,1%,R0402,1591.07,15645.93,90.000,NO
R4655,"Q_RES_0402LF-1K,1%,1/16W,EMPTYA",1K,1%,R0402,1177.33,15357.67,0.000,NO
R4656,"Q_RES_0402LF-1K,1%,1/16W,CHIP,A",1K,1%,R0402,1179.06,15480.27,0.000,NO
R4657,"Q_RES_0402LF-1K,1%,1/16W,EMPTYA",1K,1%,R0402,1317.81,15479.35,180.000,NO
R4658,"Q_RES_0402LF-1K,1%,1/16W,EMPTYA",1K,1%,R0402,1316.89,15418.74,180.000,NO
R4659,"Q_RES_0402LF-0,5%,1/16W,CHIP,CA",0,5%,R0402,755.85,15191.56,90.000,NO
R4660,"Q_RES_0402LF-0,5%,1/16W,CHIP,CA",0,5%,R0402,806.52,15191.61,90.000,NO
R4661,"Q_RES_0402LF-0,5%,1/16W,EMPTY,A",0,5%,R0402,755.85,15160.06,270.000,NO
R4662,"Q_RES_0402LF-0,5%,1/16W,EMPTY,A",0,5%,R0402,806.52,15160.11,270.000,NO
R4663,"Q_RES_0402LF-0,5%,1/16W,CHIP,CA",0,5%,R0402,1022.50,15625.53,270.000,NO
R4664,"Q_RES_0402LF-0,5%,1/16W,CHIP,CA",0,5%,R0402,971.83,15625.48,270.000,NO
R4665,"Q_RES_0402LF-0,5%,1/16W,EMPTY,A",0,5%,R0402,1022.50,15657.03,90.000,NO
R4666,"Q_RES_0402LF-0,5%,1/16W,EMPTY,A",0,5%,R0402,971.83,15656.98,90.000,NO
R4667,"Q_RES_0402LF-160K,1%,1/16W,EMPA",160K,1%,R0402,11034.57,16428.50,90.000,NO
R4668,"Q_RES_0402LF-10K,1%,1/16W,EMPTA",10K,1%,R0402,10994.57,16428.50,270.000,NO
R4669,"Q_RES_0402LF-160K,1%,1/16W,EMPA",160K,1%,R0402,11092.87,16714.40,270.000,NO
R4670,"Q_RES_0402LF-10K,1%,1/16W,EMPTA",10K,1%,R0402,11054.57,16714.50,90.000,NO
R4671,"Q_RES_0402LF-10K,1%,1/16W,EMPTA",10K,1%,R0402,10897.90,16709.63,180.000,NO
R4672,"Q_RES_0402LF-10K,1%,1/16W,EMPTA",10K,1%,R0402,10914.57,16428.50,90.000,NO
R4673,"Q_RES_0402LF-0,5%,1/16W,EMPTY,A",0,5%,R0402,10954.57,16428.50,270.000,NO
R4674,"Q_RES_0402LF-10K,1%,1/16W,CHIPA",10K,1%,R0402,12505.22,1411.68,225.000,YES
R4677,"Q_RES_0402LF-33.2,1%,1/16W,CHIA",33.2,1%,R0402,16484.00,2042.30,90.000,NO
R4678,"Q_RES_0402LF-1K,1%,1/16W,CHIP,A",1K,1%,R0402,16961.70,1983.30,180.000,YES
R4679,"Q_RES_0402LF-10K,1%,1/16W,CHIPA",10K,1%,R0402,17086.80,1737.50,270.000,YES
R4680,"Q_RES_0402LF-100K,1%,1/16W,CHIA",100K,1%,R0402,17055.70,1997.20,180.000,YES
R4681,"Q_RES_0402LF-100K,1%,1/16W,CHIA",100K,1%,R0402,16443.60,2042.40,90.000,NO
R4682,"Q_RES_0402LF-100K,1%,1/16W,CHIA",100K,1%,R0402,17128.20,1737.80,90.000,YES
R4684,"Q_RES_0402LF-0,5%,1/16W,EMPTY,A",0,5%,R0402,11738.80,16051.00,0.000,NO
R4685,"Q_RES_0402LF-10.5K,1%,1/16W,EMA",10.5K,1%,R0402,11738.80,16011.00,0.000,NO
R4686,"Q_RES_0402LF-10.5K,1%,1/16W,EMA",10.5K,1%,R0402,11375.50,15976.30,180.000,NO
R4687,"Q_RES_0402LF-4.7K,1%,1/16W,EMPA",4.7K,1%,R0402,11576.61,16338.80,0.000,NO
R4688,"Q_RES_0402LF-4.7K,1%,1/16W,EMPA",4.7K,1%,R0402,11576.61,16300.90,0.000,NO
R4689,"Q_RES_0402LF-33.2,1%,1/16W,EMPA",33.2,1%,R0402,11805.71,16129.60,0.000,NO
R4690,"Q_RES_0402LF-33.2,1%,1/16W,EMPA",33.2,1%,R0402,11576.61,16223.40,0.000,NO
R4691,"Q_RES_0402LF-0,5%,1/16W,EMPTY,A",0,5%,R0402,11603.10,16297.60,90.000,YES
R4692,"Q_RES_0402LF-4.7K,1%,1/16W,EMPA",4.7K,1%,R0402,11576.61,16262.20,0.000,NO
R4693,"Q_RES_0402LF-0,5%,1/16W,EMPTY,A",0,5%,R0402,11131.40,16714.91,90.000,NO
R4694,"Q_RES_0402LF-1K,1%,1/16W,CHIP,A",1K,1%,R0402,1814.71,15397.23,0.000,NO
R4695,"Q_RES_0402LF-0,5%,1/16W,CHIP,CA",0,5%,R0402,7162.02,16057.46,270.000,YES
R4696,"Q_RES_0402LF-0,5%,1/16W,CHIP,CA",0,5%,R0402,7081.75,16073.11,90.000,YES
R4697,"Q_RES_0402LF-0,5%,1/16W,CHIP,CA",0,5%,R0402,6013.99,4546.00,180.000,NO
R4701,"Q_RES_0402LF-4.7K,5%,1/16W,CHIA",4.7K,5%,R0402,9539.00,16653.00,90.000,YES
R4702,"Q_RES_0402LF-560,1%,1/16W,CHIPA",560,1%,R0402,14478.00,2927.00,90.000,NO
R4703,"Q_RES_0402LF-560,1%,1/16W,CHIPA",560,1%,R0402,7587.58,16679.41,270.000,YES
R4704,"Q_RES_0402LF-560,1%,1/16W,CHIPA",560,1%,R0402,14517.00,2927.00,270.000,NO
R4705,"Q_RES_0402LF-560,1%,1/16W,CHIPA",560,1%,R0402,7626.70,16679.89,90.000,YES
R4706,"Q_RES_0402LF-560,1%,1/16W,CHIPA",560,1%,R0402,14556.00,2927.00,90.000,NO
R4707,"Q_RES_0402LF-560,1%,1/16W,CHIPA",560,1%,R0402,7687.14,16679.41,270.000,YES
R4708,"Q_RES_0402LF-0,5%,1/16W,CHIP,CA",0,5%,R0402,7641.30,1146.80,270.000,NO
R4709,"Q_RES_0402LF-0,5%,1/16W,EMPTY,A",0,5%,R0402,6819.53,1234.20,180.000,NO
R4710,"Q_RES_0402LF-4.7K,5%,1/16W,CHIA",4.7K,5%,R0402,8325.00,2687.14,270.000,NO
R4711,"Q_RES_0402LF-249,1%,1/16W,CHIPA",249,1%,R0402,8044.62,2698.00,0.000,NO
R4712,"Q_RES_0402LF-100K,1%,1/16W,CHIA",100K,1%,R0402,7914.20,4025.00,0.000,NO
R4713,"Q_RES_0402LF-100K,1%,1/16W,CHIA",100K,1%,R0402,7965.46,4146.26,90.000,NO
R4714,"Q_RES_0402LF-33.2,1%,1/16W,CHIA",33.2,1%,R0402,9568.71,5407.27,0.000,NO
R4715,"Q_RES_0402LF-33.2,1%,1/16W,CHIA",33.2,1%,R0402,9568.72,5368.06,0.000,NO
R4716,"Q_RES_0402LF-8.45K,1%,1/16W,EMA",8.45K,1%,R0402,8509.00,4769.00,0.000,NO
R4717,"Q_RES_0402LF-0,5%,1/16W,EMPTY,A",0,5%,R0402,8509.00,4691.00,180.000,NO
R4718,"Q_RES_0402LF-33.2,1%,1/16W,EMPA",33.2,1%,R0402,8208.40,4729.00,180.000,NO
R4719,"Q_RES_0402LF-10K,1%,1/16W,CHIPA",10K,1%,R0402,8208.40,4689.00,180.000,NO
R4720,"Q_RES_0402LF-0,5%,1/16W,CHIP,CA",0,5%,R0402,5932.40,895.20,90.000,NO
R4721,"Q_RES_0402LF-0,5%,1/16W,CHIP,CA",0,5%,R0402,9145.00,16654.00,270.000,YES
R4722,"Q_RES_0402LF-10K,1%,1/16W,CHIPA",10K,1%,R0402,8070.70,4410.60,180.000,NO
R4723,"Q_RES_0402LF-33.2,1%,1/16W,CHIA",33.2,1%,R0402,8070.70,4451.00,180.000,NO
R4724,"Q_RES_0402LF-100K,1%,1/16W,EMPA",100K,1%,R0402,4127.00,16152.00,180.000,NO
R4725,"Q_RES_0402LF-4.7K,5%,1/16W,CHIA",4.7K,5%,R0402,4202.00,16166.00,180.000,NO
R4726,"Q_RES_0402LF-4.7K,5%,1/16W,CHIA",4.7K,5%,R0402,4127.00,16074.00,0.000,NO
R4727,"Q_RES_0402LF-10K,1%,1/16W,CHIPA",10K,1%,R0402,4127.00,16113.00,0.000,NO
R4728,"Q_RES_0402LF-0,5%,1/16W,CHIP,CA",0,5%,R0402,741.00,16173.00,90.000,NO
R4729,"Q_RES_0402LF-0,5%,1/16W,CHIP,CA",0,5%,R0402,780.00,16173.00,90.000,NO
R4730,"Q_RES_0402LF-10K,1%,1/16W,CHIPA",10K,1%,R0402,14009.00,15902.00,0.000,NO
R4731,"Q_RES_0402LF-100K,1%,1/16W,EMPA",100K,1%,R0402,14009.00,15940.00,180.000,NO
R4732,"Q_RES_0402LF-4.7K,5%,1/16W,CHIA",4.7K,5%,R0402,14164.00,15937.00,180.000,NO
R4733,"Q_RES_0402LF-4.7K,5%,1/16W,CHIA",4.7K,5%,R0402,14009.00,15864.00,0.000,NO
R4734,"Q_RES_0402LF-0,5%,1/16W,CHIP,CA",0,5%,R0402,819.00,16173.00,90.000,NO
R4735,"Q_RES_0402LF-0,5%,1/16W,CHIP,CA",0,5%,R0402,858.00,16173.00,90.000,NO
R4736,"Q_RES_0402LF-0,5%,1/16W,CHIP,CA",0,5%,R0402,980.00,16518.00,180.000,NO
R4737,"Q_RES_0402LF-10K,1%,1/16W,CHIPA",10K,1%,R0402,14424.00,16068.00,0.000,NO
R4738,"Q_RES_0402LF-100K,1%,1/16W,EMPA",100K,1%,R0402,14424.00,16110.00,180.000,NO
R4739,"Q_RES_0402LF-4.7K,5%,1/16W,CHIA",4.7K,5%,R0402,14559.65,16128.00,0.000,NO
R4740,"Q_RES_0402LF-4.7K,5%,1/16W,CHIA",4.7K,5%,R0402,14424.00,16026.00,0.000,NO
R4741,"Q_RES_0402LF-0,5%,1/16W,CHIP,CA",0,5%,R0402,980.00,16558.00,180.000,NO
R4742,"Q_RES_0402LF-0,5%,1/16W,CHIP,CA",0,5%,R0402,650.00,16777.00,270.000,NO
R4745,"Q_RES_0402LF-10K,1%,1/16W,CHIPA",10K,1%,R0402,17337.80,3947.70,90.000,NO
R4746,"Q_RES_0402LF-33.2,1%,1/16W,CHIA",33.2,1%,R0402,17298.10,3947.70,90.000,NO
R4747,"Q_RES_0402LF-33.2,1%,1/16W,CHIA",33.2,1%,R0402,17376.60,3947.70,90.000,NO
R4748,"Q_RES_0402LF-0,5%,1/16W,EMPTY,A",0,5%,R0402,17382.90,4188.40,270.000,NO
R4749,"Q_RES_0402LF-0,5%,1/16W,EMPTY,A",0,5%,R0402,17431.70,4068.00,90.000,NO
R4750,"Q_RES_0402LF-49.9,1%,1/16W,CHIA",49.9,1%,R0402,17342.90,4188.40,90.000,NO
R4751,"Q_RES_0402LF-33.2,1%,1/16W,CHIA",33.2,1%,R0402,7358.00,3697.25,90.000,NO
R4752,"Q_RES_0402LF-0,5%,1/16W,CHIP,CA",0,5%,R0402,18172.99,4174.32,180.000,NO
R4753,"Q_RES_0402LF-0,5%,1/16W,CHIP,CA",0,5%,R0402,1125.12,2748.00,0.000,NO
R4754,"Q_RES_0402LF-33.2,1%,1/16W,CHIA",33.2,1%,R0402,5369.50,4503.30,0.000,NO
R4755,"Q_RES_0402LF-33.2,1%,1/16W,CHIA",33.2,1%,R0402,5369.50,4423.76,0.000,NO
R4756,"Q_RES_0402LF-10K,1%,1/16W,CHIPA",10K,1%,R0402,5369.50,4463.96,0.000,NO
R4757,"Q_RES_0402LF-0,5%,1/16W,EMPTY,A",0,5%,R0402,5369.50,4542.70,180.000,NO
R4758,"Q_RES_0402LF-0,5%,1/16W,EMPTY,A",0,5%,R0402,5665.17,4467.06,180.000,NO
R4759,"Q_RES_0402LF-49.9,1%,1/16W,CHIA",49.9,1%,R0402,5665.40,4426.56,0.000,NO
R4760,"Q_RES_0402LF-33.2,1%,1/16W,CHIA",33.2,1%,R0402,7270.00,3697.25,90.000,NO
R4761,"Q_RES_0402LF-10K,1%,1/16W,CHIPA",10K,1%,R0402,1254.00,2748.00,180.000,NO
R4762,"Q_RES_0402LF-10K,1%,1/16W,CHIPA",10K,1%,R0402,18172.99,4134.32,180.000,NO
R4763,"Q_RES_0402LF-10K,1%,1/16W,CHIPA",10K,1%,R0402,5243.80,4784.92,0.000,NO
R4764,"Q_RES_0402LF-10K,1%,1/16W,CHIPA",10K,1%,R0402,17788.10,4536.40,90.000,NO
R4765,"Q_RES_0402LF-33.2,1%,1/16W,CHIA",33.2,1%,R0402,7225.00,3697.25,90.000,NO
R4766,"Q_RES_0402LF-49.9,1%,1/16W,CHIA",49.9,1%,R0402,12187.30,1308.10,180.000,YES
R4767,"Q_RES_0402LF-49.9,1%,1/16W,CHIA",49.9,1%,R0402,8561.90,1886.10,90.000,NO
R4768,"Q_RES_0402LF-10K,1%,1/16W,CHIPA",10K,1%,R0402,12187.00,1346.00,180.000,YES
R4769,"Q_RES_0402LF-100K,1%,1/16W,CHIA",100K,1%,R0402,7203.33,16765.00,0.000,NO
R4770,"Q_RES_0402LF-0,5%,1/16W,CHIP,CA",0,5%,R0402,6824.40,1173.70,90.000,YES
R4771,"Q_RES_0402LF-33.2,1%,1/16W,CHIA",33.2,1%,R0402,7314.00,3697.25,90.000,NO
R4772,"Q_RES_0402LF-10K,1%,1/16W,EMPTA",10K,1%,R0402,7984.00,3647.00,90.000,NO
R4773,"Q_RES_0402LF-10K,1%,1/16W,EMPTA",10K,1%,R0402,8265.00,4492.00,180.000,NO
R4774,"Q_RES_0402LF-17.8K,1%,1/16W,EMA",17.8K,1%,R0402,8060.00,3647.00,90.000,NO
R4775,"Q_RES_0402LF-5.11K,1%,1/16W,EMA",5.11K,1%,R0402,8098.00,3647.00,270.000,NO
R4776,"Q_RES_0402LF-17.8K,1%,1/16W,EMA",17.8K,1%,R0402,8363.00,4229.00,90.000,NO
R4777,"Q_RES_0402LF-5.11K,1%,1/16W,EMA",5.11K,1%,R0402,8402.00,4229.00,270.000,NO
R4778,"Q_RES_0402LF-1M,1%,1/16W,CHIP,A",1M,1%,R0402,8096.00,3846.00,270.000,NO
R4779,"Q_RES_0402LF-1M,1%,1/16W,CHIP,A",1M,1%,R0402,8490.00,4397.00,90.000,NO
R4780,"Q_RES_0402LF-0,5%,1/16W,CHIP,CA",0,5%,R0402,10089.42,2965.70,90.000,YES
R4781,"Q_RES_0402LF-0,5%,1/16W,CHIP,CA",0,5%,R0402,1455.47,4976.40,0.000,YES
R4782,"Q_RES_0402LF-33.2,1%,1/16W,EMPA",33.2,1%,R0402,8138.00,3846.00,90.000,NO
R4783,"Q_RES_0402LF-33.2,1%,1/16W,EMPA",33.2,1%,R0402,8283.00,4229.00,270.000,NO
R4784,"Q_RES_0402LF-10K,1%,1/16W,EMPTA",10K,1%,R0402,8180.00,3846.00,90.000,NO
R4785,"Q_RES_0402LF-10K,1%,1/16W,EMPTA",10K,1%,R0402,8324.00,4229.00,270.000,NO
R4786,"Q_RES_0402LF-10K,1%,1/16W,EMPTA",10K,1%,R0402,12180.00,936.00,180.000,NO
R4787,"Q_RES_0402LF-1M,1%,1/16W,EMPTYA",1M,1%,R0402,11968.00,1016.00,180.000,NO
R4788,"Q_RES_0402LF-33.2,1%,1/16W,EMPA",33.2,1%,R0402,12300.00,984.00,0.000,NO
R4789,"Q_RES_0402LF-10K,1%,1/16W,EMPTA",10K,1%,R0402,12300.00,942.00,0.000,NO
R4790,"Q_RES_0402LF-4.75K,1%,1/16W,EMA",4.75K,1%,R0402,11968.00,932.00,0.000,NO
R4791,"Q_RES_0402LF-2K,1%,1/16W,EMPTYA",2K,1%,R0402,11968.00,890.00,180.000,NO
R4792,"Q_RES_0402LF-10K,1%,1/16W,EMPTA",10K,1%,R0402,7117.80,16189.30,90.000,NO
R4793,"Q_RES_0402LF-1M,1%,1/16W,EMPTYA",1M,1%,R0402,7238.20,16189.20,270.000,NO
R4794,"Q_RES_0402LF-33.2,1%,1/16W,EMPA",33.2,1%,R0402,7267.20,16459.40,90.000,NO
R4795,"Q_RES_0402LF-160K,1%,1/16W,EMPA",160K,1%,R0402,7226.30,16514.70,90.000,NO
R4796,"Q_RES_0402LF-10K,1%,1/16W,EMPTA",10K,1%,R0402,7188.30,16514.70,270.000,NO
R4797,"Q_RES_0402LF-10K,1%,1/16W,EMPTA",10K,1%,R0402,7306.80,16459.40,90.000,NO
R4798,"Q_RES_0402LF-10K,1%,1/16W,CHIPA",10K,1%,R0402,14378.00,16245.00,180.000,NO
R4799,"Q_RES_0402LF-100K,1%,1/16W,EMPA",100K,1%,R0402,14378.00,16203.00,0.000,NO
R4800,"Q_RES_0402LF-4.7K,5%,1/16W,CHIA",4.7K,5%,R0402,14124.75,16222.00,0.000,NO
R4801,"Q_RES_0402LF-4.7K,5%,1/16W,CHIA",4.7K,5%,R0402,14378.00,16287.00,180.000,NO
R4802,"Q_RES_0402LF-0,5%,1/16W,CHIP,CA",0,5%,R0402,610.00,16777.00,270.000,NO
R4803,"Q_RES_0402LF-0,5%,1/16W,CHIP,CA",0,5%,R0402,13323.00,2049.00,180.000,YES
R4804,"Q_RES_0402LF-1K,1%,1/16W,EMPTYA",1K,1%,R0402,8289.77,4132.60,0.000,NO
R4805,"Q_RES_0402LF-1K,1%,1/16W,EMPTYA",1K,1%,R0402,10985.50,16720.30,0.000,NO
R4806,"Q_RES_0402LF-1K,1%,1/16W,CHIP,A",1K,1%,R0402,8664.86,3986.20,180.000,NO
R4807,"Q_RES_0402LF-0,5%,1/16W,EMPTY,A",0,5%,R0402,8586.20,4953.00,180.000,NO
R4808,"Q_RES_0402LF-100K,1%,1/16W,EMPA",100K,1%,R0402,8257.63,4940.00,0.000,NO
R4809,"Q_RES_0402LF-0,5%,1/16W,CHIP,CA",0,5%,R0402,5486.09,368.62,90.000,YES
R4892,"Q_RES_0402LF-49.9,1%,1/16W,EMPA",49.9,1%,R0402,11206.10,16123.20,0.000,NO
R4893,"Q_RES_0402LF-49.9,1%,1/16W,EMPA",49.9,1%,R0402,11205.80,16084.20,0.000,NO
R4894,"Q_RES_0402LF-0,5%,1/16W,EMPTY,A",0,5%,R0402,11737.60,16129.60,0.000,NO
R4895,"Q_RES_0402LF-0,5%,1/16W,EMPTY,A",0,5%,R0402,11738.80,16091.00,0.000,NO
R4896,"Q_RES_0402LF-0,5%,1/16W,EMPTY,A",0,5%,R0402,11375.50,16016.30,180.000,NO
R4901,"Q_RES_0402LF-82K,1%,1/16W,CHIPA",82K,1%,R0402,7395.38,16727.55,270.000,NO
R5234,"Q_RES_0402LF-0,5%,1/16W,CHIP,CA",0,5%,R0402,1436.56,15981.55,180.000,YES
R5236,"Q_RES_0402LF-0,5%,1/16W,CHIP,CA",0,5%,R0402,1436.56,16026.66,180.000,YES
R5238,"Q_RES_0402LF-3.9K,5%,1/16W,EMPA",3.9K,5%,R0402,322.55,4455.19,0.000,YES
R5377,"Q_RES_0402LF-0,5%,1/16W,CHIP,CA",0,5%,R0402,5612.20,1848.62,0.000,NO
R5487,"Q_RES_0402LF-0,5%,1/16W,CHIP,CA",0,5%,R0402,18012.65,1655.65,0.000,NO
SW5,SW_PUSHBUTTON4P_24-SW4S_DTSM-6A,,,SW4S_DTSM-61N,16046.08,1436.55,0.000,NO
U1_BL,"TP_TP_BOM ONLY-NA,TP12_BOM",,,TP30,19246.35,18523.55,0.000,NO
U1_BP,"TP_TP_BOM ONLY-NA,TP12_BOM",,,TP30,19376.55,18532.85,0.000,NO
U1_DC,"TP_TP_BOM ONLY-NA,TP12_BOM",,,TP30,19375.05,18425.25,0.000,NO
U2_BL,"TP_TP_BOM ONLY-NA,TP12_BOM",,,TP30,19552.95,18539.85,0.000,NO
U2_BP,"TP_TP_BOM ONLY-NA,TP12_BOM",,,TP30,19629.35,18539.05,0.000,NO
U2_DC,"TP_TP_BOM ONLY-NA,TP12_BOM",,,TP30,19247.95,18420.75,0.000,NO
U1,SOCKET4677_AZIF0045P001C01CS-SA,,,SOCKET4677_82X64-5XA_H466,4406.70,9912.20,90.000,NO
U2,SOCKET4677_AZIF0045P001C01CS-SA,,,SOCKET4677_82X64-5XA_H466,14168.12,9912.20,90.000,NO
U4,EMMITSBURG_REV0P9-GFNOCPU04302A,,,BGA749_22X23,13263.77,1907.49,0.000,NO
U13,"9SQ440NQQI8-9SQ440NQQI8,SMLF,IA",,,QFN100_TH_0-5_8X8,10066.25,3919.81,0.000,NO
U14,"QS3VH257QG8_SMLF-QS3VH257QG8,IA",,,QSOP16_0-635_4-89X3-9,3137.47,5814.08,0.000,NO
U15,"QS3VH257QG8_SMLF-QS3VH257QG8,IA",,,QSOP16_0-635_4-89X3-9,11754.58,5985.77,180.000,YES
U16,"74LVC1G66GV-74LVC1G66GV,SMLF,IA",,,SC74AXA,8542.77,7654.25,0.000,YES
U17,"74CBTLV3126PW-74CBTLV3126PW,SMA",,,TSSOP14,14478.83,2304.48,0.000,NO
U18,"74CBTLV3126PW-74CBTLV3126PW,SMA",,,TSSOP14,14473.80,2589.42,0.000,NO
U21,"NC7SB3157_SMLF-NC7SB3157P6X,NCA",,,SC70-6,8147.87,7613.15,0.000,YES
U22,"NC7SB3157_SMLF-NC7SB3157P6X,NCA",,,SC70-6,8370.57,7615.35,0.000,YES
U23,"74LVC1G02GW_SMLF-74LVC1G02GW,IA",,,SOT353_Q,7752.24,7608.96,0.000,YES
U28,"PCA9617ADP-PCA9617ADP,SMLF,IC,A",,,TSSOP8_3XB,14546.34,7369.36,0.000,YES
U29,"PCA9617ADP-PCA9617ADP,SMLF,IC,A",,,TSSOP8_3XB,462.84,7589.56,0.000,YES
U30,"PCA9517AD-PCA9517AD,SMLF,IC,ALA",,,SOIC8,15484.89,6116.38,270.000,NO
U31,"PCA9517AD-PCA9517AD,SMLF,IC,ALA",,,SOIC8,8895.00,8973.62,90.000,NO
U36,"TCA9548APWR-TCA9548APWR,SMLF,IA",,,TSSOP24XA,4760.18,5274.47,0.000,NO
U38,"9QXL2001BNHGI8-9QXL2001BNHGI8,A",,,GQFN80_TH_0-5_6X6,9251.89,4990.86,180.000,NO
U39,"TCA9548APWR-TCA9548APWR,SMLF,IA",,,TSSOP24XA,2408.49,4378.99,0.000,NO
U49,"MOSFET_N_SMLF-BSS138K,BSS138K,A",,,SOT23_GDSXD,17738.51,4337.93,180.000,NO
U50,"74LVC1G08W57-74LVC1G08W5-7,SMLA",,,SOT25-5_0-95_3X1-6,5171.84,4654.57,270.000,NO
U51,"PCA9555APW-PCA9555APW,SMLF,IC,A",,,TSSOP24XB,5540.70,4772.12,0.000,NO
U52,"APX80929SAG7-APX809-29SAG-7,SMA",,,SOT23_123XI,15304.15,1406.74,90.000,NO
U53,"74LVC1G08W57-74LVC1G08W5-7,SMLA",,,SOT25-5_0-95_3X1-6,3526.00,1522.02,0.000,NO
U58,"74LVC2G07DW7-74LVC2G07DW-7,SMLA",,,SOT363_0-65_2X1-25XC,971.40,3002.62,0.000,NO
U59,"74LVC2G07DW7-74LVC2G07DW-7,SMLA",,,SOT363_0-65_2X1-25XC,971.40,2827.62,0.000,NO
U60,"NC7SB3157_SMLF-NC7SB3157P6X,NCA",,,SC70-6,13273.32,765.14,270.000,NO
U61,"NC7SB3157_SMLF-NC7SB3157P6X,NCA",,,SC70-6,13164.78,850.70,270.000,NO
U62,"BAS70057F-BAS70-05-7-F,SMLF,ICA",,,SOT23_123XB,11947.13,1141.64,90.000,NO
U64,"M24128BWMN6TP-M24128-BWMN6TP,SA",,,SOIC8XH,11196.65,3717.35,0.000,NO
U66,"74LVC1G126SE7-74LVC1G126SE-7,SA",,,SOT353_0-65_2X1-25,18093.69,3878.52,0.000,NO
U67,"74CBTLV3126PW-74CBTLV3126PW,SMA",,,TSSOP14,7764.77,3039.08,0.000,YES
U68,"74CBTLV3126PW-74CBTLV3126PW,SMA",,,TSSOP14,8340.00,2789.48,180.000,YES
U70,"MOSFET_N_SMLF-BSS138K,BSS138K,A",,,SOT23_GDSXD,10633.30,3699.62,90.000,NO
U75,"74LVC1G17GW-74LVC1G17GW,SMLF,IA",,,TSSOP5,17930.48,1533.03,0.000,NO
U82,"74LVC1G126SE7-74LVC1G126SE-7,SA",,,SOT353_0-65_2X1-25,18268.25,1798.02,0.000,NO
U83,"GTL2014PW-GTL2014PW,SMLF,IC,ALA",,,TSSOP14,14868.84,3902.88,270.000,NO
U84,"GTL2014PW-GTL2014PW,SMLF,IC,ALA",,,TSSOP14,14632.77,3904.96,90.000,NO
U85,"NC7SB3157_SMLF-NC7SB3157P6X,NCA",,,SC70-6,4131.15,2367.26,0.000,NO
U86,"74CBTLV3126PW-74CBTLV3126PW,SMA",,,TSSOP14,4049.15,2176.26,0.000,NO
U87,"MOSFET_N_SMLF-BSS138K,BSS138K,A",,,SOT23_GDSXD,3672.20,2213.62,0.000,NO
U89,"MOSFET_N_SMLF-BSS138K,BSS138K,A",,,SOT23_GDSXD,8548.20,4264.62,90.000,NO
U90,"PI6CV304LE-PI6CV304LE,SMLF,IC,A",,,TSSOP8,8438.76,699.48,270.000,NO
U94,ADM1086AKSZREEL7-ADM1086AKSZ-RA,,,SC70-6_0-65_2X1-25XA,8422.59,5154.47,0.000,NO
U95,"74LVC1G07SE7-74LVC1G07SE-7,SMLA",,,SOT353_0-65_2X1-25,8422.70,5030.82,180.000,NO
U96,"NX3L2267GM-NX3L2267GM,SMLF,IC,A",,,XQFN10,5011.36,3053.98,180.000,NO
U97,"NX3L2267GM-NX3L2267GM,SMLF,IC,A",,,XQFN10,4677.36,3060.98,180.000,NO
U98,"PCA9306DP1-PCA9306DP1,SMLF,IC,A",,,TSSOP8_3,6072.15,2261.26,0.000,NO
U99,"RT9818C44GV-RT9818C-44GV,SMLF,A",,,SOT23_123_2-89X1-6,16450.30,1910.70,270.000,NO
U102,"INA183A1IDBVR-INA183A1IDBVR,SMA",,,SOT23-5_0-95_2-9X1-6XD,17481.87,13197.68,0.000,NO
U103,"INA183A1IDBVR-INA183A1IDBVR,SMA",,,SOT23-5_0-95_2-9X1-6XD,643.90,13223.28,0.000,NO
U104,"74LVC1G07GV-74LVC1G07GV,SMLF,IA",,,SC-74A_2-9X1-5,15356.57,1114.56,90.000,NO
U117,"TPS3895ADRYR-TPS3895ADRYR,SMLFA",,,SON6,8363.89,5278.17,0.000,NO
U134,"74LVC2G07DW7-74LVC2G07DW-7,SMLA",,,SOT363_0-65_2X1-25XC,6131.59,2549.66,0.000,NO
U142,"NC7SB3157_SMLF-NC7SB3157P6X,NCA",,,SC70-6,12100.84,2324.32,90.000,NO
U143,"PCA9545APW-PCA9545APW,SMLF,IC,A",,,TSSOP20_0-65_6-5X4-4,6107.72,3001.77,180.000,NO
U145,"74LVC1G126SE7-74LVC1G126SE-7,SA",,,SOT353_0-65_2X1-25,5713.84,2547.32,0.000,NO
U150,"74LVC2G17GW-74LVC2G17GW,SMLF,IA",,,SOT363,5545.00,3090.57,0.000,NO
U154,"74LVC1G07SE7-74LVC1G07SE-7,SMLA",,,SOT353_0-65_2X1-25,13025.54,550.62,0.000,NO
U157,"74LVC1G07GV-74LVC1G07GV,SMLF,IA",,,SC-74A_2-9X1-5,12282.31,578.40,180.000,NO
U158,MOSFET_NCH_GDS_ESD_PROTECTED-2A,,,SOT23_GDSXC,7976.30,5059.72,180.000,NO
U175,"LTC4307CMS8-LTC4307CMS8,SMLF,IA",,,MSOP8,6452.25,16741.94,270.000,NO
U176,"LTC4307CMS8-LTC4307CMS8,SMLF,EA",,,MSOP8,14313.23,15667.71,0.000,NO
U181,"PCA9539RPW-PCA9539RPW,SMLF,IC,A",,,TSSOP24XB,681.69,16425.29,90.000,NO
U192,"LTC4307CMS8-LTC4307CMS8,SMLF,IA",,,MSOP8,7077.19,16603.51,270.000,NO
U193,"MAX11617EEET-MAX11617EEE+T,SMLA",,,QSOP16_0-635_4-9X3-89,1560.77,3956.35,0.000,NO
U194,"LTC4307CMS8-LTC4307CMS8,SMLF,IA",,,MSOP8,1796.18,17115.17,0.000,NO
U195,"74LVC2G17GW-74LVC2G17GW,SMLF,IA",,,SOT363,6786.20,16708.62,0.000,NO
U196,"74LVC2G17GW-74LVC2G17GW,SMLF,IA",,,SOT363,4583.20,16432.82,0.000,NO
U200,"LTC4307CMS8-LTC4307CMS8,SMLF,IA",,,MSOP8,1536.72,17291.28,180.000,NO
U204,"74LVC1G126SE7-74LVC1G126SE-7,SA",,,SOT353_0-65_2X1-25,14316.80,15878.82,0.000,NO
U205,"TPS3700DDCR-TPS3700DDCR,SMLF,EA",,,SOT23-6XF,8477.85,4107.60,180.000,NO
U206,LT6700CS61TRPBF-LT6700CS6-1#TRA,,,TSOT23-6_0-95_2-9X1-625,8478.41,3928.80,0.000,NO
U207,"74LVC1G17GW-74LVC1G17GW,SMLF,IA",,,TSSOP5,3985.00,1583.92,0.000,NO
U208,"74LVC1G08W57-74LVC1G08W5-7,SMLA",,,SOT25-5_0-95_3X1-6,17694.10,4492.62,270.000,NO
U209,"PCA9555APW-PCA9555APW,SMLF,IC,A",,,TSSOP24XB,18020.62,4526.24,0.000,NO
U210,"74LVC1G08W57-74LVC1G08W5-7,SMLA",,,SOT25-5_0-95_3X1-6,15461.41,1429.87,90.000,NO
U211,"74LVC2G07DW7-74LVC2G07DW-7,SMLA",,,SOT363_0-65_2X1-25XC,18019.08,4213.34,0.000,NO
U212,"74LVC2G07DW7-74LVC2G07DW-7,SMLA",,,SOT363_0-65_2X1-25XC,18019.19,4080.56,0.000,NO
U215,"MOSFET_N_SMLF-BSS138K,BSS138K,A",,,SOT23_GDSXD,5183.10,4440.62,180.000,NO
U216,"APX80929SAG7-APX809-29SAG-7,SMA",,,SOT23_123XI,3168.05,1523.38,180.000,NO
U217,"74LVC1G126SE7-74LVC1G126SE-7,SA",,,SOT353_0-65_2X1-25,10961.21,759.02,180.000,NO
U218,"74LVC1G07GV-74LVC1G07GV,SMLF,IA",,,SC-74A_2-9X1-5,4466.40,1124.71,90.000,NO
U219,"74LVC1G07GV-74LVC1G07GV,SMLF,IA",,,SC-74A_2-9X1-5,10839.49,594.22,0.000,NO
U222,"74CBTLV3126PW-74CBTLV3126PW,SMA",,,TSSOP14,8239.99,3041.88,0.000,YES
U223,"74CBTLV3126PW-74CBTLV3126PW,SMA",,,TSSOP14,7813.95,2791.46,0.000,YES
U224,"74LVC1G126SE7-74LVC1G126SE-7,SA",,,SOT353_0-65_2X1-25,18088.09,3686.12,0.000,NO
U225,"74LVC1G126SE7-74LVC1G126SE-7,SA",,,SOT353_0-65_2X1-25,6022.20,4303.62,90.000,NO
U235,"PCA9617ADP-PCA9617ADP,SMLF,IC,A",,,TSSOP8_3XB,4088.80,1249.27,180.000,NO
U236,"PCA9617ADP-PCA9617ADP,SMLF,IC,A",,,TSSOP8_3XB,17514.70,1758.67,0.000,NO
U237,PI3EQX12902AZLEX-PI3EQX12902AZA,,,TQFN30_TH_0-4_4-5X2-5,862.74,15380.94,90.000,NO
U239,"74LVC1G126SE7-74LVC1G126SE-7,SA",,,SOT353_0-65_2X1-25,5876.15,1672.76,0.000,NO
U240,"74LVC2G08DP-74LVC2G08DP,SMLF,IA",,,TSSOP8_0-65_3X3,17514.10,1555.62,0.000,NO
U241,"74LVC2G08DP-74LVC2G08DP,SMLF,IA",,,TSSOP8_0-65_3X3,210.80,2941.72,0.000,NO
U242,"74LVC2G08DP-74LVC2G08DP,SMLF,IA",,,TSSOP8_0-65_3X3,516.80,2946.72,0.000,NO
U243,"NC7SB3157_SMLF-NC7SB3157P6X,NCB",,,SC70-6,5732.10,1447.32,0.000,NO
U244,"NC7SB3157_SMLF-NC7SB3157P6X,NCB",,,SC70-6,5753.10,1305.42,0.000,NO
U245,"NC7SB3157_SMLF-NC7SB3157P6X,NCB",,,SC70-6,5354.60,1318.02,0.000,NO
U246,"NC7SB3157_SMLF-NC7SB3157P6X,NCB",,,SC70-6,5354.60,1498.02,0.000,NO
U247,"9FGL0251DKILFT-9FGL0251DKILFT,A",,,VFQFPN24_TH_0-5_4X4XI,9267.89,9867.34,180.000,NO
U248,"74LVC1G32GW_SMLF-74LVC1G32GW,IA",,,SOT353_Q,4748.16,1496.28,0.000,NO
U249,LCMXO3LF9400C5BG484C-LCMXO3LF-A,,,BGA484_0-8_19X19_H67,7029.75,4463.60,90.000,NO
U252,"74LVC2G17GW-74LVC2G17GW,SMLF,IA",,,SOT363,1062.20,16853.62,0.000,NO
U253,"74LVC2G17GW-74LVC2G17GW,SMLF,IA",,,SOT363,6552.20,17203.62,0.000,NO
U255,"74LVC2G07DW7-74LVC2G07DW-7,SMLA",,,SOT363_0-65_2X1-25XC,4161.26,15500.46,180.000,NO
U256,"74LVC2G17GW-74LVC2G17GW,SMLF,IA",,,SOT363,1062.20,16963.62,0.000,NO
U257,"74LVC2G07DW7-74LVC2G07DW-7,SMLA",,,SOT363_0-65_2X1-25XC,4400.19,15832.49,90.000,NO
U259,SN74LVC2G07DCKR_SMLF-SN74LVC2GA,,,SC70-6,5349.15,1647.26,0.000,NO
U263,"ISL28022FRZT-ISL28022FRZ-T,SMLB",,,QFN16_TH_0-5_3X3XH,2862.53,1548.03,0.000,NO
U264,"ISL28022FRZT-ISL28022FRZ-T,SMLB",,,QFN16_TH_0-5_3X3XH,6011.56,2059.78,0.000,NO
U265,"ISL28022FRZT-ISL28022FRZ-T,SMLB",,,QFN16_TH_0-5_3X3XH,8235.14,1368.98,90.000,NO
U266,"ISL28022FRZT-ISL28022FRZ-T,SMLB",,,QFN16_TH_0-5_3X3XH,17349.92,3703.84,180.000,NO
U268,"GL852GOHY60-GL852G-OHY60,SMLF,A",,,QFN28_THXL,553.74,3903.01,270.000,NO
U269,ADC128D818CIMTXNOPB-ADC128D818A,,,TSSOP16XC,1169.91,4304.47,0.000,NO
U270,"LM75BD-LM75BD,SMLF,IC,AL0075BDA",,,SO8_1-27_4-9X3-9,14602.57,16662.69,270.000,NO
U271,"LM75BD-LM75BD,SMLF,IC,AL0075BDA",,,SO8_1-27_4-9X3-9,11489.45,604.26,0.000,NO
U272,"LM75BD-LM75BD,SMLF,IC,AL0075BDA",,,SO8_1-27_4-9X3-9,3943.24,16676.37,270.000,NO
U273,"LM75BD-LM75BD,SMLF,IC,AL0075BDA",,,SO8_1-27_4-9X3-9,4456.95,625.16,0.000,NO
U276,"ISL28022FRZT-ISL28022FRZ-T,SMLB",,,QFN16_TH_0-5_3X3XH,8474.79,2143.91,0.000,NO
U278,"74LVC1G08W57-74LVC1G08W5-7,SMLA",,,SOT25-5_0-95_3X1-6,7582.73,17085.40,270.000,NO
U279,"PCA9617ADP-PCA9617ADP,SMLF,IC,A",,,TSSOP8_3XB,8511.25,1721.98,180.000,NO
U286,"74LVC1G126SE7-74LVC1G126SE-7,SA",,,SOT353_0-65_2X1-25,6012.20,4933.62,90.000,NO
U290,MOSFET_NCH_GDS_ESD_PROTECTED-2A,,,SOT23_GDSXC,7594.42,16785.63,0.000,NO
U301,"GTL2014PW-GTL2014PW,SMLF,IC,ALA",,,TSSOP14,4536.21,3760.03,270.000,NO
U304,"GTL2014PW-GTL2014PW,SMLF,IC,ALA",,,TSSOP14,4514.21,4455.03,270.000,NO
U305,"GTL2014PW-GTL2014PW,SMLF,IC,ALA",,,TSSOP14,4880.70,4453.62,270.000,NO
U306,"GTL2014PW-GTL2014PW,SMLF,IC,ALA",,,TSSOP14,5577.01,3850.73,270.000,NO
U307,"MOSFET_N_SMLF-BSS138K,BSS138K,A",,,SOT23_GDSXD,6566.10,1104.12,0.000,NO
U308,"74LVC2G07DW7-74LVC2G07DW-7,SMLA",,,SOT363_0-65_2X1-25XC,12104.57,16648.55,90.000,NO
U309,PI3EQX1002EZREX-PI3EQX1002EZREA,,,TQFN24_TH_0-35_2-5X2-5,5033.10,1034.52,270.000,YES
U312,"TUSB211IRWBR-TUSB211IRWBR,SMLFA",,,X2QFN12_0-4_1-6X1-6,5538.50,1119.27,90.000,YES
U313,"GL852GOHY60-GL852G-OHY60,SMLF,B",,,QFN28_THXL,6186.44,1487.81,270.000,NO
U314,"9ZXL0451EKILFT-9ZXL0451EKILFT,A",,,VFQFPN32_TH_0-5_5X5XD,4419.90,16275.92,180.000,NO
U315,"PCA9617ADP-PCA9617ADP,SMLF,IC,A",,,TSSOP8_3XB,10577.49,5139.24,180.000,NO
U316,"74LVC2G17GW-74LVC2G17GW,SMLF,IA",,,SOT363,14119.90,16032.82,0.000,NO
U320,"74LVC1G66GV-74LVC1G66GV,SMLF,IA",,,SC74AXA,14552.00,640.62,180.000,NO
U321,"74LVC1G66GV-74LVC1G66GV,SMLF,IA",,,SC74AXA,3525.00,1262.62,0.000,NO
U322,"74LVC1G08W57-74LVC1G08W5-7,SMLA",,,SOT25-5_0-95_3X1-6,15215.00,1258.62,180.000,NO
U323,"74LVC1G08W57-74LVC1G08W5-7,SMLA",,,SOT25-5_0-95_3X1-6,3325.00,1523.62,90.000,NO
U324,MOSFET_NCH_GDS_ESD_PROTECTED-2A,,,SOT23_GDSXC,6465.00,4950.00,180.000,NO
U325,"MOSFET_N_SMLF-BSS138K,BSS138K,A",,,SOT23_GDSXD,8480.00,3783.62,0.000,NO
U327,"74CBTLV3126PW-74CBTLV3126PW,SMA",,,TSSOP14,4825.00,2203.62,0.000,NO
U328,"DS125BR111RTWR-DS125BR111RTWR,A",,,WQFN24_TH_0-5_4X4XA,1573.23,15450.01,180.000,NO
U329,MOSFET_NCH_GDS_ESD_PROTECTED-2B,,,SOT23_GDSXC,10804.57,16539.50,180.000,NO
U330,"APX80929SAG7-APX809-29SAG-7,SMA",,,SOT23_123XI,16615.10,2053.80,0.000,NO
U331,"ISL28022FRZT-ISL28022FRZ-T,SMLA",,,QFN16_TH_0-5_3X3XH,11746.81,16252.20,0.000,NO
U332,"74LVC2G07DW7-74LVC2G07DW-7,SMLB",,,SOT363_0-65_2X1-25XC,8358.24,4742.41,180.000,NO
U334,"74LVC1G08W57-74LVC1G08W5-7,SMLA",,,SOT25-5_0-95_3X1-6,17336.94,4068.54,90.000,NO
U335,"74LVC1G08W57-74LVC1G08W5-7,SMLA",,,SOT25-5_0-95_3X1-6,5533.94,4463.96,0.000,NO
U336,"APX80929SAG7-APX809-29SAG-7,SMA",,,SOT23_123XI,8667.60,1873.40,0.000,NO
U337,LM4040AIM3X25NOPB-LM4040AIM3X-A,,,SOT23_123_2-92X1-3,7854.00,3700.00,270.000,NO
U338,LM4040AIM3X25NOPB-LM4040AIM3X-A,,,SOT23_123_2-92X1-3,8248.00,4387.00,270.000,NO
U339,"AP331AWG7-AP331AWG-7,SMLF,EMPTA",,,SOT25,7998.00,3776.30,90.000,NO
U340,"AP331AWG7-AP331AWG-7,SMLF,EMPTA",,,SOT25,8392.00,4355.00,90.000,NO
U341,LM4040AIM3X25NOPB-LM4040AIM3X-A,,,SOT23_123_2-92X1-3,12144.00,834.00,0.000,NO
U342,"AP331AWG7-AP331AWG-7,SMLF,EMPTA",,,SOT25,12142.00,1038.00,0.000,NO
U343,LM4040AIM3X25NOPB-LM4040AIM3X-A,,,SOT23_123_2-92X1-3,7230.90,16637.30,90.000,NO
U344,"AP331AWG7-AP331AWG-7,SMLF,EMPTA",,,SOT25,7222.70,16329.30,90.000,NO
U345,"NCT7718W-NCT7718W,SMLF,EMPTY,AA",,,MSOP8_0-65_3X3XE,11545.87,16093.50,0.000,NO
U365,"MMBT3904_SMLF-MMBT3904    ,EMPA",,,SOT23_BEC,11154.40,15710.30,90.000,NO
U369,"TPS3700DDCR-TPS3700DDCR,SMLF,EA",,,SOT23-6XF,10963.57,16559.50,90.000,NO
U5201,"TUSB211IRWBR-TUSB211IRWBR,SMLFA",,,X2QFN12_0-4_1-6X1-6,475.46,4422.02,270.000,YES
X1,TP_TDR_4P_FTS_TH-TP_TDR_4P_DIPA,,,MPKT4_H025P0200,20685.39,11953.72,90.000,NO
X2,TP_TDR_4P_FTS_TH-TP_TDR_4P_DIPA,,,MPKT4_H025P0200,20364.52,6032.00,270.000,NO
X3,TP_TDR_4P_FTS_TH-TP_TDR_4P_DIPA,,,MPKT4_H025P0200,19844.82,11952.20,90.000,NO
X4,TP_TDR_4P_FTS_TH-TP_TDR_4P_DIPA,,,MPKT4_H025P0200,19523.95,6030.48,270.000,NO
X5,TP_TDR_4P_FTS_TH-TP_TDR_4P_DIPA,,,MPKT4_H025P0200,20474.19,6031.62,90.000,YES
X6,TP_TDR_4P_FTS_TH-TP_TDR_4P_DIPA,,,MPKT4_H025P0200,19213.95,6028.68,90.000,YES
X7,TP_TDR_4P_FTS_TH-TP_TDR_4P_DIPA,,,MPKT4_H025P0200,20785.39,6031.72,270.000,NO
X8,TP_TDR_4P_FTS_TH-TP_TDR_4P_DIPA,,,MPKT4_H025P0200,20264.52,11954.00,90.000,NO
X9,TP_TDR_4P_FTS_TH-TP_TDR_4P_DIPA,,,MPKT4_H025P0200,19944.82,6030.20,270.000,NO
X10,TP_TDR_4P_FTS_TH-TP_TDR_4P_DIPA,,,MPKT4_H025P0200,19423.95,11952.48,90.000,NO
X11,TP_TDR_4P_FTS_TH-TP_TDR_4P_DIPA,,,MPKT4_H025P0200,20574.19,11953.62,270.000,YES
X12,TP_TDR_4P_FTS_TH-TP_TDR_4P_DIPA,,,MPKT4_H025P0200,19313.95,11950.68,270.000,YES
X13,TP_TDR_4P_FTS_TH-TP_TDR_4P_DIPA,,,MPKT4_H025P0200,20574.19,-90.38,270.000,NO
X14,TP_TDR_4P_FTS_TH-TP_TDR_4P_DIPA,,,MPKT4_H025P0200,20054.52,5830.20,90.000,NO
X15,TP_TDR_4P_FTS_TH-TP_TDR_4P_DIPA,,,MPKT4_H025P0200,19633.62,5830.10,90.000,NO
X16,TP_TDR_4P_FTS_TH-TP_TDR_4P_DIPA,,,MPKT4_H025P0200,19313.95,-93.32,270.000,NO
X17,TP_TDR_4P_FTS_TH-TP_TDR_4P_DIPA,,,MPKT4_H025P0200,20264.52,-90.00,90.000,YES
X18,TP_TDR_4P_FTS_TH-TP_TDR_4P_DIPA,,,MPKT4_H025P0200,19102.75,5828.58,270.000,YES
X19,TP_TDR_4P_FTS_TH-TP_TDR_4P_DIPA,,,MPKT4_H025P0200,20474.19,5831.62,90.000,NO
X20,TP_TDR_4P_FTS_TH-TP_TDR_4P_DIPA,,,MPKT4_H025P0200,20154.52,-91.80,270.000,NO
X21,TP_TDR_4P_FTS_TH-TP_TDR_4P_DIPA,,,MPKT4_H025P0200,19733.62,-91.90,270.000,NO
X22,TP_TDR_4P_FTS_TH-TP_TDR_4P_DIPA,,,MPKT4_H025P0200,19213.95,5828.68,90.000,NO
X23,TP_TDR_4P_FTS_TH-TP_TDR_4P_DIPA,,,MPKT4_H025P0200,20364.52,5832.00,270.000,YES
X24,TP_TDR_4P_FTS_TH-TP_TDR_4P_DIPA,,,MPKT4_H025P0200,19002.75,-93.42,90.000,YES
X25,TP_TDR_4P_FTS_TH-TP_TDR_4P_DIPA,,,MPKT4_H025P0200,20054.52,6030.20,90.000,YES
X26,TP_TDR_4P_FTS_TH-TP_TDR_4P_DIPA,,,MPKT4_H025P0200,19733.62,11952.10,270.000,YES
X27,TP_TDR_4P_FTS_TH-TP_TDR_4P_DIPA,,,MPKT4_H025P0200,20154.52,11952.20,270.000,YES
X28,TP_TDR_4P_FTS_TH-TP_TDR_4P_DIPA,,,MPKT4_H025P0200,19633.62,6030.10,90.000,YES
X29,TP_TDR_4P_FTS_TH-TP_TDR_4P_DIPA,,,MPKT4_H025P0200,19944.82,5830.20,270.000,YES
X30,TP_TDR_4P_FTS_TH-TP_TDR_4P_DIPA,,,MPKT4_H025P0200,19423.95,-91.52,90.000,YES
X31,TP_TDR_4P_FTS_TH-TP_TDR_4P_DIPA,,,MPKT4_H025P0200,19844.82,-91.80,90.000,YES
X32,TP_TDR_4P_FTS_TH-TP_TDR_4P_DIPA,,,MPKT4_H025P0200,19523.95,5830.48,270.000,YES
X34,TP_TDR_4P_FTS_TH-TP_TDR_4P_DIPA,,,MPKT4_H025P0200,19002.75,9547.08,90.000,NO
X35,TP_TDR_4P_FTS_TH-TP_TDR_4P_DIPA,,,MPKT4_H025P0200,18791.55,8307.48,90.000,NO
X36,TP_TDR_4P_FTS_TH-TP_TDR_4P_DIPA,,,MPKT4_H025P0200,18891.55,4788.98,270.000,NO
X37,TP_TDR_4P_FTS_TH-TP_TDR_4P_DIPA,,,MPKT4_H025P0200,19102.75,8307.58,270.000,YES
X38,TP_TDR_4P_FTS_TH-TP_TDR_4P_DIPA,,,MPKT4_H025P0200,18791.55,6028.48,90.000,YES
X39,TP_TDR_4P_FTS_TH-TP_TDR_4P_DIPA,,,MPKT4_H025P0200,18891.55,4588.98,270.000,YES
X42,TP_TDR_4P_FTS_TH-TP_TDR_4P_DIPA,,,MPKT4_H025P0200,19102.75,8507.58,270.000,NO
X43,TP_TDR_4P_FTS_TH-TP_TDR_4P_DIPA,,,MPKT4_H025P0200,18891.55,7267.98,270.000,NO
X44,TP_TDR_4P_FTS_TH-TP_TDR_4P_DIPA,,,MPKT4_H025P0200,18791.55,5828.48,90.000,NO
X45,TP_TDR_4P_FTS_TH-TP_TDR_4P_DIPA,,,MPKT4_H025P0200,19002.75,7268.08,90.000,YES
X46,TP_TDR_4P_FTS_TH-TP_TDR_4P_DIPA,,,MPKT4_H025P0200,18891.55,7067.98,270.000,YES
X47,TP_TDR_4P_FTS_TH-TP_TDR_4P_DIPA,,,MPKT4_H025P0200,18791.55,3549.48,90.000,YES
Y1,"Q_CRYSTAL_SMLF-32.768KHZ,IC,BGA",,,X_2S_XTL721,12730.00,1223.00,135.000,NO
Y2,"Q_XTAL_4P_13BI_24GND-25MHZ,SMLB",,,X_4S_FL4000120_3-2X2-5,9749.11,3478.09,270.000,NO
Y3,"Q_XTAL_4P_13BI_24GND-25MHZ,SMLB",,,X_4S_FL4000120_3-2X2-5,9563.85,9814.23,180.000,NO
Y4,"Q_XTAL_4P_13BI_24GND-12MHZ,SMLA",,,OSC4_DNCA250000ETS_2-5X2_H26,285.40,3911.29,0.000,NO
Y7,"Q_XTAL_4P_13BI_24GND-25MHZ,SMLA",,,X_7MXA,13209.00,2716.62,90.000,NO
Y9,"Q_XTAL_4P_13BI_24GND-12MHZ,SMLB",,,OSC4_DNCA250000ETS_2-5X2_H26,5907.40,1492.29,0.000,NO
